G04 ================== begin FILE IDENTIFICATION RECORD ==================*
G04 Layout Name:  t6mg_pdb_a_v02_0109_1330.brd*
G04 Film Name:    fab.art*
G04 File Format:  Gerber RS274X*
G04 File Origin:  Cadence Allegro 16.3-S038*
G04 Origin Date:  Mon Jan 13 14:11:54 2014*
G04 *
G04 Layer:  MANUFACTURING/NCDRILL_LEGEND*
G04 Layer:  MANUFACTURING/NCDRILL_FIGURE*
G04 Layer:  MANUFACTURING/NCLEGEND-1-8*
G04 Layer:  MANUFACTURING/PHOTOPLOT_OUTLINE*
G04 Layer:  MANUFACTURING/DIMENSION*
G04 Layer:  MANUFACTURING/DETAILS*
G04 Layer:  DRAWING FORMAT/TITLE_BLOCK*
G04 Layer:  DRAWING FORMAT/TITLE_DATA_FAB*
G04 Layer:  BOARD GEOMETRY/OUTLINE*
G04 *
G04 Offset:    (0.00 0.00)*
G04 Mirror:    No*
G04 Mode:      Positive*
G04 Rotation:  0*
G04 FullContactRelief:  No*
G04 UndefLineWidth:     6.00*
G04 ================== end FILE IDENTIFICATION RECORD ====================*
%FSLAX25Y25*MOIN*%
%IR0*IPPOS*OFA0.00000B0.00000*MIA0B0*SFA1.00000B1.00000*%
%AMMACRO15*
1,1,.006,.014497,-.035*
20,1,.006,.014497,-.035,-.014497,-.035,0.0*
1,1,.006,-.014497,-.035*
20,1,.006,-.014497,-.035,-.035,-.014497,0.0*
1,1,.006,-.035,-.014497*
20,1,.006,-.035,-.014497,-.035,.014497,0.0*
1,1,.006,-.035,.014497*
20,1,.006,-.035,.014497,-.014497,.035,0.0*
1,1,.006,-.014497,.035*
20,1,.006,-.014497,.035,.014497,.035,0.0*
1,1,.006,.014497,.035*
20,1,.006,.014497,.035,.035,.014497,0.0*
1,1,.006,.035,.014497*
20,1,.006,.035,.014497,.035,-.014497,0.0*
1,1,.006,.035,-.014497*
20,1,.006,.035,-.014497,.014497,-.035,0.0*
1,1,.006,.014497,-.035*
1,1,.006,-.0385,-.0175*
20,1,.006,-.0385,-.0175,-.0385,.01225,0.0*
1,1,.006,-.0385,.01225*
20,1,.006,-.0385,.01225,-.03733,.01517,0.0*
1,1,.006,-.03733,.01517*
20,1,.006,-.03733,.01517,-.035,.01692,0.0*
1,1,.006,-.035,.01692*
20,1,.006,-.035,.01692,-.0315,.0175,0.0*
1,1,.006,-.0315,.0175*
20,1,.006,-.0315,.0175,-.028,.01633,0.0*
1,1,.006,-.028,.01633*
20,1,.006,-.028,.01633,-.02625,.01342,0.0*
1,1,.006,-.02625,.01342*
1,1,.006,-.03325,.0035*
20,1,.006,-.03325,.0035,-.04492,.0035,0.0*
1,1,.006,-.04492,.0035*
1,1,.006,.00001,.00583*
20,1,.006,.00001,.00583,.00001,-.0175,0.0*
1,1,.006,.00001,-.0175*
1,1,.006,.00001,.01517*
20,1,.006,.00001,.01517,-.00116,.01575,0.0*
1,1,.006,-.00116,.01575*
20,1,.006,-.00116,.01575,-.00116,.01692,0.0*
1,1,.006,-.00116,.01692*
20,1,.006,-.00116,.01692,.00001,.0175,0.0*
1,1,.006,.00001,.0175*
20,1,.006,.00001,.0175,.00118,.01692,0.0*
1,1,.006,.00118,.01692*
20,1,.006,.00118,.01692,.00118,.01575,0.0*
1,1,.006,.00118,.01575*
20,1,.006,.00118,.01575,.00001,.01517,0.0*
1,1,.006,.00001,.01517*
1,1,.006,.03502,.0175*
20,1,.006,.03502,.0175,.03502,-.0175,0.0*
1,1,.006,.03502,-.0175*
1,1,.006,.02685,.00583*
20,1,.006,.02685,.00583,.04319,.00583,0.0*
1,1,.006,.04319,.00583*
%
%ADD15MACRO15*%
%AMMACRO28*
1,1,.006,.1575,0.0*
20,1,.006,.1575,0.0,-.1575,0.0,0.0*
1,1,.006,-.1575,0.0*
1,1,.006,0.0,.1575*
20,1,.006,0.0,.1575,0.0,-.1575,0.0*
1,1,.006,0.0,-.1575*
1,1,.006,.03938,.07087*
20,1,.006,.03938,.07087,.12338,.07087,0.0*
1,1,.006,.12338,.07087*
20,1,.006,.12338,.07087,.1155,.08925,0.0*
1,1,.006,.1155,.08925*
20,1,.006,.1155,.08925,.10238,.09975,0.0*
1,1,.006,.10238,.09975*
20,1,.006,.10238,.09975,.084,.105,0.0*
1,1,.006,.084,.105*
20,1,.006,.084,.105,.06563,.10237,0.0*
1,1,.006,.06563,.10237*
20,1,.006,.06563,.10237,.04987,.0945,0.0*
1,1,.006,.04987,.0945*
20,1,.006,.04987,.0945,.03938,.07612,0.0*
1,1,.006,.03938,.07612*
20,1,.006,.03938,.07612,.03412,.06037,0.0*
1,1,.006,.03412,.06037*
20,1,.006,.03412,.06037,.03412,.04463,0.0*
1,1,.006,.03412,.04463*
20,1,.006,.03412,.04463,.03938,.02887,0.0*
1,1,.006,.03938,.02887*
20,1,.006,.03938,.02887,.0525,.01312,0.0*
1,1,.006,.0525,.01312*
20,1,.006,.0525,.01312,.06825,.00262,0.0*
1,1,.006,.06825,.00262*
20,1,.006,.06825,.00262,.08663,0.0,0.0*
1,1,.006,.08663,0.0*
20,1,.006,.08663,0.0,.105,.00525,0.0*
1,1,.006,.105,.00525*
20,1,.006,.105,.00525,.12338,.021,0.0*
1,1,.006,.12338,.021*
1,1,.006,.28351,-.0525*
20,1,.006,.28351,-.0525,.28351,.105,0.0*
1,1,.006,.28351,.105*
1,1,.006,.28351,.08138*
20,1,.006,.28351,.08138,.27038,.0945,0.0*
1,1,.006,.27038,.0945*
20,1,.006,.27038,.0945,.25463,.10237,0.0*
1,1,.006,.25463,.10237*
20,1,.006,.25463,.10237,.23626,.105,0.0*
1,1,.006,.23626,.105*
20,1,.006,.23626,.105,.22051,.10237,0.0*
1,1,.006,.22051,.10237*
20,1,.006,.22051,.10237,.20214,.08925,0.0*
1,1,.006,.20214,.08925*
20,1,.006,.20214,.08925,.19163,.07087,0.0*
1,1,.006,.19163,.07087*
20,1,.006,.19163,.07087,.18901,.0525,0.0*
1,1,.006,.18901,.0525*
20,1,.006,.18901,.0525,.19163,.03412,0.0*
1,1,.006,.19163,.03412*
20,1,.006,.19163,.03412,.20214,.01575,0.0*
1,1,.006,.20214,.01575*
20,1,.006,.20214,.01575,.22051,.00262,0.0*
1,1,.006,.22051,.00262*
20,1,.006,.22051,.00262,.23626,0.0,0.0*
1,1,.006,.23626,0.0*
20,1,.006,.23626,0.0,.25463,.00262,0.0*
1,1,.006,.25463,.00262*
20,1,.006,.25463,.00262,.27038,.0105,0.0*
1,1,.006,.27038,.0105*
20,1,.006,.27038,.0105,.28351,.02362,0.0*
1,1,.006,.28351,.02362*
1,1,.006,.39377,.1575*
20,1,.006,.39377,.1575,.39377,0.0,0.0*
1,1,.006,.39377,0.0*
1,1,.006,.35702,.105*
20,1,.006,.35702,.105,.43052,.105,0.0*
1,1,.006,.43052,.105*
%
%ADD28MACRO28*%
%AMMACRO26*
1,1,.006,.042457,-.1025*
20,1,.006,.042457,-.1025,-.042457,-.1025,0.0*
1,1,.006,-.042457,-.1025*
20,1,.006,-.042457,-.1025,-.1025,-.042457,0.0*
1,1,.006,-.1025,-.042457*
20,1,.006,-.1025,-.042457,-.1025,.042457,0.0*
1,1,.006,-.1025,.042457*
20,1,.006,-.1025,.042457,-.042457,.1025,0.0*
1,1,.006,-.042457,.1025*
20,1,.006,-.042457,.1025,.042457,.1025,0.0*
1,1,.006,.042457,.1025*
20,1,.006,.042457,.1025,.1025,.042457,0.0*
1,1,.006,.1025,.042457*
20,1,.006,.1025,.042457,.1025,-.042457,0.0*
1,1,.006,.1025,-.042457*
20,1,.006,.1025,-.042457,.042457,-.1025,0.0*
1,1,.006,.042457,-.1025*
1,1,.006,-.14521,.01708*
20,1,.006,-.14521,.01708,-.12471,-.05125,0.0*
1,1,.006,-.12471,-.05125*
20,1,.006,-.12471,-.05125,-.1025,.01708,0.0*
1,1,.006,-.1025,.01708*
20,1,.006,-.1025,.01708,-.08029,-.05125,0.0*
1,1,.006,-.08029,-.05125*
20,1,.006,-.08029,-.05125,-.05979,.01708,0.0*
1,1,.006,-.05979,.01708*
1,1,.006,-.03074,-.08542*
20,1,.006,-.03074,-.08542,-.03074,.01708,0.0*
1,1,.006,-.03074,.01708*
1,1,.006,-.03074,.00171*
20,1,.006,-.03074,.00171,-.0222,.01025,0.0*
1,1,.006,-.0222,.01025*
20,1,.006,-.0222,.01025,-.01366,.01537,0.0*
1,1,.006,-.01366,.01537*
20,1,.006,-.01366,.01537,.00001,.01708,0.0*
1,1,.006,.00001,.01708*
20,1,.006,.00001,.01708,.01197,.01537,0.0*
1,1,.006,.01197,.01537*
20,1,.006,.01197,.01537,.02393,.00683,0.0*
1,1,.006,.02393,.00683*
20,1,.006,.02393,.00683,.02905,-.00513,0.0*
1,1,.006,.02905,-.00513*
20,1,.006,.02905,-.00513,.03076,-.01708,0.0*
1,1,.006,.03076,-.01708*
20,1,.006,.03076,-.01708,.02905,-.02904,0.0*
1,1,.006,.02905,-.02904*
20,1,.006,.02905,-.02904,.02393,-.041,0.0*
1,1,.006,.02393,-.041*
20,1,.006,.02393,-.041,.01368,-.04783,0.0*
1,1,.006,.01368,-.04783*
20,1,.006,.01368,-.04783,.00001,-.05125,0.0*
1,1,.006,.00001,-.05125*
20,1,.006,.00001,-.05125,-.01195,-.04954,0.0*
1,1,.006,-.01195,-.04954*
20,1,.006,-.01195,-.04954,-.02391,-.04442,0.0*
1,1,.006,-.02391,-.04442*
20,1,.006,-.02391,-.04442,-.03074,-.03759,0.0*
1,1,.006,-.03074,-.03759*
1,1,.006,.10252,.05125*
20,1,.006,.10252,.05125,.10252,-.05125,0.0*
1,1,.006,.10252,-.05125*
1,1,.006,.0786,.01708*
20,1,.006,.0786,.01708,.12644,.01708,0.0*
1,1,.006,.12644,.01708*
%
%ADD26MACRO26*%
%AMMACRO22*
1,1,.006,.035,.035*
20,1,.006,.035,.035,.035,-.035,0.0*
1,1,.006,.035,-.035*
20,1,.006,.035,-.035,-.035,-.035,0.0*
1,1,.006,-.035,-.035*
20,1,.006,-.035,-.035,-.035,.035,0.0*
1,1,.006,-.035,.035*
20,1,.006,-.035,.035,.035,.035,0.0*
1,1,.006,.035,.035*
1,1,.006,-.035,.0175*
20,1,.006,-.035,.0175,-.03967,.01633,0.0*
1,1,.006,-.03967,.01633*
20,1,.006,-.03967,.01633,-.04317,.01342,0.0*
1,1,.006,-.04317,.01342*
20,1,.006,-.04317,.01342,-.0455,.00992,0.0*
1,1,.006,-.0455,.00992*
20,1,.006,-.0455,.00992,-.04725,.00525,0.0*
1,1,.006,-.04725,.00525*
20,1,.006,-.04725,.00525,-.04783,0.0,0.0*
1,1,.006,-.04783,0.0*
20,1,.006,-.04783,0.0,-.04725,-.00525,0.0*
1,1,.006,-.04725,-.00525*
20,1,.006,-.04725,-.00525,-.0455,-.00992,0.0*
1,1,.006,-.0455,-.00992*
20,1,.006,-.0455,-.00992,-.04317,-.01342,0.0*
1,1,.006,-.04317,-.01342*
20,1,.006,-.04317,-.01342,-.03967,-.01633,0.0*
1,1,.006,-.03967,-.01633*
20,1,.006,-.03967,-.01633,-.035,-.0175,0.0*
1,1,.006,-.035,-.0175*
20,1,.006,-.035,-.0175,-.03033,-.01633,0.0*
1,1,.006,-.03033,-.01633*
20,1,.006,-.03033,-.01633,-.02683,-.01342,0.0*
1,1,.006,-.02683,-.01342*
20,1,.006,-.02683,-.01342,-.0245,-.00992,0.0*
1,1,.006,-.0245,-.00992*
20,1,.006,-.0245,-.00992,-.02275,-.00525,0.0*
1,1,.006,-.02275,-.00525*
20,1,.006,-.02275,-.00525,-.02217,0.0,0.0*
1,1,.006,-.02217,0.0*
20,1,.006,-.02217,0.0,-.02275,.00525,0.0*
1,1,.006,-.02275,.00525*
20,1,.006,-.02275,.00525,-.0245,.00992,0.0*
1,1,.006,-.0245,.00992*
20,1,.006,-.0245,.00992,-.02683,.01342,0.0*
1,1,.006,-.02683,.01342*
20,1,.006,-.02683,.01342,-.03033,.01633,0.0*
1,1,.006,-.03033,.01633*
20,1,.006,-.03033,.01633,-.035,.0175,0.0*
1,1,.006,-.035,.0175*
1,1,.006,-.01107,.01167*
20,1,.006,-.01107,.01167,-.00757,.01517,0.0*
1,1,.006,-.00757,.01517*
20,1,.006,-.00757,.01517,-.00349,.01692,0.0*
1,1,.006,-.00349,.01692*
20,1,.006,-.00349,.01692,.00118,.0175,0.0*
1,1,.006,.00118,.0175*
20,1,.006,.00118,.0175,.00701,.01633,0.0*
1,1,.006,.00701,.01633*
20,1,.006,.00701,.01633,.01109,.01342,0.0*
1,1,.006,.01109,.01342*
20,1,.006,.01109,.01342,.01226,.00992,0.0*
1,1,.006,.01226,.00992*
20,1,.006,.01226,.00992,.01168,.00642,0.0*
1,1,.006,.01168,.00642*
20,1,.006,.01168,.00642,.00934,.0035,0.0*
1,1,.006,.00934,.0035*
20,1,.006,.00934,.0035,-.00232,-.00233,0.0*
1,1,.006,-.00232,-.00233*
20,1,.006,-.00232,-.00233,-.00757,-.00642,0.0*
1,1,.006,-.00757,-.00642*
20,1,.006,-.00757,-.00642,-.01107,-.01225,0.0*
1,1,.006,-.01107,-.01225*
20,1,.006,-.01107,-.01225,-.01224,-.0175,0.0*
1,1,.006,-.01224,-.0175*
20,1,.006,-.01224,-.0175,.01226,-.0175,0.0*
1,1,.006,.01226,-.0175*
1,1,.006,.02394,.01167*
20,1,.006,.02394,.01167,.02744,.01517,0.0*
1,1,.006,.02744,.01517*
20,1,.006,.02744,.01517,.03152,.01692,0.0*
1,1,.006,.03152,.01692*
20,1,.006,.03152,.01692,.03619,.0175,0.0*
1,1,.006,.03619,.0175*
20,1,.006,.03619,.0175,.04202,.01633,0.0*
1,1,.006,.04202,.01633*
20,1,.006,.04202,.01633,.0461,.01342,0.0*
1,1,.006,.0461,.01342*
20,1,.006,.0461,.01342,.04727,.00992,0.0*
1,1,.006,.04727,.00992*
20,1,.006,.04727,.00992,.04669,.00642,0.0*
1,1,.006,.04669,.00642*
20,1,.006,.04669,.00642,.04435,.0035,0.0*
1,1,.006,.04435,.0035*
20,1,.006,.04435,.0035,.03269,-.00233,0.0*
1,1,.006,.03269,-.00233*
20,1,.006,.03269,-.00233,.02744,-.00642,0.0*
1,1,.006,.02744,-.00642*
20,1,.006,.02744,-.00642,.02394,-.01225,0.0*
1,1,.006,.02394,-.01225*
20,1,.006,.02394,-.01225,.02277,-.0175,0.0*
1,1,.006,.02277,-.0175*
20,1,.006,.02277,-.0175,.04727,-.0175,0.0*
1,1,.006,.04727,-.0175*
%
%ADD22MACRO22*%
%AMMACRO16*
1,1,.006,.0475,0.0*
20,1,.006,.0475,0.0,0.0,-.0475,0.0*
1,1,.006,0.0,-.0475*
20,1,.006,0.0,-.0475,-.0475,0.0,0.0*
1,1,.006,-.0475,0.0*
20,1,.006,-.0475,0.0,0.0,.0475,0.0*
1,1,.006,0.0,.0475*
20,1,.006,0.0,.0475,.0475,0.0,0.0*
1,1,.006,.0475,0.0*
1,1,.006,-.06175,-.03958*
20,1,.006,-.06175,-.03958,-.06175,.00792,0.0*
1,1,.006,-.06175,.00792*
1,1,.006,-.06175,.00079*
20,1,.006,-.06175,.00079,-.05779,.00475,0.0*
1,1,.006,-.05779,.00475*
20,1,.006,-.05779,.00475,-.05383,.00712,0.0*
1,1,.006,-.05383,.00712*
20,1,.006,-.05383,.00712,-.0475,.00792,0.0*
1,1,.006,-.0475,.00792*
20,1,.006,-.0475,.00792,-.04196,.00712,0.0*
1,1,.006,-.04196,.00712*
20,1,.006,-.04196,.00712,-.03642,.00317,0.0*
1,1,.006,-.03642,.00317*
20,1,.006,-.03642,.00317,-.03404,-.00238,0.0*
1,1,.006,-.03404,-.00238*
20,1,.006,-.03404,-.00238,-.03325,-.00792,0.0*
1,1,.006,-.03325,-.00792*
20,1,.006,-.03325,-.00792,-.03404,-.01346,0.0*
1,1,.006,-.03404,-.01346*
20,1,.006,-.03404,-.01346,-.03642,-.019,0.0*
1,1,.006,-.03642,-.019*
20,1,.006,-.03642,-.019,-.04117,-.02217,0.0*
1,1,.006,-.04117,-.02217*
20,1,.006,-.04117,-.02217,-.0475,-.02375,0.0*
1,1,.006,-.0475,-.02375*
20,1,.006,-.0475,-.02375,-.05304,-.02296,0.0*
1,1,.006,-.05304,-.02296*
20,1,.006,-.05304,-.02296,-.05858,-.02058,0.0*
1,1,.006,-.05858,-.02058*
20,1,.006,-.05858,-.02058,-.06175,-.01742,0.0*
1,1,.006,-.06175,-.01742*
1,1,.006,.00001,-.02375*
20,1,.006,.00001,-.02375,-.00474,-.02296,0.0*
1,1,.006,-.00474,-.02296*
20,1,.006,-.00474,-.02296,-.00949,-.01979,0.0*
1,1,.006,-.00949,-.01979*
20,1,.006,-.00949,-.01979,-.01266,-.01425,0.0*
1,1,.006,-.01266,-.01425*
20,1,.006,-.01266,-.01425,-.01424,-.00792,0.0*
1,1,.006,-.01424,-.00792*
20,1,.006,-.01424,-.00792,-.01266,-.00158,0.0*
1,1,.006,-.01266,-.00158*
20,1,.006,-.01266,-.00158,-.00949,.00396,0.0*
1,1,.006,-.00949,.00396*
20,1,.006,-.00949,.00396,-.00474,.00712,0.0*
1,1,.006,-.00474,.00712*
20,1,.006,-.00474,.00712,.00001,.00792,0.0*
1,1,.006,.00001,.00792*
20,1,.006,.00001,.00792,.00476,.00712,0.0*
1,1,.006,.00476,.00712*
20,1,.006,.00476,.00712,.00951,.00396,0.0*
1,1,.006,.00951,.00396*
20,1,.006,.00951,.00396,.01268,-.00158,0.0*
1,1,.006,.01268,-.00158*
20,1,.006,.01268,-.00158,.01347,-.00792,0.0*
1,1,.006,.01347,-.00792*
20,1,.006,.01347,-.00792,.01268,-.01425,0.0*
1,1,.006,.01268,-.01425*
20,1,.006,.01268,-.01425,.00951,-.01979,0.0*
1,1,.006,.00951,-.01979*
20,1,.006,.00951,-.01979,.00476,-.02296,0.0*
1,1,.006,.00476,-.02296*
20,1,.006,.00476,-.02296,.00001,-.02375,0.0*
1,1,.006,.00001,-.02375*
1,1,.006,.04752,.02375*
20,1,.006,.04752,.02375,.04752,-.02375,0.0*
1,1,.006,.04752,-.02375*
1,1,.006,.03644,.00792*
20,1,.006,.03644,.00792,.0586,.00792,0.0*
1,1,.006,.0586,.00792*
%
%ADD16MACRO16*%
%AMMACRO13*
1,1,.006,.035,.035*
20,1,.006,.035,.035,.035,-.035,0.0*
1,1,.006,.035,-.035*
20,1,.006,.035,-.035,-.035,-.035,0.0*
1,1,.006,-.035,-.035*
20,1,.006,-.035,-.035,-.035,.035,0.0*
1,1,.006,-.035,.035*
20,1,.006,-.035,.035,.035,.035,0.0*
1,1,.006,.035,.035*
1,1,.006,-.035,.0175*
20,1,.006,-.035,.0175,-.03967,.01633,0.0*
1,1,.006,-.03967,.01633*
20,1,.006,-.03967,.01633,-.04317,.01342,0.0*
1,1,.006,-.04317,.01342*
20,1,.006,-.04317,.01342,-.0455,.00992,0.0*
1,1,.006,-.0455,.00992*
20,1,.006,-.0455,.00992,-.04725,.00525,0.0*
1,1,.006,-.04725,.00525*
20,1,.006,-.04725,.00525,-.04783,0.0,0.0*
1,1,.006,-.04783,0.0*
20,1,.006,-.04783,0.0,-.04725,-.00525,0.0*
1,1,.006,-.04725,-.00525*
20,1,.006,-.04725,-.00525,-.0455,-.00992,0.0*
1,1,.006,-.0455,-.00992*
20,1,.006,-.0455,-.00992,-.04317,-.01342,0.0*
1,1,.006,-.04317,-.01342*
20,1,.006,-.04317,-.01342,-.03967,-.01633,0.0*
1,1,.006,-.03967,-.01633*
20,1,.006,-.03967,-.01633,-.035,-.0175,0.0*
1,1,.006,-.035,-.0175*
20,1,.006,-.035,-.0175,-.03033,-.01633,0.0*
1,1,.006,-.03033,-.01633*
20,1,.006,-.03033,-.01633,-.02683,-.01342,0.0*
1,1,.006,-.02683,-.01342*
20,1,.006,-.02683,-.01342,-.0245,-.00992,0.0*
1,1,.006,-.0245,-.00992*
20,1,.006,-.0245,-.00992,-.02275,-.00525,0.0*
1,1,.006,-.02275,-.00525*
20,1,.006,-.02275,-.00525,-.02217,0.0,0.0*
1,1,.006,-.02217,0.0*
20,1,.006,-.02217,0.0,-.02275,.00525,0.0*
1,1,.006,-.02275,.00525*
20,1,.006,-.02275,.00525,-.0245,.00992,0.0*
1,1,.006,-.0245,.00992*
20,1,.006,-.0245,.00992,-.02683,.01342,0.0*
1,1,.006,-.02683,.01342*
20,1,.006,-.02683,.01342,-.03033,.01633,0.0*
1,1,.006,-.03033,.01633*
20,1,.006,-.03033,.01633,-.035,.0175,0.0*
1,1,.006,-.035,.0175*
1,1,.006,-.01282,-.0105*
20,1,.006,-.01282,-.0105,-.00932,-.01458,0.0*
1,1,.006,-.00932,-.01458*
20,1,.006,-.00932,-.01458,-.00466,-.01692,0.0*
1,1,.006,-.00466,-.01692*
20,1,.006,-.00466,-.01692,.00059,-.0175,0.0*
1,1,.006,.00059,-.0175*
20,1,.006,.00059,-.0175,.00526,-.01692,0.0*
1,1,.006,.00526,-.01692*
20,1,.006,.00526,-.01692,.00993,-.014,0.0*
1,1,.006,.00993,-.014*
20,1,.006,.00993,-.014,.01284,-.0105,0.0*
1,1,.006,.01284,-.0105*
20,1,.006,.01284,-.0105,.01343,-.007,0.0*
1,1,.006,.01343,-.007*
20,1,.006,.01343,-.007,.01226,-.00292,0.0*
1,1,.006,.01226,-.00292*
20,1,.006,.01226,-.00292,.00818,0.0,0.0*
1,1,.006,.00818,0.0*
20,1,.006,.00818,0.0,.00409,.00117,0.0*
1,1,.006,.00409,.00117*
20,1,.006,.00409,.00117,-.00116,.00117,0.0*
1,1,.006,-.00116,.00117*
1,1,.006,.00409,.00117*
20,1,.006,.00409,.00117,.00759,.00292,0.0*
1,1,.006,.00759,.00292*
20,1,.006,.00759,.00292,.01051,.00583,0.0*
1,1,.006,.01051,.00583*
20,1,.006,.01051,.00583,.01168,.00933,0.0*
1,1,.006,.01168,.00933*
20,1,.006,.01168,.00933,.01051,.01283,0.0*
1,1,.006,.01051,.01283*
20,1,.006,.01051,.01283,.00759,.01575,0.0*
1,1,.006,.00759,.01575*
20,1,.006,.00759,.01575,.00234,.0175,0.0*
1,1,.006,.00234,.0175*
20,1,.006,.00234,.0175,-.00291,.01692,0.0*
1,1,.006,-.00291,.01692*
20,1,.006,-.00291,.01692,-.00816,.01458,0.0*
1,1,.006,-.00816,.01458*
1,1,.006,.02394,-.00292*
20,1,.006,.02394,-.00292,.02802,.00117,0.0*
1,1,.006,.02802,.00117*
20,1,.006,.02802,.00117,.03152,.0035,0.0*
1,1,.006,.03152,.0035*
20,1,.006,.03152,.0035,.03619,.00467,0.0*
1,1,.006,.03619,.00467*
20,1,.006,.03619,.00467,.04027,.0035,0.0*
1,1,.006,.04027,.0035*
20,1,.006,.04027,.0035,.04319,.00117,0.0*
1,1,.006,.04319,.00117*
20,1,.006,.04319,.00117,.04552,-.00233,0.0*
1,1,.006,.04552,-.00233*
20,1,.006,.04552,-.00233,.0461,-.00642,0.0*
1,1,.006,.0461,-.00642*
20,1,.006,.0461,-.00642,.04552,-.00992,0.0*
1,1,.006,.04552,-.00992*
20,1,.006,.04552,-.00992,.04319,-.01342,0.0*
1,1,.006,.04319,-.01342*
20,1,.006,.04319,-.01342,.03969,-.01633,0.0*
1,1,.006,.03969,-.01633*
20,1,.006,.03969,-.01633,.0356,-.0175,0.0*
1,1,.006,.0356,-.0175*
20,1,.006,.0356,-.0175,.03094,-.01633,0.0*
1,1,.006,.03094,-.01633*
20,1,.006,.03094,-.01633,.02685,-.01283,0.0*
1,1,.006,.02685,-.01283*
20,1,.006,.02685,-.01283,.02452,-.00758,0.0*
1,1,.006,.02452,-.00758*
20,1,.006,.02452,-.00758,.02394,-.00175,0.0*
1,1,.006,.02394,-.00175*
20,1,.006,.02394,-.00175,.0251,.00583,0.0*
1,1,.006,.0251,.00583*
20,1,.006,.0251,.00583,.02685,.00992,0.0*
1,1,.006,.02685,.00992*
20,1,.006,.02685,.00992,.02977,.014,0.0*
1,1,.006,.02977,.014*
20,1,.006,.02977,.014,.03385,.01692,0.0*
1,1,.006,.03385,.01692*
20,1,.006,.03385,.01692,.03794,.0175,0.0*
1,1,.006,.03794,.0175*
20,1,.006,.03794,.0175,.04202,.01633,0.0*
1,1,.006,.04202,.01633*
20,1,.006,.04202,.01633,.04494,.01342,0.0*
1,1,.006,.04494,.01342*
%
%ADD13MACRO13*%
%AMMACRO25*
1,1,.006,.0495,0.0*
20,1,.006,.0495,0.0,0.0,-.0495,0.0*
1,1,.006,0.0,-.0495*
20,1,.006,0.0,-.0495,-.0495,0.0,0.0*
1,1,.006,-.0495,0.0*
20,1,.006,-.0495,0.0,0.0,.0495,0.0*
1,1,.006,0.0,.0495*
20,1,.006,0.0,.0495,.0495,0.0,0.0*
1,1,.006,.0495,0.0*
1,1,.006,-.06435,-.04125*
20,1,.006,-.06435,-.04125,-.06435,.00825,0.0*
1,1,.006,-.06435,.00825*
1,1,.006,-.06435,.00083*
20,1,.006,-.06435,.00083,-.06022,.00495,0.0*
1,1,.006,-.06022,.00495*
20,1,.006,-.06022,.00495,-.0561,.00742,0.0*
1,1,.006,-.0561,.00742*
20,1,.006,-.0561,.00742,-.0495,.00825,0.0*
1,1,.006,-.0495,.00825*
20,1,.006,-.0495,.00825,-.04373,.00742,0.0*
1,1,.006,-.04373,.00742*
20,1,.006,-.04373,.00742,-.03795,.0033,0.0*
1,1,.006,-.03795,.0033*
20,1,.006,-.03795,.0033,-.03547,-.00248,0.0*
1,1,.006,-.03547,-.00248*
20,1,.006,-.03547,-.00248,-.03465,-.00825,0.0*
1,1,.006,-.03465,-.00825*
20,1,.006,-.03465,-.00825,-.03547,-.01403,0.0*
1,1,.006,-.03547,-.01403*
20,1,.006,-.03547,-.01403,-.03795,-.0198,0.0*
1,1,.006,-.03795,-.0198*
20,1,.006,-.03795,-.0198,-.0429,-.0231,0.0*
1,1,.006,-.0429,-.0231*
20,1,.006,-.0429,-.0231,-.0495,-.02475,0.0*
1,1,.006,-.0495,-.02475*
20,1,.006,-.0495,-.02475,-.05527,-.02393,0.0*
1,1,.006,-.05527,-.02393*
20,1,.006,-.05527,-.02393,-.06105,-.02145,0.0*
1,1,.006,-.06105,-.02145*
20,1,.006,-.06105,-.02145,-.06435,-.01815,0.0*
1,1,.006,-.06435,-.01815*
1,1,.006,.00001,-.02475*
20,1,.006,.00001,-.02475,-.00494,-.02393,0.0*
1,1,.006,-.00494,-.02393*
20,1,.006,-.00494,-.02393,-.00989,-.02063,0.0*
1,1,.006,-.00989,-.02063*
20,1,.006,-.00989,-.02063,-.01319,-.01485,0.0*
1,1,.006,-.01319,-.01485*
20,1,.006,-.01319,-.01485,-.01484,-.00825,0.0*
1,1,.006,-.01484,-.00825*
20,1,.006,-.01484,-.00825,-.01319,-.00165,0.0*
1,1,.006,-.01319,-.00165*
20,1,.006,-.01319,-.00165,-.00989,.00412,0.0*
1,1,.006,-.00989,.00412*
20,1,.006,-.00989,.00412,-.00494,.00742,0.0*
1,1,.006,-.00494,.00742*
20,1,.006,-.00494,.00742,.00001,.00825,0.0*
1,1,.006,.00001,.00825*
20,1,.006,.00001,.00825,.00496,.00742,0.0*
1,1,.006,.00496,.00742*
20,1,.006,.00496,.00742,.00991,.00412,0.0*
1,1,.006,.00991,.00412*
20,1,.006,.00991,.00412,.01321,-.00165,0.0*
1,1,.006,.01321,-.00165*
20,1,.006,.01321,-.00165,.01404,-.00825,0.0*
1,1,.006,.01404,-.00825*
20,1,.006,.01404,-.00825,.01321,-.01485,0.0*
1,1,.006,.01321,-.01485*
20,1,.006,.01321,-.01485,.00991,-.02063,0.0*
1,1,.006,.00991,-.02063*
20,1,.006,.00991,-.02063,.00496,-.02393,0.0*
1,1,.006,.00496,-.02393*
20,1,.006,.00496,-.02393,.00001,-.02475,0.0*
1,1,.006,.00001,-.02475*
1,1,.006,.04952,-.02475*
20,1,.006,.04952,-.02475,.04457,-.02393,0.0*
1,1,.006,.04457,-.02393*
20,1,.006,.04457,-.02393,.03962,-.02063,0.0*
1,1,.006,.03962,-.02063*
20,1,.006,.03962,-.02063,.03632,-.01485,0.0*
1,1,.006,.03632,-.01485*
20,1,.006,.03632,-.01485,.03467,-.00825,0.0*
1,1,.006,.03467,-.00825*
20,1,.006,.03467,-.00825,.03632,-.00165,0.0*
1,1,.006,.03632,-.00165*
20,1,.006,.03632,-.00165,.03962,.00412,0.0*
1,1,.006,.03962,.00412*
20,1,.006,.03962,.00412,.04457,.00742,0.0*
1,1,.006,.04457,.00742*
20,1,.006,.04457,.00742,.04952,.00825,0.0*
1,1,.006,.04952,.00825*
20,1,.006,.04952,.00825,.05447,.00742,0.0*
1,1,.006,.05447,.00742*
20,1,.006,.05447,.00742,.05942,.00412,0.0*
1,1,.006,.05942,.00412*
20,1,.006,.05942,.00412,.06272,-.00165,0.0*
1,1,.006,.06272,-.00165*
20,1,.006,.06272,-.00165,.06355,-.00825,0.0*
1,1,.006,.06355,-.00825*
20,1,.006,.06355,-.00825,.06272,-.01485,0.0*
1,1,.006,.06272,-.01485*
20,1,.006,.06272,-.01485,.05942,-.02063,0.0*
1,1,.006,.05942,-.02063*
20,1,.006,.05942,-.02063,.05447,-.02393,0.0*
1,1,.006,.05447,-.02393*
20,1,.006,.05447,-.02393,.04952,-.02475,0.0*
1,1,.006,.04952,-.02475*
%
%ADD25MACRO25*%
%AMMACRO21*
1,1,.006,.035,.035*
20,1,.006,.035,.035,.035,-.035,0.0*
1,1,.006,.035,-.035*
20,1,.006,.035,-.035,-.035,-.035,0.0*
1,1,.006,-.035,-.035*
20,1,.006,-.035,-.035,-.035,.035,0.0*
1,1,.006,-.035,.035*
20,1,.006,-.035,.035,.035,.035,0.0*
1,1,.006,.035,.035*
1,1,.006,-.035,.0175*
20,1,.006,-.035,.0175,-.03967,.01633,0.0*
1,1,.006,-.03967,.01633*
20,1,.006,-.03967,.01633,-.04317,.01342,0.0*
1,1,.006,-.04317,.01342*
20,1,.006,-.04317,.01342,-.0455,.00992,0.0*
1,1,.006,-.0455,.00992*
20,1,.006,-.0455,.00992,-.04725,.00525,0.0*
1,1,.006,-.04725,.00525*
20,1,.006,-.04725,.00525,-.04783,0.0,0.0*
1,1,.006,-.04783,0.0*
20,1,.006,-.04783,0.0,-.04725,-.00525,0.0*
1,1,.006,-.04725,-.00525*
20,1,.006,-.04725,-.00525,-.0455,-.00992,0.0*
1,1,.006,-.0455,-.00992*
20,1,.006,-.0455,-.00992,-.04317,-.01342,0.0*
1,1,.006,-.04317,-.01342*
20,1,.006,-.04317,-.01342,-.03967,-.01633,0.0*
1,1,.006,-.03967,-.01633*
20,1,.006,-.03967,-.01633,-.035,-.0175,0.0*
1,1,.006,-.035,-.0175*
20,1,.006,-.035,-.0175,-.03033,-.01633,0.0*
1,1,.006,-.03033,-.01633*
20,1,.006,-.03033,-.01633,-.02683,-.01342,0.0*
1,1,.006,-.02683,-.01342*
20,1,.006,-.02683,-.01342,-.0245,-.00992,0.0*
1,1,.006,-.0245,-.00992*
20,1,.006,-.0245,-.00992,-.02275,-.00525,0.0*
1,1,.006,-.02275,-.00525*
20,1,.006,-.02275,-.00525,-.02217,0.0,0.0*
1,1,.006,-.02217,0.0*
20,1,.006,-.02217,0.0,-.02275,.00525,0.0*
1,1,.006,-.02275,.00525*
20,1,.006,-.02275,.00525,-.0245,.00992,0.0*
1,1,.006,-.0245,.00992*
20,1,.006,-.0245,.00992,-.02683,.01342,0.0*
1,1,.006,-.02683,.01342*
20,1,.006,-.02683,.01342,-.03033,.01633,0.0*
1,1,.006,-.03033,.01633*
20,1,.006,-.03033,.01633,-.035,.0175,0.0*
1,1,.006,-.035,.0175*
1,1,.006,-.01282,-.0105*
20,1,.006,-.01282,-.0105,-.00932,-.01458,0.0*
1,1,.006,-.00932,-.01458*
20,1,.006,-.00932,-.01458,-.00466,-.01692,0.0*
1,1,.006,-.00466,-.01692*
20,1,.006,-.00466,-.01692,.00059,-.0175,0.0*
1,1,.006,.00059,-.0175*
20,1,.006,.00059,-.0175,.00526,-.01692,0.0*
1,1,.006,.00526,-.01692*
20,1,.006,.00526,-.01692,.00993,-.014,0.0*
1,1,.006,.00993,-.014*
20,1,.006,.00993,-.014,.01284,-.0105,0.0*
1,1,.006,.01284,-.0105*
20,1,.006,.01284,-.0105,.01343,-.007,0.0*
1,1,.006,.01343,-.007*
20,1,.006,.01343,-.007,.01226,-.00292,0.0*
1,1,.006,.01226,-.00292*
20,1,.006,.01226,-.00292,.00818,0.0,0.0*
1,1,.006,.00818,0.0*
20,1,.006,.00818,0.0,.00409,.00117,0.0*
1,1,.006,.00409,.00117*
20,1,.006,.00409,.00117,-.00116,.00117,0.0*
1,1,.006,-.00116,.00117*
1,1,.006,.00409,.00117*
20,1,.006,.00409,.00117,.00759,.00292,0.0*
1,1,.006,.00759,.00292*
20,1,.006,.00759,.00292,.01051,.00583,0.0*
1,1,.006,.01051,.00583*
20,1,.006,.01051,.00583,.01168,.00933,0.0*
1,1,.006,.01168,.00933*
20,1,.006,.01168,.00933,.01051,.01283,0.0*
1,1,.006,.01051,.01283*
20,1,.006,.01051,.01283,.00759,.01575,0.0*
1,1,.006,.00759,.01575*
20,1,.006,.00759,.01575,.00234,.0175,0.0*
1,1,.006,.00234,.0175*
20,1,.006,.00234,.0175,-.00291,.01692,0.0*
1,1,.006,-.00291,.01692*
20,1,.006,-.00291,.01692,-.00816,.01458,0.0*
1,1,.006,-.00816,.01458*
1,1,.006,.0251,-.01342*
20,1,.006,.0251,-.01342,.02919,-.01633,0.0*
1,1,.006,.02919,-.01633*
20,1,.006,.02919,-.01633,.03385,-.0175,0.0*
1,1,.006,.03385,-.0175*
20,1,.006,.03385,-.0175,.03852,-.01633,0.0*
1,1,.006,.03852,-.01633*
20,1,.006,.03852,-.01633,.0426,-.01283,0.0*
1,1,.006,.0426,-.01283*
20,1,.006,.0426,-.01283,.04552,-.00758,0.0*
1,1,.006,.04552,-.00758*
20,1,.006,.04552,-.00758,.04669,-.00233,0.0*
1,1,.006,.04669,-.00233*
20,1,.006,.04669,-.00233,.04669,.00408,0.0*
1,1,.006,.04669,.00408*
20,1,.006,.04669,.00408,.04552,.00933,0.0*
1,1,.006,.04552,.00933*
20,1,.006,.04552,.00933,.0426,.014,0.0*
1,1,.006,.0426,.014*
20,1,.006,.0426,.014,.0391,.01633,0.0*
1,1,.006,.0391,.01633*
20,1,.006,.0391,.01633,.03502,.0175,0.0*
1,1,.006,.03502,.0175*
20,1,.006,.03502,.0175,.03035,.01633,0.0*
1,1,.006,.03035,.01633*
20,1,.006,.03035,.01633,.02685,.014,0.0*
1,1,.006,.02685,.014*
20,1,.006,.02685,.014,.02452,.0105,0.0*
1,1,.006,.02452,.0105*
20,1,.006,.02452,.0105,.02335,.00583,0.0*
1,1,.006,.02335,.00583*
20,1,.006,.02335,.00583,.02452,.00175,0.0*
1,1,.006,.02452,.00175*
20,1,.006,.02452,.00175,.02744,-.00233,0.0*
1,1,.006,.02744,-.00233*
20,1,.006,.02744,-.00233,.03094,-.00467,0.0*
1,1,.006,.03094,-.00467*
20,1,.006,.03094,-.00467,.03502,-.00525,0.0*
1,1,.006,.03502,-.00525*
20,1,.006,.03502,-.00525,.03969,-.00408,0.0*
1,1,.006,.03969,-.00408*
20,1,.006,.03969,-.00408,.04319,-.00117,0.0*
1,1,.006,.04319,-.00117*
20,1,.006,.04319,-.00117,.04669,.00408,0.0*
1,1,.006,.04669,.00408*
%
%ADD21MACRO21*%
%AMMACRO10*
1,1,.006,.066,0.0*
20,1,.006,.066,0.0,.033,.057158,0.0*
1,1,.006,.033,.057158*
20,1,.006,.033,.057158,-.033,.057158,0.0*
1,1,.006,-.033,.057158*
20,1,.006,-.033,.057158,-.066,0.0,0.0*
1,1,.006,-.066,0.0*
20,1,.006,-.066,0.0,-.033,-.057158,0.0*
1,1,.006,-.033,-.057158*
20,1,.006,-.033,-.057158,.033,-.057158,0.0*
1,1,.006,.033,-.057158*
20,1,.006,.033,-.057158,.066,0.0,0.0*
1,1,.006,.066,0.0*
1,1,.006,-.0462,-.055*
20,1,.006,-.0462,-.055,-.0462,.011,0.0*
1,1,.006,-.0462,.011*
1,1,.006,-.0462,.0011*
20,1,.006,-.0462,.0011,-.0517,.0066,0.0*
1,1,.006,-.0517,.0066*
20,1,.006,-.0517,.0066,-.0583,.0099,0.0*
1,1,.006,-.0583,.0099*
20,1,.006,-.0583,.0099,-.066,.011,0.0*
1,1,.006,-.066,.011*
20,1,.006,-.066,.011,-.0726,.0099,0.0*
1,1,.006,-.0726,.0099*
20,1,.006,-.0726,.0099,-.0803,.0044,0.0*
1,1,.006,-.0803,.0044*
20,1,.006,-.0803,.0044,-.0847,-.0033,0.0*
1,1,.006,-.0847,-.0033*
20,1,.006,-.0847,-.0033,-.0858,-.011,0.0*
1,1,.006,-.0858,-.011*
20,1,.006,-.0858,-.011,-.0847,-.0187,0.0*
1,1,.006,-.0847,-.0187*
20,1,.006,-.0847,-.0187,-.0803,-.0264,0.0*
1,1,.006,-.0803,-.0264*
20,1,.006,-.0803,-.0264,-.0726,-.0319,0.0*
1,1,.006,-.0726,-.0319*
20,1,.006,-.0726,-.0319,-.066,-.033,0.0*
1,1,.006,-.066,-.033*
20,1,.006,-.066,-.033,-.0583,-.0319,0.0*
1,1,.006,-.0583,-.0319*
20,1,.006,-.0583,-.0319,-.0517,-.0286,0.0*
1,1,.006,-.0517,-.0286*
20,1,.006,-.0517,-.0286,-.0462,-.0231,0.0*
1,1,.006,-.0462,-.0231*
1,1,.006,-.01649,-.0033*
20,1,.006,-.01649,-.0033,.01871,-.0033,0.0*
1,1,.006,.01871,-.0033*
20,1,.006,.01871,-.0033,.01541,.0044,0.0*
1,1,.006,.01541,.0044*
20,1,.006,.01541,.0044,.00991,.0088,0.0*
1,1,.006,.00991,.0088*
20,1,.006,.00991,.0088,.00221,.011,0.0*
1,1,.006,.00221,.011*
20,1,.006,.00221,.011,-.00549,.0099,0.0*
1,1,.006,-.00549,.0099*
20,1,.006,-.00549,.0099,-.01209,.0066,0.0*
1,1,.006,-.01209,.0066*
20,1,.006,-.01209,.0066,-.01649,-.0011,0.0*
1,1,.006,-.01649,-.0011*
20,1,.006,-.01649,-.0011,-.01869,-.0077,0.0*
1,1,.006,-.01869,-.0077*
20,1,.006,-.01869,-.0077,-.01869,-.0143,0.0*
1,1,.006,-.01869,-.0143*
20,1,.006,-.01869,-.0143,-.01649,-.0209,0.0*
1,1,.006,-.01649,-.0209*
20,1,.006,-.01649,-.0209,-.01099,-.0275,0.0*
1,1,.006,-.01099,-.0275*
20,1,.006,-.01099,-.0275,-.00439,-.0319,0.0*
1,1,.006,-.00439,-.0319*
20,1,.006,-.00439,-.0319,.00331,-.033,0.0*
1,1,.006,.00331,-.033*
20,1,.006,.00331,-.033,.01101,-.0308,0.0*
1,1,.006,.01101,-.0308*
20,1,.006,.01101,-.0308,.01871,-.0242,0.0*
1,1,.006,.01871,-.0242*
1,1,.006,.03852,.011*
20,1,.006,.03852,.011,.05172,-.033,0.0*
1,1,.006,.05172,-.033*
20,1,.006,.05172,-.033,.06602,.011,0.0*
1,1,.006,.06602,.011*
20,1,.006,.06602,.011,.08032,-.033,0.0*
1,1,.006,.08032,-.033*
20,1,.006,.08032,-.033,.09352,.011,0.0*
1,1,.006,.09352,.011*
%
%ADD10MACRO10*%
%AMMACRO11*
1,1,.006,.035,0.0*
20,1,.006,.035,0.0,.034468,-.006078,0.0*
1,1,.006,.034468,-.006078*
20,1,.006,.034468,-.006078,.032889,-.011971,0.0*
1,1,.006,.032889,-.011971*
20,1,.006,.032889,-.011971,.030311,-.0175,0.0*
1,1,.006,.030311,-.0175*
20,1,.006,.030311,-.0175,.026812,-.022498,0.0*
1,1,.006,.026812,-.022498*
20,1,.006,.026812,-.022498,.022498,-.026812,0.0*
1,1,.006,.022498,-.026812*
20,1,.006,.022498,-.026812,.0175,-.030311,0.0*
1,1,.006,.0175,-.030311*
20,1,.006,.0175,-.030311,.011971,-.032889,0.0*
1,1,.006,.011971,-.032889*
20,1,.006,.011971,-.032889,.006078,-.034468,0.0*
1,1,.006,.006078,-.034468*
20,1,.006,.006078,-.034468,0.0,-.035,0.0*
1,1,.006,0.0,-.035*
20,1,.006,0.0,-.035,-.006078,-.034468,0.0*
1,1,.006,-.006078,-.034468*
20,1,.006,-.006078,-.034468,-.011971,-.032889,0.0*
1,1,.006,-.011971,-.032889*
20,1,.006,-.011971,-.032889,-.0175,-.030311,0.0*
1,1,.006,-.0175,-.030311*
20,1,.006,-.0175,-.030311,-.022498,-.026812,0.0*
1,1,.006,-.022498,-.026812*
20,1,.006,-.022498,-.026812,-.026812,-.022498,0.0*
1,1,.006,-.026812,-.022498*
20,1,.006,-.026812,-.022498,-.030311,-.0175,0.0*
1,1,.006,-.030311,-.0175*
20,1,.006,-.030311,-.0175,-.032889,-.011971,0.0*
1,1,.006,-.032889,-.011971*
20,1,.006,-.032889,-.011971,-.034468,-.006078,0.0*
1,1,.006,-.034468,-.006078*
20,1,.006,-.034468,-.006078,-.035,0.0,0.0*
1,1,.006,-.035,0.0*
20,1,.006,-.035,0.0,-.034468,.006078,0.0*
1,1,.006,-.034468,.006078*
20,1,.006,-.034468,.006078,-.032889,.011971,0.0*
1,1,.006,-.032889,.011971*
20,1,.006,-.032889,.011971,-.030311,.0175,0.0*
1,1,.006,-.030311,.0175*
20,1,.006,-.030311,.0175,-.026812,.022498,0.0*
1,1,.006,-.026812,.022498*
20,1,.006,-.026812,.022498,-.022498,.026812,0.0*
1,1,.006,-.022498,.026812*
20,1,.006,-.022498,.026812,-.0175,.030311,0.0*
1,1,.006,-.0175,.030311*
20,1,.006,-.0175,.030311,-.011971,.032889,0.0*
1,1,.006,-.011971,.032889*
20,1,.006,-.011971,.032889,-.006078,.034468,0.0*
1,1,.006,-.006078,.034468*
20,1,.006,-.006078,.034468,0.0,.035,0.0*
1,1,.006,0.0,.035*
20,1,.006,0.0,.035,.006078,.034468,0.0*
1,1,.006,.006078,.034468*
20,1,.006,.006078,.034468,.011971,.032889,0.0*
1,1,.006,.011971,.032889*
20,1,.006,.011971,.032889,.0175,.030311,0.0*
1,1,.006,.0175,.030311*
20,1,.006,.0175,.030311,.022498,.026812,0.0*
1,1,.006,.022498,.026812*
20,1,.006,.022498,.026812,.026812,.022498,0.0*
1,1,.006,.026812,.022498*
20,1,.006,.026812,.022498,.030311,.0175,0.0*
1,1,.006,.030311,.0175*
20,1,.006,.030311,.0175,.032889,.011971,0.0*
1,1,.006,.032889,.011971*
20,1,.006,.032889,.011971,.034468,.006078,0.0*
1,1,.006,.034468,.006078*
20,1,.006,.034468,.006078,.035,0.0,0.0*
1,1,.006,.035,0.0*
1,1,.006,-.04958,.0175*
20,1,.006,-.04958,.0175,-.035,-.0175,0.0*
1,1,.006,-.035,-.0175*
20,1,.006,-.035,-.0175,-.02042,.0175,0.0*
1,1,.006,-.02042,.0175*
1,1,.006,.00001,-.0175*
20,1,.006,.00001,-.0175,.00001,.0175,0.0*
1,1,.006,.00001,.0175*
20,1,.006,.00001,.0175,-.00699,.0105,0.0*
1,1,.006,-.00699,.0105*
1,1,.006,-.00699,-.0175*
20,1,.006,-.00699,-.0175,.00701,-.0175,0.0*
1,1,.006,.00701,-.0175*
1,1,.006,.03502,.0175*
20,1,.006,.03502,.0175,.03035,.01633,0.0*
1,1,.006,.03035,.01633*
20,1,.006,.03035,.01633,.02685,.01342,0.0*
1,1,.006,.02685,.01342*
20,1,.006,.02685,.01342,.02452,.00992,0.0*
1,1,.006,.02452,.00992*
20,1,.006,.02452,.00992,.02277,.00525,0.0*
1,1,.006,.02277,.00525*
20,1,.006,.02277,.00525,.02219,0.0,0.0*
1,1,.006,.02219,0.0*
20,1,.006,.02219,0.0,.02277,-.00525,0.0*
1,1,.006,.02277,-.00525*
20,1,.006,.02277,-.00525,.02452,-.00992,0.0*
1,1,.006,.02452,-.00992*
20,1,.006,.02452,-.00992,.02685,-.01342,0.0*
1,1,.006,.02685,-.01342*
20,1,.006,.02685,-.01342,.03035,-.01633,0.0*
1,1,.006,.03035,-.01633*
20,1,.006,.03035,-.01633,.03502,-.0175,0.0*
1,1,.006,.03502,-.0175*
20,1,.006,.03502,-.0175,.03969,-.01633,0.0*
1,1,.006,.03969,-.01633*
20,1,.006,.03969,-.01633,.04319,-.01342,0.0*
1,1,.006,.04319,-.01342*
20,1,.006,.04319,-.01342,.04552,-.00992,0.0*
1,1,.006,.04552,-.00992*
20,1,.006,.04552,-.00992,.04727,-.00525,0.0*
1,1,.006,.04727,-.00525*
20,1,.006,.04727,-.00525,.04785,0.0,0.0*
1,1,.006,.04785,0.0*
20,1,.006,.04785,0.0,.04727,.00525,0.0*
1,1,.006,.04727,.00525*
20,1,.006,.04727,.00525,.04552,.00992,0.0*
1,1,.006,.04552,.00992*
20,1,.006,.04552,.00992,.04319,.01342,0.0*
1,1,.006,.04319,.01342*
20,1,.006,.04319,.01342,.03969,.01633,0.0*
1,1,.006,.03969,.01633*
20,1,.006,.03969,.01633,.03502,.0175,0.0*
1,1,.006,.03502,.0175*
%
%ADD11MACRO11*%
%AMMACRO27*
1,1,.006,-.1025,-.0195*
20,1,.006,-.1025,-.0195,-.1025,.0195,0.0*
1,1,.006,-.1025,.0195*
20,1,.006,-.1025,.0195,-.100943,.037299,0.0*
1,1,.006,-.100943,.037299*
20,1,.006,-.100943,.037299,-.096318,.054557,0.0*
1,1,.006,-.096318,.054557*
20,1,.006,-.096318,.054557,-.088768,.07075,0.0*
1,1,.006,-.088768,.07075*
20,1,.006,-.088768,.07075,-.07852,.085386,0.0*
1,1,.006,-.07852,.085386*
20,1,.006,-.07852,.085386,-.065886,.09802,0.0*
1,1,.006,-.065886,.09802*
20,1,.006,-.065886,.09802,-.05125,.108268,0.0*
1,1,.006,-.05125,.108268*
20,1,.006,-.05125,.108268,-.035057,.115818,0.0*
1,1,.006,-.035057,.115818*
20,1,.006,-.035057,.115818,-.017799,.120443,0.0*
1,1,.006,-.017799,.120443*
20,1,.006,-.017799,.120443,0.0,.122,0.0*
1,1,.006,0.0,.122*
20,1,.006,0.0,.122,.017799,.120443,0.0*
1,1,.006,.017799,.120443*
20,1,.006,.017799,.120443,.035057,.115818,0.0*
1,1,.006,.035057,.115818*
20,1,.006,.035057,.115818,.05125,.108268,0.0*
1,1,.006,.05125,.108268*
20,1,.006,.05125,.108268,.065886,.09802,0.0*
1,1,.006,.065886,.09802*
20,1,.006,.065886,.09802,.07852,.085386,0.0*
1,1,.006,.07852,.085386*
20,1,.006,.07852,.085386,.088768,.07075,0.0*
1,1,.006,.088768,.07075*
20,1,.006,.088768,.07075,.096318,.054557,0.0*
1,1,.006,.096318,.054557*
20,1,.006,.096318,.054557,.100943,.037299,0.0*
1,1,.006,.100943,.037299*
20,1,.006,.100943,.037299,.1025,.0195,0.0*
1,1,.006,.1025,.0195*
20,1,.006,.1025,.0195,.1025,-.0195,0.0*
1,1,.006,.1025,-.0195*
20,1,.006,.1025,-.0195,.100943,-.037299,0.0*
1,1,.006,.100943,-.037299*
20,1,.006,.100943,-.037299,.096318,-.054557,0.0*
1,1,.006,.096318,-.054557*
20,1,.006,.096318,-.054557,.088768,-.07075,0.0*
1,1,.006,.088768,-.07075*
20,1,.006,.088768,-.07075,.07852,-.085386,0.0*
1,1,.006,.07852,-.085386*
20,1,.006,.07852,-.085386,.065886,-.09802,0.0*
1,1,.006,.065886,-.09802*
20,1,.006,.065886,-.09802,.05125,-.108268,0.0*
1,1,.006,.05125,-.108268*
20,1,.006,.05125,-.108268,.035057,-.115818,0.0*
1,1,.006,.035057,-.115818*
20,1,.006,.035057,-.115818,.017799,-.120443,0.0*
1,1,.006,.017799,-.120443*
20,1,.006,.017799,-.120443,0.0,-.122,0.0*
1,1,.006,0.0,-.122*
20,1,.006,0.0,-.122,-.017799,-.120443,0.0*
1,1,.006,-.017799,-.120443*
20,1,.006,-.017799,-.120443,-.035057,-.115818,0.0*
1,1,.006,-.035057,-.115818*
20,1,.006,-.035057,-.115818,-.05125,-.108268,0.0*
1,1,.006,-.05125,-.108268*
20,1,.006,-.05125,-.108268,-.065886,-.09802,0.0*
1,1,.006,-.065886,-.09802*
20,1,.006,-.065886,-.09802,-.07852,-.085386,0.0*
1,1,.006,-.07852,-.085386*
20,1,.006,-.07852,-.085386,-.088768,-.07075,0.0*
1,1,.006,-.088768,-.07075*
20,1,.006,-.088768,-.07075,-.096318,-.054557,0.0*
1,1,.006,-.096318,-.054557*
20,1,.006,-.096318,-.054557,-.100943,-.037299,0.0*
1,1,.006,-.100943,-.037299*
20,1,.006,-.100943,-.037299,-.1025,-.0195,0.0*
1,1,.006,-.1025,-.0195*
1,1,.006,-.13325,-.05467*
20,1,.006,-.13325,-.05467,-.07175,.05125,0.0*
1,1,.006,-.07175,.05125*
1,1,.006,-.13325,.05125*
20,1,.006,-.13325,.05125,-.1435,.04783,0.0*
1,1,.006,-.1435,.04783*
20,1,.006,-.1435,.04783,-.14863,.04271,0.0*
1,1,.006,-.14863,.04271*
20,1,.006,-.14863,.04271,-.15204,.03246,0.0*
1,1,.006,-.15204,.03246*
20,1,.006,-.15204,.03246,-.14863,.02221,0.0*
1,1,.006,-.14863,.02221*
20,1,.006,-.14863,.02221,-.1435,.01708,0.0*
1,1,.006,-.1435,.01708*
20,1,.006,-.1435,.01708,-.13325,.01367,0.0*
1,1,.006,-.13325,.01367*
20,1,.006,-.13325,.01367,-.123,.01708,0.0*
1,1,.006,-.123,.01708*
20,1,.006,-.123,.01708,-.11788,.02221,0.0*
1,1,.006,-.11788,.02221*
20,1,.006,-.11788,.02221,-.11446,.03246,0.0*
1,1,.006,-.11446,.03246*
20,1,.006,-.11446,.03246,-.11788,.04271,0.0*
1,1,.006,-.11788,.04271*
20,1,.006,-.11788,.04271,-.123,.04783,0.0*
1,1,.006,-.123,.04783*
20,1,.006,-.123,.04783,-.13325,.05125,0.0*
1,1,.006,-.13325,.05125*
1,1,.006,-.07175,-.01708*
20,1,.006,-.07175,-.01708,-.082,-.0205,0.0*
1,1,.006,-.082,-.0205*
20,1,.006,-.082,-.0205,-.08712,-.02562,0.0*
1,1,.006,-.08712,-.02562*
20,1,.006,-.08712,-.02562,-.09054,-.03588,0.0*
1,1,.006,-.09054,-.03588*
20,1,.006,-.09054,-.03588,-.08712,-.04613,0.0*
1,1,.006,-.08712,-.04613*
20,1,.006,-.08712,-.04613,-.082,-.05125,0.0*
1,1,.006,-.082,-.05125*
20,1,.006,-.082,-.05125,-.07175,-.05467,0.0*
1,1,.006,-.07175,-.05467*
20,1,.006,-.07175,-.05467,-.0615,-.05125,0.0*
1,1,.006,-.0615,-.05125*
20,1,.006,-.0615,-.05125,-.05637,-.04613,0.0*
1,1,.006,-.05637,-.04613*
20,1,.006,-.05637,-.04613,-.05296,-.03588,0.0*
1,1,.006,-.05296,-.03588*
20,1,.006,-.05296,-.03588,-.05637,-.02562,0.0*
1,1,.006,-.05637,-.02562*
20,1,.006,-.05637,-.02562,-.0615,-.0205,0.0*
1,1,.006,-.0615,-.0205*
20,1,.006,-.0615,-.0205,-.07175,-.01708,0.0*
1,1,.006,-.07175,-.01708*
1,1,.006,-.03245,-.05125*
20,1,.006,-.03245,-.05125,-.03245,.05125,0.0*
1,1,.006,-.03245,.05125*
20,1,.006,-.03245,.05125,.03247,.05125,0.0*
1,1,.006,.03247,.05125*
1,1,.006,.00855,.00171*
20,1,.006,.00855,.00171,-.03245,.00171,0.0*
1,1,.006,-.03245,.00171*
1,1,.006,.05127,-.041*
20,1,.006,.05127,-.041,.05127,-.05125,0.0*
1,1,.006,.05127,-.05125*
20,1,.006,.05127,-.05125,.06835,-.06833,0.0*
1,1,.006,.06835,-.06833*
20,1,.006,.06835,-.06833,.13669,-.06833,0.0*
1,1,.006,.13669,-.06833*
20,1,.006,.13669,-.06833,.15377,-.05125,0.0*
1,1,.006,.15377,-.05125*
20,1,.006,.15377,-.05125,.15377,-.03417,0.0*
1,1,.006,.15377,-.03417*
20,1,.006,.15377,-.03417,.13669,-.01708,0.0*
1,1,.006,.13669,-.01708*
20,1,.006,.13669,-.01708,.06835,-.01708,0.0*
1,1,.006,.06835,-.01708*
20,1,.006,.06835,-.01708,.05127,0.0,0.0*
1,1,.006,.05127,0.0*
20,1,.006,.05127,0.0,.05127,.01708,0.0*
1,1,.006,.05127,.01708*
20,1,.006,.05127,.01708,.06835,.03417,0.0*
1,1,.006,.06835,.03417*
20,1,.006,.06835,.03417,.13669,.03417,0.0*
1,1,.006,.13669,.03417*
20,1,.006,.13669,.03417,.15377,.01708,0.0*
1,1,.006,.15377,.01708*
20,1,.006,.15377,.01708,.15377,.00683,0.0*
1,1,.006,.15377,.00683*
1,1,.006,.1196,.05125*
20,1,.006,.1196,.05125,.1196,-.08542,0.0*
1,1,.006,.1196,-.08542*
1,1,.006,.08544,-.08542*
20,1,.006,.08544,-.08542,.08544,.05125,0.0*
1,1,.006,.08544,.05125*
%
%ADD27MACRO27*%
%AMMACRO23*
1,1,.006,.079,0.0*
20,1,.006,.079,0.0,.0395,.068416,0.0*
1,1,.006,.0395,.068416*
20,1,.006,.0395,.068416,-.0395,.068416,0.0*
1,1,.006,-.0395,.068416*
20,1,.006,-.0395,.068416,-.079,0.0,0.0*
1,1,.006,-.079,0.0*
20,1,.006,-.079,0.0,-.0395,-.068416,0.0*
1,1,.006,-.0395,-.068416*
20,1,.006,-.0395,-.068416,.0395,-.068416,0.0*
1,1,.006,.0395,-.068416*
20,1,.006,.0395,-.068416,.079,0.0,0.0*
1,1,.006,.079,0.0*
1,1,.006,-.0553,-.06583*
20,1,.006,-.0553,-.06583,-.0553,.01317,0.0*
1,1,.006,-.0553,.01317*
1,1,.006,-.0553,.00132*
20,1,.006,-.0553,.00132,-.06188,.0079,0.0*
1,1,.006,-.06188,.0079*
20,1,.006,-.06188,.0079,-.06978,.01185,0.0*
1,1,.006,-.06978,.01185*
20,1,.006,-.06978,.01185,-.079,.01317,0.0*
1,1,.006,-.079,.01317*
20,1,.006,-.079,.01317,-.0869,.01185,0.0*
1,1,.006,-.0869,.01185*
20,1,.006,-.0869,.01185,-.09612,.00527,0.0*
1,1,.006,-.09612,.00527*
20,1,.006,-.09612,.00527,-.10138,-.00395,0.0*
1,1,.006,-.10138,-.00395*
20,1,.006,-.10138,-.00395,-.1027,-.01317,0.0*
1,1,.006,-.1027,-.01317*
20,1,.006,-.1027,-.01317,-.10138,-.02238,0.0*
1,1,.006,-.10138,-.02238*
20,1,.006,-.10138,-.02238,-.09612,-.0316,0.0*
1,1,.006,-.09612,-.0316*
20,1,.006,-.09612,-.0316,-.0869,-.03818,0.0*
1,1,.006,-.0869,-.03818*
20,1,.006,-.0869,-.03818,-.079,-.0395,0.0*
1,1,.006,-.079,-.0395*
20,1,.006,-.079,-.0395,-.06978,-.03818,0.0*
1,1,.006,-.06978,-.03818*
20,1,.006,-.06978,-.03818,-.06188,-.03423,0.0*
1,1,.006,-.06188,-.03423*
20,1,.006,-.06188,-.03423,-.0553,-.02765,0.0*
1,1,.006,-.0553,-.02765*
1,1,.006,.00001,.0395*
20,1,.006,.00001,.0395,.00001,-.0395,0.0*
1,1,.006,.00001,-.0395*
1,1,.006,-.01842,.01317*
20,1,.006,-.01842,.01317,.01844,.01317,0.0*
1,1,.006,.01844,.01317*
1,1,.006,.07902,.01317*
20,1,.006,.07902,.01317,.07902,-.0395,0.0*
1,1,.006,.07902,-.0395*
1,1,.006,.07902,.03423*
20,1,.006,.07902,.03423,.07639,.03555,0.0*
1,1,.006,.07639,.03555*
20,1,.006,.07639,.03555,.07639,.03818,0.0*
1,1,.006,.07639,.03818*
20,1,.006,.07639,.03818,.07902,.0395,0.0*
1,1,.006,.07902,.0395*
20,1,.006,.07902,.0395,.08165,.03818,0.0*
1,1,.006,.08165,.03818*
20,1,.006,.08165,.03818,.08165,.03555,0.0*
1,1,.006,.08165,.03555*
20,1,.006,.08165,.03555,.07902,.03423,0.0*
1,1,.006,.07902,.03423*
%
%ADD23MACRO23*%
%AMMACRO18*
1,1,.006,0.0,.035*
20,1,.006,0.0,.035,.035,-.035,0.0*
1,1,.006,.035,-.035*
20,1,.006,.035,-.035,-.035,-.035,0.0*
1,1,.006,-.035,-.035*
20,1,.006,-.035,-.035,0.0,.035,0.0*
1,1,.006,0.0,.035*
1,1,.006,-.0455,-.02917*
20,1,.006,-.0455,-.02917,-.0455,.00583,0.0*
1,1,.006,-.0455,.00583*
1,1,.006,-.0455,.00058*
20,1,.006,-.0455,.00058,-.04258,.0035,0.0*
1,1,.006,-.04258,.0035*
20,1,.006,-.04258,.0035,-.03967,.00525,0.0*
1,1,.006,-.03967,.00525*
20,1,.006,-.03967,.00525,-.035,.00583,0.0*
1,1,.006,-.035,.00583*
20,1,.006,-.035,.00583,-.03092,.00525,0.0*
1,1,.006,-.03092,.00525*
20,1,.006,-.03092,.00525,-.02683,.00233,0.0*
1,1,.006,-.02683,.00233*
20,1,.006,-.02683,.00233,-.02508,-.00175,0.0*
1,1,.006,-.02508,-.00175*
20,1,.006,-.02508,-.00175,-.0245,-.00583,0.0*
1,1,.006,-.0245,-.00583*
20,1,.006,-.0245,-.00583,-.02508,-.00992,0.0*
1,1,.006,-.02508,-.00992*
20,1,.006,-.02508,-.00992,-.02683,-.014,0.0*
1,1,.006,-.02683,-.014*
20,1,.006,-.02683,-.014,-.03033,-.01633,0.0*
1,1,.006,-.03033,-.01633*
20,1,.006,-.03033,-.01633,-.035,-.0175,0.0*
1,1,.006,-.035,-.0175*
20,1,.006,-.035,-.0175,-.03908,-.01692,0.0*
1,1,.006,-.03908,-.01692*
20,1,.006,-.03908,-.01692,-.04317,-.01517,0.0*
1,1,.006,-.04317,-.01517*
20,1,.006,-.04317,-.01517,-.0455,-.01283,0.0*
1,1,.006,-.0455,-.01283*
1,1,.006,.00001,.0175*
20,1,.006,.00001,.0175,.00001,-.0175,0.0*
1,1,.006,.00001,-.0175*
1,1,.006,-.00816,.00583*
20,1,.006,-.00816,.00583,.00818,.00583,0.0*
1,1,.006,.00818,.00583*
1,1,.006,.02044,.00583*
20,1,.006,.02044,.00583,.02744,-.0175,0.0*
1,1,.006,.02744,-.0175*
20,1,.006,.02744,-.0175,.03502,.00583,0.0*
1,1,.006,.03502,.00583*
20,1,.006,.03502,.00583,.0426,-.0175,0.0*
1,1,.006,.0426,-.0175*
20,1,.006,.0426,-.0175,.0496,.00583,0.0*
1,1,.006,.0496,.00583*
%
%ADD18MACRO18*%
%AMMACRO14*
1,1,.006,.063,0.0*
20,1,.006,.063,0.0,.0315,.05456,0.0*
1,1,.006,.0315,.05456*
20,1,.006,.0315,.05456,-.0315,.05456,0.0*
1,1,.006,-.0315,.05456*
20,1,.006,-.0315,.05456,-.063,0.0,0.0*
1,1,.006,-.063,0.0*
20,1,.006,-.063,0.0,-.0315,-.05456,0.0*
1,1,.006,-.0315,-.05456*
20,1,.006,-.0315,-.05456,.0315,-.05456,0.0*
1,1,.006,.0315,-.05456*
20,1,.006,.0315,-.05456,.063,0.0,0.0*
1,1,.006,.063,0.0*
1,1,.006,-.0441,-.0525*
20,1,.006,-.0441,-.0525,-.0441,.0105,0.0*
1,1,.006,-.0441,.0105*
1,1,.006,-.0441,.00105*
20,1,.006,-.0441,.00105,-.04935,.0063,0.0*
1,1,.006,-.04935,.0063*
20,1,.006,-.04935,.0063,-.05565,.00945,0.0*
1,1,.006,-.05565,.00945*
20,1,.006,-.05565,.00945,-.063,.0105,0.0*
1,1,.006,-.063,.0105*
20,1,.006,-.063,.0105,-.0693,.00945,0.0*
1,1,.006,-.0693,.00945*
20,1,.006,-.0693,.00945,-.07665,.0042,0.0*
1,1,.006,-.07665,.0042*
20,1,.006,-.07665,.0042,-.08085,-.00315,0.0*
1,1,.006,-.08085,-.00315*
20,1,.006,-.08085,-.00315,-.0819,-.0105,0.0*
1,1,.006,-.0819,-.0105*
20,1,.006,-.0819,-.0105,-.08085,-.01785,0.0*
1,1,.006,-.08085,-.01785*
20,1,.006,-.08085,-.01785,-.07665,-.0252,0.0*
1,1,.006,-.07665,-.0252*
20,1,.006,-.07665,-.0252,-.0693,-.03045,0.0*
1,1,.006,-.0693,-.03045*
20,1,.006,-.0693,-.03045,-.063,-.0315,0.0*
1,1,.006,-.063,-.0315*
20,1,.006,-.063,-.0315,-.05565,-.03045,0.0*
1,1,.006,-.05565,-.03045*
20,1,.006,-.05565,-.03045,-.04935,-.0273,0.0*
1,1,.006,-.04935,-.0273*
20,1,.006,-.04935,-.0273,-.0441,-.02205,0.0*
1,1,.006,-.0441,-.02205*
1,1,.006,-.02624,.0105*
20,1,.006,-.02624,.0105,-.01364,-.0315,0.0*
1,1,.006,-.01364,-.0315*
20,1,.006,-.01364,-.0315,.00001,.0105,0.0*
1,1,.006,.00001,.0105*
20,1,.006,.00001,.0105,.01366,-.0315,0.0*
1,1,.006,.01366,-.0315*
20,1,.006,.01366,-.0315,.02626,.0105,0.0*
1,1,.006,.02626,.0105*
1,1,.006,.04097,-.0504*
20,1,.006,.04097,-.0504,.04727,-.0525,0.0*
1,1,.006,.04727,-.0525*
20,1,.006,.04727,-.0525,.05567,-.0504,0.0*
1,1,.006,.05567,-.0504*
20,1,.006,.05567,-.0504,.06092,-.0462,0.0*
1,1,.006,.06092,-.0462*
20,1,.006,.06092,-.0462,.06512,-.04095,0.0*
1,1,.006,.06512,-.04095*
20,1,.006,.06512,-.04095,.07142,-.02415,0.0*
1,1,.006,.07142,-.02415*
20,1,.006,.07142,-.02415,.08507,.0105,0.0*
1,1,.006,.08507,.0105*
1,1,.006,.05147,.0105*
20,1,.006,.05147,.0105,.07142,-.02415,0.0*
1,1,.006,.07142,-.02415*
%
%ADD14MACRO14*%
%AMMACRO12*
1,1,.006,0.0,.035*
20,1,.006,0.0,.035,.035,-.035,0.0*
1,1,.006,.035,-.035*
20,1,.006,.035,-.035,-.035,-.035,0.0*
1,1,.006,-.035,-.035*
20,1,.006,-.035,-.035,0.0,.035,0.0*
1,1,.006,0.0,.035*
1,1,.006,-.035,.0175*
20,1,.006,-.035,.0175,-.03967,.01633,0.0*
1,1,.006,-.03967,.01633*
20,1,.006,-.03967,.01633,-.04317,.01342,0.0*
1,1,.006,-.04317,.01342*
20,1,.006,-.04317,.01342,-.0455,.00992,0.0*
1,1,.006,-.0455,.00992*
20,1,.006,-.0455,.00992,-.04725,.00525,0.0*
1,1,.006,-.04725,.00525*
20,1,.006,-.04725,.00525,-.04783,0.0,0.0*
1,1,.006,-.04783,0.0*
20,1,.006,-.04783,0.0,-.04725,-.00525,0.0*
1,1,.006,-.04725,-.00525*
20,1,.006,-.04725,-.00525,-.0455,-.00992,0.0*
1,1,.006,-.0455,-.00992*
20,1,.006,-.0455,-.00992,-.04317,-.01342,0.0*
1,1,.006,-.04317,-.01342*
20,1,.006,-.04317,-.01342,-.03967,-.01633,0.0*
1,1,.006,-.03967,-.01633*
20,1,.006,-.03967,-.01633,-.035,-.0175,0.0*
1,1,.006,-.035,-.0175*
20,1,.006,-.035,-.0175,-.03033,-.01633,0.0*
1,1,.006,-.03033,-.01633*
20,1,.006,-.03033,-.01633,-.02683,-.01342,0.0*
1,1,.006,-.02683,-.01342*
20,1,.006,-.02683,-.01342,-.0245,-.00992,0.0*
1,1,.006,-.0245,-.00992*
20,1,.006,-.0245,-.00992,-.02275,-.00525,0.0*
1,1,.006,-.02275,-.00525*
20,1,.006,-.02275,-.00525,-.02217,0.0,0.0*
1,1,.006,-.02217,0.0*
20,1,.006,-.02217,0.0,-.02275,.00525,0.0*
1,1,.006,-.02275,.00525*
20,1,.006,-.02275,.00525,-.0245,.00992,0.0*
1,1,.006,-.0245,.00992*
20,1,.006,-.0245,.00992,-.02683,.01342,0.0*
1,1,.006,-.02683,.01342*
20,1,.006,-.02683,.01342,-.03033,.01633,0.0*
1,1,.006,-.03033,.01633*
20,1,.006,-.03033,.01633,-.035,.0175,0.0*
1,1,.006,-.035,.0175*
1,1,.006,.00701,-.0175*
20,1,.006,.00701,-.0175,.00701,.0175,0.0*
1,1,.006,.00701,.0175*
20,1,.006,.00701,.0175,-.01457,-.00758,0.0*
1,1,.006,-.01457,-.00758*
20,1,.006,-.01457,-.00758,.01459,-.00758,0.0*
1,1,.006,.01459,-.00758*
1,1,.006,.02219,-.0105*
20,1,.006,.02219,-.0105,.02569,-.01458,0.0*
1,1,.006,.02569,-.01458*
20,1,.006,.02569,-.01458,.03035,-.01692,0.0*
1,1,.006,.03035,-.01692*
20,1,.006,.03035,-.01692,.0356,-.0175,0.0*
1,1,.006,.0356,-.0175*
20,1,.006,.0356,-.0175,.04027,-.01692,0.0*
1,1,.006,.04027,-.01692*
20,1,.006,.04027,-.01692,.04494,-.014,0.0*
1,1,.006,.04494,-.014*
20,1,.006,.04494,-.014,.04785,-.0105,0.0*
1,1,.006,.04785,-.0105*
20,1,.006,.04785,-.0105,.04844,-.007,0.0*
1,1,.006,.04844,-.007*
20,1,.006,.04844,-.007,.04727,-.00292,0.0*
1,1,.006,.04727,-.00292*
20,1,.006,.04727,-.00292,.04319,0.0,0.0*
1,1,.006,.04319,0.0*
20,1,.006,.04319,0.0,.0391,.00117,0.0*
1,1,.006,.0391,.00117*
20,1,.006,.0391,.00117,.03385,.00117,0.0*
1,1,.006,.03385,.00117*
1,1,.006,.0391,.00117*
20,1,.006,.0391,.00117,.0426,.00292,0.0*
1,1,.006,.0426,.00292*
20,1,.006,.0426,.00292,.04552,.00583,0.0*
1,1,.006,.04552,.00583*
20,1,.006,.04552,.00583,.04669,.00933,0.0*
1,1,.006,.04669,.00933*
20,1,.006,.04669,.00933,.04552,.01283,0.0*
1,1,.006,.04552,.01283*
20,1,.006,.04552,.01283,.0426,.01575,0.0*
1,1,.006,.0426,.01575*
20,1,.006,.0426,.01575,.03735,.0175,0.0*
1,1,.006,.03735,.0175*
20,1,.006,.03735,.0175,.0321,.01692,0.0*
1,1,.006,.0321,.01692*
20,1,.006,.0321,.01692,.02685,.01458,0.0*
1,1,.006,.02685,.01458*
%
%ADD12MACRO12*%
%AMMACRO24*
1,1,.006,0.0,.035*
20,1,.006,0.0,.035,.035,-.035,0.0*
1,1,.006,.035,-.035*
20,1,.006,.035,-.035,-.035,-.035,0.0*
1,1,.006,-.035,-.035*
20,1,.006,-.035,-.035,0.0,.035,0.0*
1,1,.006,0.0,.035*
1,1,.006,-.035,.0175*
20,1,.006,-.035,.0175,-.03967,.01633,0.0*
1,1,.006,-.03967,.01633*
20,1,.006,-.03967,.01633,-.04317,.01342,0.0*
1,1,.006,-.04317,.01342*
20,1,.006,-.04317,.01342,-.0455,.00992,0.0*
1,1,.006,-.0455,.00992*
20,1,.006,-.0455,.00992,-.04725,.00525,0.0*
1,1,.006,-.04725,.00525*
20,1,.006,-.04725,.00525,-.04783,0.0,0.0*
1,1,.006,-.04783,0.0*
20,1,.006,-.04783,0.0,-.04725,-.00525,0.0*
1,1,.006,-.04725,-.00525*
20,1,.006,-.04725,-.00525,-.0455,-.00992,0.0*
1,1,.006,-.0455,-.00992*
20,1,.006,-.0455,-.00992,-.04317,-.01342,0.0*
1,1,.006,-.04317,-.01342*
20,1,.006,-.04317,-.01342,-.03967,-.01633,0.0*
1,1,.006,-.03967,-.01633*
20,1,.006,-.03967,-.01633,-.035,-.0175,0.0*
1,1,.006,-.035,-.0175*
20,1,.006,-.035,-.0175,-.03033,-.01633,0.0*
1,1,.006,-.03033,-.01633*
20,1,.006,-.03033,-.01633,-.02683,-.01342,0.0*
1,1,.006,-.02683,-.01342*
20,1,.006,-.02683,-.01342,-.0245,-.00992,0.0*
1,1,.006,-.0245,-.00992*
20,1,.006,-.0245,-.00992,-.02275,-.00525,0.0*
1,1,.006,-.02275,-.00525*
20,1,.006,-.02275,-.00525,-.02217,0.0,0.0*
1,1,.006,-.02217,0.0*
20,1,.006,-.02217,0.0,-.02275,.00525,0.0*
1,1,.006,-.02275,.00525*
20,1,.006,-.02275,.00525,-.0245,.00992,0.0*
1,1,.006,-.0245,.00992*
20,1,.006,-.0245,.00992,-.02683,.01342,0.0*
1,1,.006,-.02683,.01342*
20,1,.006,-.02683,.01342,-.03033,.01633,0.0*
1,1,.006,-.03033,.01633*
20,1,.006,-.03033,.01633,-.035,.0175,0.0*
1,1,.006,-.035,.0175*
1,1,.006,.00701,-.0175*
20,1,.006,.00701,-.0175,.00701,.0175,0.0*
1,1,.006,.00701,.0175*
20,1,.006,.00701,.0175,-.01457,-.00758,0.0*
1,1,.006,-.01457,-.00758*
20,1,.006,-.01457,-.00758,.01459,-.00758,0.0*
1,1,.006,.01459,-.00758*
1,1,.006,.04202,-.0175*
20,1,.006,.04202,-.0175,.04202,.0175,0.0*
1,1,.006,.04202,.0175*
20,1,.006,.04202,.0175,.02044,-.00758,0.0*
1,1,.006,.02044,-.00758*
20,1,.006,.02044,-.00758,.0496,-.00758,0.0*
1,1,.006,.0496,-.00758*
%
%ADD24MACRO24*%
%AMMACRO19*
1,1,.006,0.0,.035*
20,1,.006,0.0,.035,.035,-.035,0.0*
1,1,.006,.035,-.035*
20,1,.006,.035,-.035,-.035,-.035,0.0*
1,1,.006,-.035,-.035*
20,1,.006,-.035,-.035,0.0,.035,0.0*
1,1,.006,0.0,.035*
1,1,.006,-.035,.0175*
20,1,.006,-.035,.0175,-.03967,.01633,0.0*
1,1,.006,-.03967,.01633*
20,1,.006,-.03967,.01633,-.04317,.01342,0.0*
1,1,.006,-.04317,.01342*
20,1,.006,-.04317,.01342,-.0455,.00992,0.0*
1,1,.006,-.0455,.00992*
20,1,.006,-.0455,.00992,-.04725,.00525,0.0*
1,1,.006,-.04725,.00525*
20,1,.006,-.04725,.00525,-.04783,0.0,0.0*
1,1,.006,-.04783,0.0*
20,1,.006,-.04783,0.0,-.04725,-.00525,0.0*
1,1,.006,-.04725,-.00525*
20,1,.006,-.04725,-.00525,-.0455,-.00992,0.0*
1,1,.006,-.0455,-.00992*
20,1,.006,-.0455,-.00992,-.04317,-.01342,0.0*
1,1,.006,-.04317,-.01342*
20,1,.006,-.04317,-.01342,-.03967,-.01633,0.0*
1,1,.006,-.03967,-.01633*
20,1,.006,-.03967,-.01633,-.035,-.0175,0.0*
1,1,.006,-.035,-.0175*
20,1,.006,-.035,-.0175,-.03033,-.01633,0.0*
1,1,.006,-.03033,-.01633*
20,1,.006,-.03033,-.01633,-.02683,-.01342,0.0*
1,1,.006,-.02683,-.01342*
20,1,.006,-.02683,-.01342,-.0245,-.00992,0.0*
1,1,.006,-.0245,-.00992*
20,1,.006,-.0245,-.00992,-.02275,-.00525,0.0*
1,1,.006,-.02275,-.00525*
20,1,.006,-.02275,-.00525,-.02217,0.0,0.0*
1,1,.006,-.02217,0.0*
20,1,.006,-.02217,0.0,-.02275,.00525,0.0*
1,1,.006,-.02275,.00525*
20,1,.006,-.02275,.00525,-.0245,.00992,0.0*
1,1,.006,-.0245,.00992*
20,1,.006,-.0245,.00992,-.02683,.01342,0.0*
1,1,.006,-.02683,.01342*
20,1,.006,-.02683,.01342,-.03033,.01633,0.0*
1,1,.006,-.03033,.01633*
20,1,.006,-.03033,.01633,-.035,.0175,0.0*
1,1,.006,-.035,.0175*
1,1,.006,-.01107,-.00292*
20,1,.006,-.01107,-.00292,-.00699,.00117,0.0*
1,1,.006,-.00699,.00117*
20,1,.006,-.00699,.00117,-.00349,.0035,0.0*
1,1,.006,-.00349,.0035*
20,1,.006,-.00349,.0035,.00118,.00467,0.0*
1,1,.006,.00118,.00467*
20,1,.006,.00118,.00467,.00526,.0035,0.0*
1,1,.006,.00526,.0035*
20,1,.006,.00526,.0035,.00818,.00117,0.0*
1,1,.006,.00818,.00117*
20,1,.006,.00818,.00117,.01051,-.00233,0.0*
1,1,.006,.01051,-.00233*
20,1,.006,.01051,-.00233,.01109,-.00642,0.0*
1,1,.006,.01109,-.00642*
20,1,.006,.01109,-.00642,.01051,-.00992,0.0*
1,1,.006,.01051,-.00992*
20,1,.006,.01051,-.00992,.00818,-.01342,0.0*
1,1,.006,.00818,-.01342*
20,1,.006,.00818,-.01342,.00468,-.01633,0.0*
1,1,.006,.00468,-.01633*
20,1,.006,.00468,-.01633,.00059,-.0175,0.0*
1,1,.006,.00059,-.0175*
20,1,.006,.00059,-.0175,-.00407,-.01633,0.0*
1,1,.006,-.00407,-.01633*
20,1,.006,-.00407,-.01633,-.00816,-.01283,0.0*
1,1,.006,-.00816,-.01283*
20,1,.006,-.00816,-.01283,-.01049,-.00758,0.0*
1,1,.006,-.01049,-.00758*
20,1,.006,-.01049,-.00758,-.01107,-.00175,0.0*
1,1,.006,-.01107,-.00175*
20,1,.006,-.01107,-.00175,-.00991,.00583,0.0*
1,1,.006,-.00991,.00583*
20,1,.006,-.00991,.00583,-.00816,.00992,0.0*
1,1,.006,-.00816,.00992*
20,1,.006,-.00816,.00992,-.00524,.014,0.0*
1,1,.006,-.00524,.014*
20,1,.006,-.00524,.014,-.00116,.01692,0.0*
1,1,.006,-.00116,.01692*
20,1,.006,-.00116,.01692,.00293,.0175,0.0*
1,1,.006,.00293,.0175*
20,1,.006,.00293,.0175,.00701,.01633,0.0*
1,1,.006,.00701,.01633*
20,1,.006,.00701,.01633,.00993,.01342,0.0*
1,1,.006,.00993,.01342*
1,1,.006,.02219,-.0105*
20,1,.006,.02219,-.0105,.02569,-.01458,0.0*
1,1,.006,.02569,-.01458*
20,1,.006,.02569,-.01458,.03035,-.01692,0.0*
1,1,.006,.03035,-.01692*
20,1,.006,.03035,-.01692,.0356,-.0175,0.0*
1,1,.006,.0356,-.0175*
20,1,.006,.0356,-.0175,.04027,-.01692,0.0*
1,1,.006,.04027,-.01692*
20,1,.006,.04027,-.01692,.04494,-.014,0.0*
1,1,.006,.04494,-.014*
20,1,.006,.04494,-.014,.04785,-.0105,0.0*
1,1,.006,.04785,-.0105*
20,1,.006,.04785,-.0105,.04844,-.007,0.0*
1,1,.006,.04844,-.007*
20,1,.006,.04844,-.007,.04727,-.00292,0.0*
1,1,.006,.04727,-.00292*
20,1,.006,.04727,-.00292,.04319,0.0,0.0*
1,1,.006,.04319,0.0*
20,1,.006,.04319,0.0,.0391,.00117,0.0*
1,1,.006,.0391,.00117*
20,1,.006,.0391,.00117,.03385,.00117,0.0*
1,1,.006,.03385,.00117*
1,1,.006,.0391,.00117*
20,1,.006,.0391,.00117,.0426,.00292,0.0*
1,1,.006,.0426,.00292*
20,1,.006,.0426,.00292,.04552,.00583,0.0*
1,1,.006,.04552,.00583*
20,1,.006,.04552,.00583,.04669,.00933,0.0*
1,1,.006,.04669,.00933*
20,1,.006,.04669,.00933,.04552,.01283,0.0*
1,1,.006,.04552,.01283*
20,1,.006,.04552,.01283,.0426,.01575,0.0*
1,1,.006,.0426,.01575*
20,1,.006,.0426,.01575,.03735,.0175,0.0*
1,1,.006,.03735,.0175*
20,1,.006,.03735,.0175,.0321,.01692,0.0*
1,1,.006,.0321,.01692*
20,1,.006,.0321,.01692,.02685,.01458,0.0*
1,1,.006,.02685,.01458*
%
%ADD19MACRO19*%
%AMMACRO17*
1,1,.006,0.0,.035*
20,1,.006,0.0,.035,.035,-.035,0.0*
1,1,.006,.035,-.035*
20,1,.006,.035,-.035,-.035,-.035,0.0*
1,1,.006,-.035,-.035*
20,1,.006,-.035,-.035,0.0,.035,0.0*
1,1,.006,0.0,.035*
1,1,.006,-.035,.0175*
20,1,.006,-.035,.0175,-.03967,.01633,0.0*
1,1,.006,-.03967,.01633*
20,1,.006,-.03967,.01633,-.04317,.01342,0.0*
1,1,.006,-.04317,.01342*
20,1,.006,-.04317,.01342,-.0455,.00992,0.0*
1,1,.006,-.0455,.00992*
20,1,.006,-.0455,.00992,-.04725,.00525,0.0*
1,1,.006,-.04725,.00525*
20,1,.006,-.04725,.00525,-.04783,0.0,0.0*
1,1,.006,-.04783,0.0*
20,1,.006,-.04783,0.0,-.04725,-.00525,0.0*
1,1,.006,-.04725,-.00525*
20,1,.006,-.04725,-.00525,-.0455,-.00992,0.0*
1,1,.006,-.0455,-.00992*
20,1,.006,-.0455,-.00992,-.04317,-.01342,0.0*
1,1,.006,-.04317,-.01342*
20,1,.006,-.04317,-.01342,-.03967,-.01633,0.0*
1,1,.006,-.03967,-.01633*
20,1,.006,-.03967,-.01633,-.035,-.0175,0.0*
1,1,.006,-.035,-.0175*
20,1,.006,-.035,-.0175,-.03033,-.01633,0.0*
1,1,.006,-.03033,-.01633*
20,1,.006,-.03033,-.01633,-.02683,-.01342,0.0*
1,1,.006,-.02683,-.01342*
20,1,.006,-.02683,-.01342,-.0245,-.00992,0.0*
1,1,.006,-.0245,-.00992*
20,1,.006,-.0245,-.00992,-.02275,-.00525,0.0*
1,1,.006,-.02275,-.00525*
20,1,.006,-.02275,-.00525,-.02217,0.0,0.0*
1,1,.006,-.02217,0.0*
20,1,.006,-.02217,0.0,-.02275,.00525,0.0*
1,1,.006,-.02275,.00525*
20,1,.006,-.02275,.00525,-.0245,.00992,0.0*
1,1,.006,-.0245,.00992*
20,1,.006,-.0245,.00992,-.02683,.01342,0.0*
1,1,.006,-.02683,.01342*
20,1,.006,-.02683,.01342,-.03033,.01633,0.0*
1,1,.006,-.03033,.01633*
20,1,.006,-.03033,.01633,-.035,.0175,0.0*
1,1,.006,-.035,.0175*
1,1,.006,-.01282,-.01225*
20,1,.006,-.01282,-.01225,-.00932,-.01517,0.0*
1,1,.006,-.00932,-.01517*
20,1,.006,-.00932,-.01517,-.00524,-.01692,0.0*
1,1,.006,-.00524,-.01692*
20,1,.006,-.00524,-.01692,.00001,-.0175,0.0*
1,1,.006,.00001,-.0175*
20,1,.006,.00001,-.0175,.00526,-.01633,0.0*
1,1,.006,.00526,-.01633*
20,1,.006,.00526,-.01633,.00934,-.014,0.0*
1,1,.006,.00934,-.014*
20,1,.006,.00934,-.014,.01226,-.00992,0.0*
1,1,.006,.01226,-.00992*
20,1,.006,.01226,-.00992,.01284,-.00525,0.0*
1,1,.006,.01284,-.00525*
20,1,.006,.01284,-.00525,.01168,-.00058,0.0*
1,1,.006,.01168,-.00058*
20,1,.006,.01168,-.00058,.00876,.00233,0.0*
1,1,.006,.00876,.00233*
20,1,.006,.00876,.00233,.00468,.00467,0.0*
1,1,.006,.00468,.00467*
20,1,.006,.00468,.00467,.00059,.00525,0.0*
1,1,.006,.00059,.00525*
20,1,.006,.00059,.00525,-.00349,.00467,0.0*
1,1,.006,-.00349,.00467*
20,1,.006,-.00349,.00467,-.00874,.00233,0.0*
1,1,.006,-.00874,.00233*
20,1,.006,-.00874,.00233,-.00699,.0175,0.0*
1,1,.006,-.00699,.0175*
20,1,.006,-.00699,.0175,.00876,.0175,0.0*
1,1,.006,.00876,.0175*
1,1,.006,.03385,-.0175*
20,1,.006,.03385,-.0175,.03502,-.00992,0.0*
1,1,.006,.03502,-.00992*
20,1,.006,.03502,-.00992,.03677,-.0035,0.0*
1,1,.006,.03677,-.0035*
20,1,.006,.03677,-.0035,.0391,.00233,0.0*
1,1,.006,.0391,.00233*
20,1,.006,.0391,.00233,.04202,.00875,0.0*
1,1,.006,.04202,.00875*
20,1,.006,.04202,.00875,.04669,.0175,0.0*
1,1,.006,.04669,.0175*
20,1,.006,.04669,.0175,.02335,.0175,0.0*
1,1,.006,.02335,.0175*
%
%ADD17MACRO17*%
%AMMACRO20*
1,1,.006,.035,0.0*
20,1,.006,.035,0.0,.034468,-.006078,0.0*
1,1,.006,.034468,-.006078*
20,1,.006,.034468,-.006078,.032889,-.011971,0.0*
1,1,.006,.032889,-.011971*
20,1,.006,.032889,-.011971,.030311,-.0175,0.0*
1,1,.006,.030311,-.0175*
20,1,.006,.030311,-.0175,.026812,-.022498,0.0*
1,1,.006,.026812,-.022498*
20,1,.006,.026812,-.022498,.022498,-.026812,0.0*
1,1,.006,.022498,-.026812*
20,1,.006,.022498,-.026812,.0175,-.030311,0.0*
1,1,.006,.0175,-.030311*
20,1,.006,.0175,-.030311,.011971,-.032889,0.0*
1,1,.006,.011971,-.032889*
20,1,.006,.011971,-.032889,.006078,-.034468,0.0*
1,1,.006,.006078,-.034468*
20,1,.006,.006078,-.034468,0.0,-.035,0.0*
1,1,.006,0.0,-.035*
20,1,.006,0.0,-.035,-.006078,-.034468,0.0*
1,1,.006,-.006078,-.034468*
20,1,.006,-.006078,-.034468,-.011971,-.032889,0.0*
1,1,.006,-.011971,-.032889*
20,1,.006,-.011971,-.032889,-.0175,-.030311,0.0*
1,1,.006,-.0175,-.030311*
20,1,.006,-.0175,-.030311,-.022498,-.026812,0.0*
1,1,.006,-.022498,-.026812*
20,1,.006,-.022498,-.026812,-.026812,-.022498,0.0*
1,1,.006,-.026812,-.022498*
20,1,.006,-.026812,-.022498,-.030311,-.0175,0.0*
1,1,.006,-.030311,-.0175*
20,1,.006,-.030311,-.0175,-.032889,-.011971,0.0*
1,1,.006,-.032889,-.011971*
20,1,.006,-.032889,-.011971,-.034468,-.006078,0.0*
1,1,.006,-.034468,-.006078*
20,1,.006,-.034468,-.006078,-.035,0.0,0.0*
1,1,.006,-.035,0.0*
20,1,.006,-.035,0.0,-.034468,.006078,0.0*
1,1,.006,-.034468,.006078*
20,1,.006,-.034468,.006078,-.032889,.011971,0.0*
1,1,.006,-.032889,.011971*
20,1,.006,-.032889,.011971,-.030311,.0175,0.0*
1,1,.006,-.030311,.0175*
20,1,.006,-.030311,.0175,-.026812,.022498,0.0*
1,1,.006,-.026812,.022498*
20,1,.006,-.026812,.022498,-.022498,.026812,0.0*
1,1,.006,-.022498,.026812*
20,1,.006,-.022498,.026812,-.0175,.030311,0.0*
1,1,.006,-.0175,.030311*
20,1,.006,-.0175,.030311,-.011971,.032889,0.0*
1,1,.006,-.011971,.032889*
20,1,.006,-.011971,.032889,-.006078,.034468,0.0*
1,1,.006,-.006078,.034468*
20,1,.006,-.006078,.034468,0.0,.035,0.0*
1,1,.006,0.0,.035*
20,1,.006,0.0,.035,.006078,.034468,0.0*
1,1,.006,.006078,.034468*
20,1,.006,.006078,.034468,.011971,.032889,0.0*
1,1,.006,.011971,.032889*
20,1,.006,.011971,.032889,.0175,.030311,0.0*
1,1,.006,.0175,.030311*
20,1,.006,.0175,.030311,.022498,.026812,0.0*
1,1,.006,.022498,.026812*
20,1,.006,.022498,.026812,.026812,.022498,0.0*
1,1,.006,.026812,.022498*
20,1,.006,.026812,.022498,.030311,.0175,0.0*
1,1,.006,.030311,.0175*
20,1,.006,.030311,.0175,.032889,.011971,0.0*
1,1,.006,.032889,.011971*
20,1,.006,.032889,.011971,.034468,.006078,0.0*
1,1,.006,.034468,.006078*
20,1,.006,.034468,.006078,.035,0.0,0.0*
1,1,.006,.035,0.0*
1,1,.006,-.0455,.00583*
20,1,.006,-.0455,.00583,-.035,-.0175,0.0*
1,1,.006,-.035,-.0175*
20,1,.006,-.035,-.0175,-.0245,.00583,0.0*
1,1,.006,-.0245,.00583*
1,1,.006,.00001,.00583*
20,1,.006,.00001,.00583,.00001,-.0175,0.0*
1,1,.006,.00001,-.0175*
1,1,.006,.00001,.01517*
20,1,.006,.00001,.01517,-.00116,.01575,0.0*
1,1,.006,-.00116,.01575*
20,1,.006,-.00116,.01575,-.00116,.01692,0.0*
1,1,.006,-.00116,.01692*
20,1,.006,-.00116,.01692,.00001,.0175,0.0*
1,1,.006,.00001,.0175*
20,1,.006,.00001,.0175,.00118,.01692,0.0*
1,1,.006,.00118,.01692*
20,1,.006,.00118,.01692,.00118,.01575,0.0*
1,1,.006,.00118,.01575*
20,1,.006,.00118,.01575,.00001,.01517,0.0*
1,1,.006,.00001,.01517*
1,1,.006,.04552,-.0175*
20,1,.006,.04552,-.0175,.04552,.00583,0.0*
1,1,.006,.04552,.00583*
1,1,.006,.04552,.00175*
20,1,.006,.04552,.00175,.04319,.00408,0.0*
1,1,.006,.04319,.00408*
20,1,.006,.04319,.00408,.03969,.00525,0.0*
1,1,.006,.03969,.00525*
20,1,.006,.03969,.00525,.0356,.00583,0.0*
1,1,.006,.0356,.00583*
20,1,.006,.0356,.00583,.03152,.00467,0.0*
1,1,.006,.03152,.00467*
20,1,.006,.03152,.00467,.02802,.00233,0.0*
1,1,.006,.02802,.00233*
20,1,.006,.02802,.00233,.02569,-.00117,0.0*
1,1,.006,.02569,-.00117*
20,1,.006,.02569,-.00117,.02452,-.00583,0.0*
1,1,.006,.02452,-.00583*
20,1,.006,.02452,-.00583,.02569,-.0105,0.0*
1,1,.006,.02569,-.0105*
20,1,.006,.02569,-.0105,.02802,-.014,0.0*
1,1,.006,.02802,-.014*
20,1,.006,.02802,-.014,.03152,-.01633,0.0*
1,1,.006,.03152,-.01633*
20,1,.006,.03152,-.01633,.0356,-.0175,0.0*
1,1,.006,.0356,-.0175*
20,1,.006,.0356,-.0175,.03969,-.01692,0.0*
1,1,.006,.03969,-.01692*
20,1,.006,.03969,-.01692,.04319,-.01517,0.0*
1,1,.006,.04319,-.01517*
20,1,.006,.04319,-.01517,.04552,-.01283,0.0*
1,1,.006,.04552,-.01283*
%
%ADD20MACRO20*%
%ADD29C,.006*%
G75*
%LPD*%
G75*
G54D10*
X29979Y30500D03*
Y75500D03*
Y166500D03*
Y211500D03*
Y239500D03*
Y284500D03*
Y375500D03*
Y420500D03*
X553766Y251796D03*
G54D20*
X49441Y1238962D03*
X45581Y1278420D03*
X45413Y1283724D03*
X45244Y1289067D03*
X45350Y1299697D03*
X45267Y1294203D03*
X45281Y1310893D03*
X45244Y1305787D03*
X46980Y1325843D03*
Y1315843D03*
Y1320843D03*
Y1330843D03*
Y1345843D03*
Y1340843D03*
X61888Y666012D03*
X57124Y675327D03*
X54483Y679810D03*
X59236Y670758D03*
X70865Y872278D03*
Y866278D03*
Y860278D03*
Y897750D03*
Y890116D03*
X61866Y1309190D03*
X54543Y1308995D03*
X67568Y1307829D03*
X61866Y1342104D03*
X95775Y751469D03*
X89338Y878294D03*
X91733Y899382D03*
X92633Y907404D03*
X91294Y926951D03*
X98139Y990959D03*
X82763Y1060051D03*
X96684Y1081791D03*
X96510Y1395382D03*
X106958Y26285D03*
X107405Y49898D03*
X107037Y34687D03*
X106836Y376461D03*
X106709Y391219D03*
X107025Y725368D03*
X106935Y745139D03*
X107173Y735219D03*
X100687Y999391D03*
X107351Y1093484D03*
X107235Y1081791D03*
X107215Y1072208D03*
X105152Y1118381D03*
X100719Y1312810D03*
Y1306810D03*
Y1330810D03*
Y1336810D03*
Y1324810D03*
Y1318810D03*
Y1346065D03*
X106962Y1434041D03*
X106921Y1419492D03*
X106763Y1444599D03*
X107006Y1452651D03*
X107355Y1770437D03*
X107220Y1791589D03*
X107373Y1780544D03*
X106819Y1802230D03*
X144878Y1738861D03*
X157558Y51426D03*
X156865Y401207D03*
X156610Y751063D03*
X156854Y1101031D03*
X158618Y1399448D03*
X164037Y1400226D03*
X170351Y1401324D03*
X159192Y1451105D03*
X163257Y1737619D03*
X150309Y1737009D03*
X168151Y1739208D03*
X165782Y1732903D03*
X156183Y1735240D03*
X156452Y1800821D03*
X175989Y944537D03*
X176011Y936829D03*
X175359Y963486D03*
X175561Y955964D03*
X175135Y972490D03*
X175022Y980281D03*
X175742Y989958D03*
X175449Y997660D03*
X175698Y1008730D03*
X175473Y1016296D03*
X175448Y1031766D03*
X175897Y1023997D03*
X176083Y1402321D03*
X173394Y1736051D03*
X256947Y128276D03*
X257125Y115559D03*
X263086Y147675D03*
X265722Y463102D03*
X265737Y473680D03*
X264516Y497341D03*
X255837Y823626D03*
X255687Y812192D03*
X264181Y847354D03*
X262559Y1191777D03*
X271943Y147630D03*
X271547Y260353D03*
X281193Y256624D03*
X281074Y322688D03*
X289895D03*
X281569Y436169D03*
X291002Y432844D03*
X273405Y497341D03*
X285348Y610540D03*
X270109Y672192D03*
X278955D03*
X273114Y785968D03*
X282737Y782643D03*
X273305Y847237D03*
X285966Y959767D03*
X281124Y1016162D03*
X290107D03*
X282958Y1134471D03*
X272082Y1191777D03*
X283808Y1308959D03*
X279518Y1374543D03*
X270579Y1374626D03*
X279990Y1479435D03*
X270234Y1482760D03*
X291054Y1543211D03*
X284086Y1659883D03*
X284583Y1723465D03*
X274704Y1723196D03*
X281066Y1834569D03*
X291550Y1829846D03*
X280240Y1858668D03*
X279976Y1864565D03*
X282717Y1898327D03*
X273817D03*
X304151Y78778D03*
X313089D03*
X294483Y82732D03*
X308057Y248863D03*
X306267Y241010D03*
X314914Y238162D03*
X314940Y252083D03*
X295509Y607215D03*
X295874Y956442D03*
X309678Y1053262D03*
X292698Y1131146D03*
X312527Y1162266D03*
X312698Y1172804D03*
X294133Y1305634D03*
X314183Y1403423D03*
X302267Y1524401D03*
X301734Y1513883D03*
X300392Y1543211D03*
X312077Y1575871D03*
X294090Y1656558D03*
X314562Y2009087D03*
X331403Y51409D03*
X333889Y56021D03*
X338227Y61559D03*
X322005Y78778D03*
X320372Y225979D03*
X318088Y231820D03*
X321899Y238137D03*
X331046Y232021D03*
X320961Y250105D03*
X324709Y231580D03*
X335522Y404033D03*
X323313Y418313D03*
X326196Y413982D03*
X328950Y409216D03*
X320980Y423225D03*
X336617Y577978D03*
X319305Y582111D03*
X329636Y584715D03*
X317724Y588250D03*
X337387Y586230D03*
X320380Y576491D03*
X331867Y589810D03*
X333750Y595326D03*
X321742Y599041D03*
X331568Y752967D03*
X339012Y752859D03*
X329336Y762693D03*
X334010Y758588D03*
X327524Y758020D03*
X329938Y948756D03*
X332527Y943746D03*
X324098Y946104D03*
X318557Y941178D03*
X323868Y929978D03*
X326646Y939788D03*
X336160Y937262D03*
X328583Y933262D03*
X321425Y951577D03*
X324246Y1051786D03*
X335677Y1048904D03*
X317592Y1053050D03*
X337509Y1109598D03*
X328989Y1121090D03*
X326558Y1126368D03*
X327452Y1279447D03*
X321978Y1282086D03*
X329619Y1284016D03*
X327932Y1289221D03*
X325636Y1399114D03*
X334646Y1400804D03*
X323720Y1570924D03*
X333474Y1566686D03*
X335963Y1573797D03*
X323813Y1753231D03*
X329887Y1752081D03*
X332399Y1926787D03*
X324803Y2005272D03*
X359931Y52189D03*
X348289Y50863D03*
X345089Y56190D03*
X340373Y51579D03*
X342097Y401684D03*
X363825Y401768D03*
X342900Y580126D03*
X362577Y752783D03*
X344109Y751809D03*
X343656Y933725D03*
X345578Y1047844D03*
X344099Y1106798D03*
X344130Y1401670D03*
X350690Y1403243D03*
X348710Y1570187D03*
X361011Y1568890D03*
X343402Y1572080D03*
X348245Y1575241D03*
X355364Y1570990D03*
X345537Y1916558D03*
X344402Y1911123D03*
X363361Y1918313D03*
X358318Y1920680D03*
X363411Y1923459D03*
X340336Y1922409D03*
X372204Y56126D03*
X379257Y52158D03*
X387524Y76847D03*
X374442Y406857D03*
X374542Y401282D03*
X368907Y404308D03*
X376654Y754748D03*
X382892Y767710D03*
X386790Y774338D03*
X379335Y1189778D03*
X383276Y1184136D03*
X386816Y1179841D03*
X376472Y1194999D03*
X373674Y1199967D03*
X371523Y1204725D03*
X367829Y1566108D03*
X374431Y1901397D03*
X374775Y1919243D03*
X379403Y1917261D03*
X369748Y1921795D03*
X553766Y913296D03*
G54D11*
X25219Y18752D03*
X3001Y52034D03*
Y100034D03*
Y150034D03*
Y200034D03*
Y250034D03*
Y300034D03*
Y350034D03*
Y400034D03*
Y450034D03*
Y500034D03*
X13441Y495961D03*
X3001Y550034D03*
X10914Y578848D03*
X15984Y578849D03*
X3001Y600034D03*
Y650034D03*
Y700034D03*
Y750034D03*
Y800034D03*
Y850034D03*
Y900034D03*
Y950034D03*
Y1000034D03*
Y1050034D03*
Y1100034D03*
Y1150034D03*
Y1200034D03*
Y1250034D03*
Y1300034D03*
Y1350034D03*
Y1400034D03*
Y1450034D03*
Y1500034D03*
Y1550034D03*
X11541Y1562330D03*
X3006Y1594602D03*
X3012Y1610165D03*
X3001Y1650034D03*
X11153Y1638435D03*
X16552Y1638005D03*
X3001Y1700034D03*
Y1750034D03*
Y1800034D03*
Y1850034D03*
Y1900034D03*
Y1950034D03*
Y2000034D03*
Y2050034D03*
X48433Y866179D03*
X48467Y869278D03*
X46980Y1335843D03*
X26833Y2067866D03*
X60815Y1019026D03*
X63577Y1019115D03*
X59127Y1257647D03*
X57458Y1253378D03*
X58356Y1279812D03*
X58416Y1272383D03*
X54543Y1296513D03*
X63061Y1296312D03*
X67568Y1296654D03*
X54130Y1313763D03*
X70340Y1328203D03*
X55544Y1770835D03*
X55080Y1762982D03*
X54948Y1755171D03*
X56425Y1778371D03*
X70376Y1796383D03*
X75219Y18752D03*
X97417Y32853D03*
Y37438D03*
X97536Y376580D03*
X97457Y371909D03*
X97985Y391220D03*
X97643Y396024D03*
X93223Y417736D03*
X94347Y421562D03*
X86187Y680710D03*
X79520Y682439D03*
X88681Y704108D03*
X81563Y705437D03*
X86673Y685710D03*
X79536D03*
X96308Y696622D03*
X98591Y720745D03*
X98564Y715937D03*
X97443Y739962D03*
X97534Y735248D03*
X98124Y745139D03*
X76446Y1014871D03*
X79499D03*
X96904Y1067515D03*
X96948Y1092036D03*
X96949Y1087095D03*
X96774Y1072226D03*
X97403Y1424340D03*
X97825Y1419492D03*
X96993Y1443743D03*
X96996Y1438980D03*
X97465Y1447919D03*
X95236Y1453321D03*
X88837Y1771103D03*
X91460Y1765062D03*
X93771Y1748227D03*
X80376Y1772098D03*
Y1768566D03*
X75376Y1796236D03*
X80376Y1796163D03*
X85376Y1796236D03*
X80376Y1775609D03*
X76833Y2067866D03*
X106335Y22580D03*
X108082Y38899D03*
X102646Y49461D03*
X101430Y41803D03*
X104350Y62293D03*
X107263Y72244D03*
X109054Y58250D03*
X104116Y82557D03*
X108672Y86150D03*
X105451Y406795D03*
X114498Y396207D03*
X101990Y426104D03*
X109475Y434743D03*
X111017Y419566D03*
X102960Y672823D03*
X113018Y706356D03*
X105087Y754126D03*
X101244Y774100D03*
X112836Y769122D03*
X111967Y795261D03*
X115139Y849240D03*
X105395Y972040D03*
X102611Y972220D03*
X98652Y1096403D03*
X108779Y1105760D03*
X112503Y1115860D03*
X105684Y1125919D03*
X108468Y1129286D03*
X105455Y1472894D03*
X108574Y1463389D03*
X113518Y1489571D03*
X99103Y1765722D03*
X99068Y1760827D03*
X99047Y1785571D03*
X98873Y1780542D03*
X99294Y1789947D03*
X107391Y1794460D03*
X105669Y1815227D03*
X108819Y1812118D03*
Y1824470D03*
X109991Y2083607D03*
X125219Y3002D03*
X162384Y56744D03*
X161742Y72497D03*
X162586Y68130D03*
X161339Y88108D03*
X159417Y91281D03*
X158901Y85017D03*
X169500Y126110D03*
Y118626D03*
Y111407D03*
X166500D03*
Y118626D03*
Y126110D03*
X169329Y140623D03*
X169500Y132705D03*
X169329Y148066D03*
X166329D03*
X166500Y132705D03*
X166329Y140623D03*
X169329Y156102D03*
Y163621D03*
X166329D03*
Y156102D03*
X168975Y265783D03*
X165975D03*
X168975Y296140D03*
Y286803D03*
Y276298D03*
X165975D03*
Y286803D03*
Y296140D03*
X168975Y312307D03*
Y303868D03*
X165975D03*
Y312307D03*
X161377Y407575D03*
X161517Y436119D03*
X161257Y420869D03*
X159019Y439268D03*
X158807Y432969D03*
X159430Y461714D03*
X156430D03*
X159430Y483012D03*
X159259Y490930D03*
X159430Y468933D03*
Y476417D03*
X156430D03*
Y468933D03*
X156259Y490930D03*
X156430Y483012D03*
X159259Y513928D03*
Y498373D03*
Y506409D03*
X156259D03*
Y498373D03*
Y513928D03*
X157272Y604773D03*
X160272D03*
X157272Y633416D03*
Y613574D03*
Y624079D03*
X160272D03*
Y613574D03*
Y633416D03*
X157272Y641144D03*
Y649583D03*
X160272D03*
Y641144D03*
X161826Y756757D03*
X161131Y774878D03*
X161644Y764231D03*
X158956Y780982D03*
X161479Y784141D03*
X159053Y787280D03*
X158444Y822725D03*
X165872D03*
X162872D03*
X155444D03*
X165872Y830209D03*
X158444D03*
X165872Y836804D03*
X158444D03*
X165701Y844722D03*
X158273D03*
X165701Y852165D03*
X158273D03*
X155273D03*
X162701D03*
X155273Y844722D03*
X162701D03*
X155444Y836804D03*
X162872D03*
X155444Y830209D03*
X162872D03*
X165701Y860201D03*
X158273D03*
X165701Y867720D03*
X158273D03*
X155273D03*
X162701D03*
X155273Y860201D03*
X162701D03*
X163699Y972924D03*
X166699D03*
X163699Y983439D03*
Y993944D03*
X166699D03*
Y983439D03*
X163424Y1011298D03*
Y1003570D03*
Y1019737D03*
X166424D03*
Y1003570D03*
Y1011298D03*
X164539Y1116135D03*
X162140Y1106853D03*
X159382Y1136151D03*
X158456Y1129045D03*
X156124Y1176256D03*
X163552D03*
Y1183740D03*
Y1190335D03*
X156124D03*
Y1183740D03*
X163552Y1169037D03*
X156124D03*
X153124D03*
X160552D03*
X153124Y1183740D03*
Y1190335D03*
X160552D03*
Y1183740D03*
Y1176256D03*
X153124D03*
X169375Y1183740D03*
Y1190335D03*
Y1176256D03*
X163381Y1198253D03*
X155953D03*
X152953D03*
X160381D03*
X169204D03*
X158749Y1307733D03*
X155749D03*
X158749Y1328753D03*
Y1318248D03*
X155749D03*
Y1328753D03*
X158749Y1354257D03*
Y1338090D03*
Y1345818D03*
X155749D03*
Y1338090D03*
Y1354257D03*
X163099Y1457084D03*
X162524Y1462651D03*
X162242Y1471380D03*
X159216Y1477124D03*
X154109Y1499221D03*
X161537D03*
Y1506440D03*
X170360D03*
X154109D03*
X157109D03*
X164537D03*
Y1499221D03*
X157109D03*
X159526Y1483434D03*
X153938Y1528437D03*
X154109Y1513924D03*
Y1520519D03*
X170360Y1513924D03*
Y1520519D03*
X161537D03*
Y1513924D03*
X161366Y1528437D03*
X170189D03*
X164366D03*
X164537Y1513924D03*
Y1520519D03*
X157109D03*
Y1513924D03*
X156938Y1528437D03*
X153938Y1535880D03*
Y1543916D03*
Y1551435D03*
X170189Y1535880D03*
Y1543916D03*
X161366Y1535880D03*
Y1543916D03*
Y1551435D03*
X170189D03*
X164366D03*
Y1543916D03*
Y1535880D03*
X156938Y1551435D03*
Y1543916D03*
Y1535880D03*
X161492Y1667763D03*
Y1657248D03*
X158492D03*
Y1667763D03*
X161492Y1695333D03*
Y1687605D03*
Y1678268D03*
X158492D03*
Y1687605D03*
Y1695333D03*
X161492Y1703772D03*
X158492D03*
X163250Y1815631D03*
X162140Y1807740D03*
X161844Y1828225D03*
X159822Y1831380D03*
X159075Y1825087D03*
X155091Y1866003D03*
X162519D03*
X159519D03*
X152091D03*
X155091Y1880706D03*
Y1887301D03*
X162519D03*
Y1880706D03*
Y1873222D03*
X155091D03*
X152091D03*
X168342D03*
X159519D03*
Y1880706D03*
Y1887301D03*
X168342D03*
Y1880706D03*
X152091Y1887301D03*
Y1880706D03*
X154920Y1902662D03*
Y1910698D03*
X162348Y1902662D03*
Y1910698D03*
X154920Y1895219D03*
X162348D03*
X168171D03*
X159348D03*
X151920D03*
X159348Y1910698D03*
Y1902662D03*
X168171Y1910698D03*
Y1902662D03*
X151920Y1910698D03*
Y1902662D03*
X154920Y1918217D03*
X162348D03*
X168171D03*
X159348D03*
X151920D03*
X159991Y2083607D03*
X175219Y3002D03*
X176928Y126110D03*
Y118626D03*
Y111407D03*
X173928D03*
Y118626D03*
Y126110D03*
X176757Y140623D03*
X176928Y132705D03*
X176757Y148066D03*
X173757D03*
X173928Y132705D03*
X173757Y140623D03*
X176757Y156102D03*
Y163621D03*
X173757D03*
Y156102D03*
X175033Y261594D03*
Y268813D03*
X178033D03*
Y261594D03*
X175033Y282892D03*
X174862Y290810D03*
Y298253D03*
X175033Y276297D03*
X178033D03*
X177862Y298253D03*
Y290810D03*
X178033Y282892D03*
X174862Y313808D03*
Y306289D03*
X177862D03*
Y313808D03*
X182191Y822725D03*
X174695D03*
X171695D03*
X179191D03*
X174524Y844722D03*
Y852165D03*
X182191Y830209D03*
X174695D03*
X182191Y836804D03*
X174695D03*
X182020Y844722D03*
Y852165D03*
X179020D03*
Y844722D03*
X171695Y836804D03*
X179191D03*
X171695Y830209D03*
X179191D03*
X171524Y852165D03*
Y844722D03*
X174524Y860201D03*
Y867720D03*
X182020Y860201D03*
Y867720D03*
X179020D03*
Y860201D03*
X171524Y867720D03*
Y860201D03*
X184284Y948331D03*
X184196Y967371D03*
X184632Y983423D03*
X184353Y1001556D03*
X184118Y1019280D03*
X188385Y1020810D03*
X179871Y1176256D03*
Y1190335D03*
Y1183740D03*
X172375Y1176256D03*
Y1190335D03*
Y1183740D03*
X176871D03*
Y1190335D03*
Y1176256D03*
X179700Y1198253D03*
X172204D03*
X176700D03*
X177856Y1506440D03*
X173360D03*
X180856D03*
X177856Y1513924D03*
Y1520519D03*
X177685Y1528437D03*
X173189D03*
X173360Y1520519D03*
Y1513924D03*
X180685Y1528437D03*
X180856Y1520519D03*
Y1513924D03*
X177685Y1535880D03*
Y1543916D03*
Y1551435D03*
X173189D03*
Y1543916D03*
Y1535880D03*
X180685Y1551435D03*
Y1543916D03*
Y1535880D03*
X178838Y1880706D03*
Y1887301D03*
Y1873222D03*
X171342Y1880706D03*
Y1887301D03*
Y1873222D03*
X175838D03*
Y1887301D03*
Y1880706D03*
X178667Y1902662D03*
Y1910698D03*
Y1895219D03*
X171171Y1902662D03*
Y1910698D03*
Y1895219D03*
X175667D03*
Y1910698D03*
Y1902662D03*
X178667Y1918217D03*
X171171D03*
X175667D03*
X217732Y153964D03*
Y170131D03*
Y161692D03*
Y164692D03*
Y173131D03*
Y156964D03*
X219214Y1287272D03*
Y1301975D03*
X219349Y1308924D03*
X219214Y1294491D03*
X219178Y1324285D03*
Y1332321D03*
Y1316842D03*
Y1339840D03*
X219131Y1663167D03*
Y1670386D03*
Y1684465D03*
Y1677870D03*
X218960Y1692383D03*
Y1699826D03*
Y1707862D03*
Y1715381D03*
X209991Y2083607D03*
X225219Y3002D03*
X237955Y56999D03*
X240955D03*
X237955Y64483D03*
X237784Y78996D03*
X237955Y71078D03*
X240955D03*
X240784Y78996D03*
X240955Y64483D03*
X237784Y94475D03*
Y101994D03*
Y86439D03*
X240784D03*
Y101994D03*
Y94475D03*
X238741Y153964D03*
X227700D03*
X238741Y170131D03*
Y161692D03*
X227700Y170131D03*
Y161692D03*
Y164692D03*
Y173131D03*
X238741Y164692D03*
Y173131D03*
X227700Y156964D03*
X238741D03*
X241033Y244995D03*
X233537D03*
X224714Y237776D03*
Y244995D03*
X227714D03*
Y237776D03*
X236537Y244995D03*
X241033Y259074D03*
X240862Y266992D03*
Y274435D03*
X241033Y252479D03*
X233537Y259074D03*
X233366Y266992D03*
Y274435D03*
X224714Y259074D03*
X224543Y266992D03*
Y274435D03*
X233537Y252479D03*
X224714D03*
X227714D03*
X236537D03*
X227543Y274435D03*
Y266992D03*
X227714Y259074D03*
X236366Y274435D03*
Y266992D03*
X236537Y259074D03*
X240862Y289990D03*
Y282471D03*
X233366Y289990D03*
X224543D03*
X233366Y282471D03*
X224543D03*
X227543D03*
X236366D03*
X227543Y289990D03*
X236366D03*
X239746Y407393D03*
Y396878D03*
Y417898D03*
Y399878D03*
Y410393D03*
Y420898D03*
X229548Y461083D03*
X232548D03*
X238371Y482381D03*
X238200Y490299D03*
X229548Y482381D03*
X229377Y490299D03*
X238371Y468302D03*
Y475786D03*
X229548Y468302D03*
Y475786D03*
X232548D03*
Y468302D03*
X241371Y475786D03*
Y468302D03*
X232377Y490299D03*
X232548Y482381D03*
X241200Y490299D03*
X241371Y482381D03*
X238200Y513297D03*
X229377D03*
X238200Y497742D03*
X229377D03*
X238200Y505778D03*
X229377D03*
X232377D03*
X241200D03*
X232377Y497742D03*
X241200D03*
X232377Y513297D03*
X241200D03*
X227963Y608108D03*
X235391D03*
X227963Y601513D03*
X235391D03*
Y594029D03*
X227963D03*
X230963D03*
X238391D03*
Y601513D03*
X230963D03*
X238391Y608108D03*
X230963D03*
X227792Y631505D03*
X235220D03*
X227792Y623469D03*
X235220D03*
X227792Y616026D03*
X235220D03*
X238220D03*
X230792D03*
X238220Y623469D03*
X230792D03*
X238220Y631505D03*
X230792D03*
X227792Y639024D03*
X235220D03*
X238220D03*
X230792D03*
X234012Y754782D03*
X237012D03*
X234012Y762510D03*
Y770949D03*
X237012D03*
Y762510D03*
X241396Y862887D03*
Y855159D03*
Y871326D03*
X238396D03*
Y855159D03*
Y862887D03*
X231339Y959673D03*
X238767D03*
Y967157D03*
Y973752D03*
X231339D03*
Y967157D03*
X238767Y952454D03*
X231339D03*
X234339D03*
X241767D03*
X234339Y967157D03*
Y973752D03*
X241767D03*
Y967157D03*
Y959673D03*
X234339D03*
X238596Y981670D03*
X231168D03*
X238596Y997149D03*
Y989113D03*
X231168Y997149D03*
Y989113D03*
X234168D03*
Y997149D03*
X241596Y989113D03*
Y997149D03*
X234168Y981670D03*
X241596D03*
X238596Y1004668D03*
X231168D03*
X234168D03*
X241596D03*
X235709Y1124900D03*
Y1135415D03*
X232709D03*
Y1124900D03*
X242677Y1135415D03*
Y1124900D03*
X235709Y1145920D03*
X232709D03*
X242677D03*
X235659Y1215296D03*
X228231D03*
X235659Y1207777D03*
Y1199741D03*
X228231Y1207777D03*
Y1199741D03*
X231231D03*
Y1207777D03*
X238659Y1199741D03*
Y1207777D03*
X231231Y1215296D03*
X238659D03*
X226642Y1287272D03*
X222214D03*
X229642D03*
X226642Y1301975D03*
X235465D03*
X226777Y1308924D03*
X235600D03*
X242961Y1301975D03*
X243096Y1308924D03*
X226642Y1294491D03*
X235465D03*
X242961D03*
X222214D03*
X222349Y1308924D03*
X222214Y1301975D03*
X238465Y1294491D03*
X229642D03*
X238600Y1308924D03*
X229777D03*
X238465Y1301975D03*
X229642D03*
X226606Y1324285D03*
X235429D03*
X226606Y1332321D03*
X235429D03*
X242925Y1324285D03*
Y1332321D03*
X226606Y1316842D03*
X235429D03*
X242925D03*
X222178D03*
Y1332321D03*
Y1324285D03*
X238429Y1316842D03*
X229606D03*
X238429Y1332321D03*
X229606D03*
X238429Y1324285D03*
X229606D03*
X226606Y1339840D03*
X235429D03*
X242925D03*
X222178D03*
X238429D03*
X229606D03*
X235382Y1670386D03*
X226559Y1663167D03*
Y1670386D03*
X222131D03*
X229559D03*
Y1663167D03*
X238382Y1670386D03*
X222131Y1663167D03*
X242878Y1670386D03*
X235382Y1677870D03*
X235211Y1692383D03*
X235382Y1684465D03*
X226559D03*
Y1677870D03*
X226388Y1692383D03*
X221960D03*
X222131Y1677870D03*
Y1684465D03*
X229388Y1692383D03*
X229559Y1677870D03*
Y1684465D03*
X238382D03*
X238211Y1692383D03*
X238382Y1677870D03*
X242878D03*
Y1684465D03*
X242707Y1692383D03*
X235211Y1699826D03*
X226388D03*
X235211Y1715381D03*
Y1707862D03*
X226388D03*
Y1715381D03*
X221960D03*
Y1707862D03*
X229388Y1715381D03*
Y1707862D03*
X238211D03*
Y1715381D03*
X221960Y1699826D03*
X229388D03*
X238211D03*
X242707D03*
Y1707862D03*
Y1715381D03*
X226573Y2031480D03*
X236541D03*
X226573Y2020965D03*
X236541D03*
X242582D03*
Y2031480D03*
X231541Y2020965D03*
X221573D03*
X231541Y2031480D03*
X221573D03*
X226573Y2059050D03*
X236541Y2051322D03*
Y2059050D03*
X226573Y2041985D03*
Y2051322D03*
X236541Y2041985D03*
X242582Y2059050D03*
Y2051322D03*
Y2041985D03*
X231541D03*
X221573Y2051322D03*
Y2041985D03*
X231541Y2059050D03*
Y2051322D03*
X221573Y2059050D03*
X236541Y2067489D03*
X226573D03*
X242582D03*
X221573D03*
X231541D03*
X256566Y54944D03*
X264104D03*
X256566Y45572D03*
X264104D03*
Y48572D03*
X256566D03*
X245451Y56999D03*
X248451D03*
X256566Y65449D03*
X264104D03*
Y57944D03*
X256566D03*
X264104Y68449D03*
X256566D03*
X245451Y64483D03*
X245280Y78996D03*
X245451Y71078D03*
X248451D03*
X248280Y78996D03*
X248451Y64483D03*
X245280Y94475D03*
Y101994D03*
Y86439D03*
X248280D03*
Y101994D03*
Y94475D03*
X267627Y115559D03*
X267420Y147540D03*
X256861Y153964D03*
X248083D03*
X256861Y170131D03*
Y161692D03*
X248083Y170131D03*
Y161692D03*
Y164692D03*
Y173131D03*
X256861Y164692D03*
Y173131D03*
X248083Y156964D03*
X256861D03*
X264596Y221664D03*
X252818D03*
X255818D03*
X261596D03*
X264596Y242684D03*
Y232179D03*
X252818Y242684D03*
Y232179D03*
X255818D03*
Y242684D03*
X261596Y232179D03*
Y242684D03*
X244033Y244995D03*
X264596Y268188D03*
Y259749D03*
Y252021D03*
X252818Y268188D03*
Y252021D03*
Y259749D03*
X255818D03*
Y252021D03*
Y268188D03*
X261596Y252021D03*
Y259749D03*
Y268188D03*
X244033Y252479D03*
X243862Y274435D03*
Y266992D03*
X244033Y259074D03*
X243862Y282471D03*
Y289990D03*
X266040Y407146D03*
Y396631D03*
Y417651D03*
X257572Y396630D03*
Y407145D03*
X248714Y407536D03*
Y397021D03*
X257572Y417650D03*
X248714Y418041D03*
Y400021D03*
Y410536D03*
X257572Y410145D03*
Y399630D03*
X266040Y399631D03*
Y410146D03*
X248714Y421041D03*
X257572Y420650D03*
X266040Y420651D03*
X245867Y482381D03*
X245696Y490299D03*
X245867Y468302D03*
Y475786D03*
X248867D03*
Y468302D03*
X248696Y490299D03*
X248867Y482381D03*
X245696Y513297D03*
Y497742D03*
Y505778D03*
X248696D03*
Y497742D03*
Y513297D03*
X267166Y581440D03*
Y572639D03*
X264166D03*
Y581440D03*
X267166Y609010D03*
Y601282D03*
Y591945D03*
X264166D03*
Y601282D03*
Y609010D03*
X251710Y608108D03*
Y601513D03*
Y594029D03*
X244214Y608108D03*
Y601513D03*
Y594029D03*
X247214D03*
Y601513D03*
Y608108D03*
X254710Y594029D03*
Y601513D03*
Y608108D03*
X267166Y617449D03*
X264166D03*
X264433Y624321D03*
X267433D03*
X251539Y631505D03*
Y623469D03*
Y616026D03*
X244043Y631505D03*
Y623469D03*
Y616026D03*
X247043D03*
Y623469D03*
Y631505D03*
X254539Y616026D03*
Y623469D03*
Y631505D03*
X251539Y639024D03*
X244043D03*
X247043D03*
X254539D03*
X243980Y754782D03*
X255021D03*
X258021D03*
X246980D03*
X243980Y762510D03*
Y770949D03*
X255021Y762510D03*
Y770949D03*
X258021D03*
Y762510D03*
X246980Y770949D03*
Y762510D03*
X253174Y855159D03*
Y862887D03*
Y871326D03*
X250174D03*
Y862887D03*
Y855159D03*
X265766Y949344D03*
X262766D03*
X265766Y967106D03*
Y959859D03*
X265621Y974386D03*
X262621D03*
X262766Y959859D03*
Y967106D03*
X255086Y959673D03*
Y973752D03*
Y967157D03*
X247590Y959673D03*
Y973752D03*
Y967157D03*
X250590D03*
Y973752D03*
Y959673D03*
X258086Y967157D03*
Y973752D03*
Y959673D03*
X265621Y990553D03*
Y982114D03*
X262621D03*
Y990553D03*
X254915Y981670D03*
Y997149D03*
Y989113D03*
X247419Y981670D03*
Y997149D03*
Y989113D03*
X250419D03*
Y997149D03*
Y981670D03*
X257915Y989113D03*
Y997149D03*
Y981670D03*
X254915Y1004668D03*
X247419D03*
X250419D03*
X257915D03*
X263473Y1124613D03*
Y1135128D03*
X245677Y1124900D03*
Y1135415D03*
X254433Y1135271D03*
Y1124756D03*
X251433D03*
Y1135271D03*
X260473Y1135128D03*
Y1124613D03*
X263473Y1145633D03*
X245677Y1145920D03*
X254433Y1145776D03*
X251433D03*
X260473Y1145633D03*
X267194Y1191777D03*
X251978Y1215296D03*
X244482D03*
X251978Y1207777D03*
Y1199741D03*
X244482Y1207777D03*
Y1199741D03*
X247482D03*
Y1207777D03*
X254978Y1199741D03*
Y1207777D03*
X247482Y1215296D03*
X254978D03*
X259581Y1272430D03*
Y1282945D03*
X256581D03*
Y1272430D03*
X267622D03*
Y1282945D03*
X245961Y1294491D03*
X246096Y1308924D03*
X245961Y1301975D03*
X259581Y1293450D03*
Y1302787D03*
Y1310515D03*
X256581D03*
Y1302787D03*
Y1293450D03*
X267622Y1310515D03*
Y1302787D03*
Y1293450D03*
X245925Y1316842D03*
Y1332321D03*
Y1324285D03*
X259581Y1318954D03*
X256581D03*
X267622D03*
X245925Y1339840D03*
X260939Y1548010D03*
Y1534139D03*
Y1541055D03*
X263939D03*
Y1534139D03*
Y1548010D03*
X258564Y1621823D03*
X261564D03*
X258564Y1642843D03*
Y1632338D03*
X261564D03*
Y1642843D03*
X258564Y1668347D03*
Y1659908D03*
Y1652180D03*
X261564D03*
Y1659908D03*
Y1668347D03*
X245878Y1670386D03*
X262759Y1697613D03*
Y1676593D03*
Y1687108D03*
X251718Y1697613D03*
Y1687108D03*
Y1676593D03*
X254718D03*
Y1687108D03*
X265759D03*
Y1676593D03*
X254718Y1697613D03*
X265759D03*
X245707Y1692383D03*
X245878Y1684465D03*
Y1677870D03*
X262498Y1722140D03*
X262759Y1714678D03*
Y1706950D03*
X251457Y1722140D03*
X251718Y1714678D03*
Y1706950D03*
X265759D03*
X254718D03*
Y1714678D03*
X265759D03*
X265498Y1722140D03*
X254457D03*
X245707Y1715381D03*
Y1707862D03*
Y1699826D03*
X261639Y1819074D03*
Y1812119D03*
Y1805203D03*
X253468Y1819074D03*
Y1812119D03*
Y1805203D03*
X267396Y1812122D03*
Y1805206D03*
Y1819077D03*
X250468Y1805203D03*
Y1812119D03*
Y1819074D03*
X258639Y1805203D03*
Y1812119D03*
Y1819074D03*
X261459Y1826219D03*
X253288D03*
X261459Y1840090D03*
Y1833135D03*
X253288D03*
Y1840090D03*
X250288D03*
Y1833135D03*
X267037Y1840093D03*
Y1833138D03*
X258459Y1833135D03*
Y1840090D03*
X267037Y1826222D03*
X250288Y1826219D03*
X258459D03*
X247582Y2031480D03*
Y2020965D03*
X260337D03*
Y2031480D03*
X267115Y2020965D03*
Y2031480D03*
X255337D03*
Y2020965D03*
X247582Y2041985D03*
Y2051322D03*
Y2059050D03*
X260337Y2051322D03*
Y2059050D03*
Y2041985D03*
X267115D03*
Y2059050D03*
Y2051322D03*
X255337Y2041985D03*
Y2059050D03*
Y2051322D03*
X260337Y2067489D03*
X247582D03*
X267115D03*
X255337D03*
X259991Y2083607D03*
X275219Y3002D03*
X288102Y54944D03*
Y45572D03*
X271572Y54944D03*
X279754D03*
X271572Y45572D03*
X279754D03*
Y48572D03*
X271572D03*
X288102D03*
Y65449D03*
X271572D03*
X279754D03*
Y57944D03*
X271572D03*
X288102D03*
X279754Y68449D03*
X271572D03*
X288102D03*
X276523Y147585D03*
X276617Y256400D03*
X285513Y322688D03*
X274531Y407289D03*
Y396774D03*
Y417794D03*
Y399774D03*
Y410289D03*
Y420794D03*
X286665Y432844D03*
X274991Y463099D03*
X277776Y497341D03*
X268938D03*
X289569Y532762D03*
Y516595D03*
Y524323D03*
X278944Y581440D03*
Y572639D03*
X275944D03*
Y581440D03*
X278944Y601282D03*
Y609010D03*
Y591945D03*
X275944D03*
Y609010D03*
Y601282D03*
X290984Y607215D03*
X278944Y617449D03*
X275944D03*
X276044Y624627D03*
X279044D03*
X274514Y672192D03*
X283340D03*
X278184Y782643D03*
X270070Y812192D03*
X268686Y847488D03*
X277788Y847237D03*
X277544Y949344D03*
X274544D03*
X277544Y967106D03*
Y959859D03*
X277399Y974386D03*
X274399D03*
X274544Y959859D03*
Y967106D03*
X291194Y956442D03*
X277399Y990553D03*
Y982114D03*
X274399D03*
Y990553D03*
X285666Y1016162D03*
X272821Y1124471D03*
Y1134986D03*
X269821D03*
Y1124471D03*
X288188Y1131146D03*
X272821Y1145491D03*
X269821D03*
X284182Y1184455D03*
Y1192183D03*
X287182D03*
Y1184455D03*
X276807Y1191777D03*
X284182Y1200622D03*
X287182D03*
X270622Y1282945D03*
Y1272430D03*
Y1293450D03*
Y1302787D03*
Y1310515D03*
X289210Y1305634D03*
X270622Y1318954D03*
X284240Y1374544D03*
X275052Y1374715D03*
X275521Y1479435D03*
X275400Y1548190D03*
X268534Y1548010D03*
X282995Y1548190D03*
X275400Y1534319D03*
Y1541235D03*
X268534Y1534139D03*
Y1541055D03*
X282995Y1534319D03*
Y1541235D03*
X285995D03*
Y1534319D03*
X271534Y1541055D03*
Y1534139D03*
X278400Y1541235D03*
Y1534319D03*
X285995Y1548190D03*
X271534Y1548010D03*
X278400Y1548190D03*
X270342Y1621823D03*
X273342D03*
X270342Y1642843D03*
Y1632338D03*
X273342D03*
Y1642843D03*
X270342Y1668347D03*
Y1652180D03*
Y1659908D03*
X273342D03*
Y1652180D03*
Y1668347D03*
X289421Y1656558D03*
X279703Y1723398D03*
X289499Y1723735D03*
X270396Y1819077D03*
Y1805206D03*
Y1812122D03*
X270037Y1826222D03*
Y1833138D03*
Y1840093D03*
X286623Y1829400D03*
X287121Y1898327D03*
X278262D03*
X272115Y2031480D03*
Y2020965D03*
Y2051322D03*
Y2059050D03*
Y2041985D03*
Y2067489D03*
X299687Y78778D03*
X308651D03*
X294506Y322688D03*
X300537Y516309D03*
X307966Y516419D03*
Y524147D03*
X300537Y524037D03*
Y532476D03*
X307966Y532586D03*
X292569Y524323D03*
Y516595D03*
Y532762D03*
X304966Y532586D03*
X297537Y532476D03*
Y524037D03*
X304966Y524147D03*
Y516419D03*
X297537Y516309D03*
X313791Y532871D03*
Y516704D03*
Y524432D03*
X315187Y652457D03*
X304146D03*
X307146D03*
X315187Y661258D03*
X304146D03*
Y681100D03*
X315187D03*
Y671763D03*
X304146D03*
X307146D03*
Y681100D03*
Y661258D03*
X315187Y688828D03*
X304146D03*
Y697267D03*
X315187D03*
X307146D03*
Y688828D03*
X310194Y1020657D03*
X310078Y1007303D03*
X310274Y1001286D03*
X310143Y1014094D03*
X307143D03*
X307274Y1001286D03*
X307078Y1007303D03*
X307194Y1020657D03*
X294617Y1016162D03*
X310129Y1027081D03*
X309999Y1033718D03*
X306999D03*
X307129Y1027081D03*
X309159Y1184526D03*
Y1192254D03*
X300691Y1184526D03*
X292721Y1184312D03*
Y1192040D03*
X300691Y1192254D03*
X303691D03*
X295721Y1192040D03*
Y1184312D03*
X303691Y1184526D03*
X312159Y1192254D03*
Y1184526D03*
X309159Y1200693D03*
X300691D03*
X292721Y1200479D03*
X295721D03*
X303691Y1200693D03*
X312159D03*
X312823Y1472957D03*
X312464Y1480102D03*
X312823Y1466002D03*
Y1459086D03*
X295715Y1480099D03*
X295895Y1472954D03*
X304066D03*
X303886Y1480099D03*
X295895Y1459083D03*
Y1465999D03*
X304066D03*
Y1459083D03*
X301066D03*
Y1465999D03*
X292895D03*
Y1459083D03*
X300886Y1480099D03*
X301066Y1472954D03*
X292895D03*
X292715Y1480099D03*
X309823Y1459086D03*
Y1466002D03*
X309464Y1480102D03*
X309823Y1472957D03*
X312464Y1493973D03*
Y1487018D03*
X295715Y1487015D03*
Y1493970D03*
X303886D03*
Y1487015D03*
X300886D03*
Y1493970D03*
X292715D03*
Y1487015D03*
X309464Y1487018D03*
Y1493973D03*
X313894Y1513883D03*
X304870Y1543211D03*
X295675D03*
X292614Y1864565D03*
X293606Y1858668D03*
X295754Y1917148D03*
X303349D03*
X295754Y1910232D03*
X303349D03*
X310215Y1910412D03*
X314810D03*
X307215D03*
X300349Y1910232D03*
X292754D03*
X300349Y1917148D03*
X292754D03*
X310215Y1917328D03*
X295754Y1924103D03*
X303349D03*
X310215Y1924283D03*
X307215D03*
X314810D03*
X300349Y1924103D03*
X292754D03*
X307215Y1917328D03*
X314810D03*
X309991Y2083607D03*
X325219Y3002D03*
X317567Y78778D03*
X332775Y318634D03*
X332693Y311980D03*
X329693D03*
X329775Y318634D03*
X332775Y335272D03*
Y342461D03*
Y325935D03*
X329775D03*
Y342461D03*
Y335272D03*
X332685Y348655D03*
X329685D03*
X325139Y516632D03*
Y524360D03*
X316791Y524432D03*
Y516704D03*
Y532871D03*
X325139Y532799D03*
X322139D03*
Y524360D03*
Y516632D03*
X318187Y652457D03*
Y671763D03*
Y681100D03*
Y661258D03*
Y697267D03*
Y688828D03*
X321235Y1020657D03*
X321315Y1001286D03*
X321119Y1007303D03*
X321184Y1014094D03*
X318184D03*
X318119Y1007303D03*
X318315Y1001286D03*
X318235Y1020657D03*
X321170Y1027081D03*
X321040Y1033718D03*
X318040D03*
X318170Y1027081D03*
X325796Y1162266D03*
X317936Y1192253D03*
Y1184525D03*
X320936D03*
Y1192253D03*
X323403Y1172804D03*
X317936Y1200692D03*
X320936D03*
X317810Y1910412D03*
Y1917328D03*
Y1924283D03*
X320045Y2005215D03*
X343816Y318634D03*
X343734Y311980D03*
X340734D03*
X340816Y318634D03*
X361799Y311938D03*
X343816Y335272D03*
Y342461D03*
Y325935D03*
X340816D03*
Y342461D03*
Y335272D03*
X362236Y324983D03*
X343726Y348655D03*
X340726D03*
X354000Y652170D03*
X356559Y675167D03*
X363169Y1329686D03*
X351391D03*
X354391D03*
X363169Y1350706D03*
Y1360043D03*
Y1340201D03*
X351391Y1350706D03*
Y1360043D03*
Y1340201D03*
X354391D03*
Y1360043D03*
Y1350706D03*
X363169Y1376210D03*
Y1367771D03*
X351391Y1376210D03*
Y1367771D03*
X354391D03*
Y1376210D03*
X352337Y1887285D03*
X359991Y2083607D03*
X375219Y3002D03*
X366169Y1329686D03*
Y1340201D03*
Y1360043D03*
Y1350706D03*
X373564Y1352548D03*
X366169Y1367771D03*
Y1376210D03*
X374681Y1365620D03*
X366306Y1899864D03*
X402512Y17108D03*
Y67108D03*
Y117108D03*
Y167108D03*
Y217108D03*
Y267108D03*
Y317108D03*
Y367108D03*
Y417108D03*
Y467108D03*
Y517108D03*
Y567108D03*
Y617108D03*
Y667108D03*
Y717108D03*
Y767108D03*
Y817108D03*
Y867108D03*
Y917108D03*
Y967108D03*
Y1017108D03*
Y1067108D03*
Y1117108D03*
Y1167108D03*
Y1217108D03*
Y1267108D03*
Y1317108D03*
Y1367108D03*
Y1417108D03*
Y1467108D03*
Y1517108D03*
Y1567108D03*
Y1617108D03*
Y1667108D03*
Y1717108D03*
Y1767108D03*
Y1817108D03*
Y1867108D03*
Y1917108D03*
Y1967108D03*
Y2017108D03*
Y2067108D03*
X553766Y960546D03*
G54D12*
X22756Y113818D03*
Y125629D03*
X22480Y316838D03*
Y328649D03*
Y340460D03*
X22756Y1866819D03*
Y1878630D03*
Y1948818D03*
Y1960629D03*
Y2023818D03*
Y2035629D03*
X553766Y629796D03*
G54D21*
X64979Y35500D03*
Y45500D03*
Y55500D03*
X54979Y40500D03*
Y50500D03*
X64979Y65500D03*
X54979Y60500D03*
Y70500D03*
X64979Y171500D03*
X54979Y176500D03*
X64979Y181500D03*
Y191500D03*
Y201500D03*
X54979Y186500D03*
Y196500D03*
Y206500D03*
X64979Y244500D03*
X54979Y249500D03*
X64979Y254500D03*
Y264500D03*
Y274500D03*
X54979Y259500D03*
Y269500D03*
Y279500D03*
X64979Y380500D03*
Y390500D03*
X54979Y385500D03*
Y395500D03*
X64979Y400500D03*
Y410500D03*
X54979Y405500D03*
Y415500D03*
X553766Y677046D03*
G54D13*
X14073Y512197D03*
Y522000D03*
Y552000D03*
Y561803D03*
Y1580004D03*
Y1570201D03*
Y1610004D03*
Y1619807D03*
X65254Y519500D03*
Y529500D03*
Y539500D03*
X55254Y524500D03*
Y534500D03*
X65254Y549500D03*
X55254Y544500D03*
Y554500D03*
X65254Y1577504D03*
Y1587504D03*
Y1597504D03*
X55254Y1582504D03*
Y1592504D03*
Y1602504D03*
X65254Y1607504D03*
X55254Y1612504D03*
X189762Y73105D03*
X190289Y152050D03*
X190357Y247568D03*
X190817Y331786D03*
X189761Y421732D03*
X190553Y506517D03*
X192888Y598130D03*
X190816Y681645D03*
X191846Y774526D03*
X191606Y856244D03*
X196311Y947202D03*
X195516Y1032544D03*
X191250Y1122856D03*
X191342Y1206233D03*
X191846Y1299104D03*
X190552Y1380966D03*
X189463Y1474162D03*
X191079Y1557277D03*
X192143Y1648177D03*
X191607Y1731351D03*
X191530Y1823227D03*
X190289Y1900420D03*
X192125Y1998730D03*
X191530Y2043388D03*
X203542Y73105D03*
X204069Y152050D03*
X204137Y247568D03*
X204597Y331786D03*
X203541Y421732D03*
X204333Y506517D03*
X206668Y598130D03*
X204596Y681645D03*
X205626Y774526D03*
X205386Y856244D03*
X210091Y947202D03*
X209296Y1032544D03*
X205030Y1122856D03*
X205122Y1206233D03*
X205626Y1299104D03*
X204332Y1380966D03*
X203243Y1474162D03*
X204859Y1557277D03*
X205923Y1648177D03*
X205387Y1731351D03*
X205310Y1823227D03*
X204069Y1900420D03*
X205905Y1998730D03*
X205310Y2043388D03*
X553766Y724296D03*
G54D22*
X65354Y101180D03*
X55511Y105117D03*
X51574Y114960D03*
X55511Y124803D03*
X65354Y128740D03*
Y451180D03*
X55511Y455117D03*
X51574Y464960D03*
X55511Y474803D03*
X65354Y478740D03*
Y801180D03*
X55511Y805117D03*
X51574Y814960D03*
X55511Y824803D03*
X65354Y828740D03*
Y1151180D03*
X55511Y1155117D03*
X51574Y1164960D03*
X55511Y1174803D03*
X65354Y1178740D03*
Y1501180D03*
X55511Y1505117D03*
X51574Y1514960D03*
X55511Y1524803D03*
X65354Y1528740D03*
Y1851180D03*
X55511Y1855117D03*
X51574Y1864960D03*
X55511Y1874803D03*
X65354Y1878740D03*
X75197Y105117D03*
Y124803D03*
X79134Y114960D03*
Y464960D03*
X75197Y455117D03*
Y474803D03*
Y805117D03*
Y824803D03*
X79134Y814960D03*
Y1164960D03*
X75197Y1155117D03*
Y1174803D03*
Y1505117D03*
Y1524803D03*
X79134Y1514960D03*
Y1864960D03*
X75197Y1855117D03*
Y1874803D03*
X307086Y113385D03*
X297243Y117322D03*
X293306Y127165D03*
X297243Y137008D03*
X307086Y140945D03*
Y463385D03*
X297243Y467322D03*
X293306Y477165D03*
X297243Y487008D03*
X307086Y490945D03*
Y813385D03*
X297243Y817322D03*
X293306Y827165D03*
X297243Y837008D03*
X307086Y840945D03*
Y1329724D03*
X297243Y1333661D03*
X293306Y1343504D03*
X297243Y1353347D03*
X307086Y1357284D03*
Y1679724D03*
X297243Y1683661D03*
X293306Y1693504D03*
X297243Y1703347D03*
X307086Y1707284D03*
X307087Y2029723D03*
X297244Y2033660D03*
X293307Y2043503D03*
X297244Y2053346D03*
X307087Y2057283D03*
X320866Y127165D03*
X316929Y117322D03*
Y137008D03*
Y467322D03*
Y487008D03*
X320866Y477165D03*
Y827165D03*
X316929Y817322D03*
Y837008D03*
Y1333661D03*
Y1353347D03*
X320866Y1343504D03*
Y1693504D03*
X316929Y1683661D03*
Y1703347D03*
X316930Y2033660D03*
Y2053346D03*
X320867Y2043503D03*
X553766Y866046D03*
G54D14*
X30254Y514500D03*
Y559500D03*
Y1572504D03*
Y1617504D03*
X553766Y299046D03*
G54D23*
X65354Y114960D03*
Y464960D03*
Y814960D03*
Y1164960D03*
Y1514960D03*
Y1864960D03*
X307086Y127165D03*
Y477165D03*
Y827165D03*
Y1343504D03*
Y1693504D03*
X307087Y2043503D03*
X553766Y204546D03*
G54D24*
X119920Y18071D03*
Y28071D03*
Y38071D03*
Y48071D03*
Y58071D03*
Y68071D03*
Y78071D03*
Y88071D03*
Y98071D03*
Y108071D03*
Y118071D03*
Y128071D03*
Y138071D03*
Y148071D03*
Y158071D03*
Y168071D03*
Y178071D03*
Y188071D03*
Y198071D03*
Y208071D03*
Y218071D03*
Y228071D03*
Y238071D03*
Y248071D03*
Y258071D03*
Y268071D03*
Y278071D03*
Y288071D03*
Y298071D03*
Y308071D03*
Y318071D03*
Y328071D03*
Y366102D03*
Y376102D03*
Y386102D03*
Y396102D03*
Y406102D03*
Y416102D03*
Y426102D03*
Y436102D03*
Y446102D03*
Y456102D03*
Y466102D03*
Y476102D03*
Y486102D03*
Y496102D03*
Y506102D03*
Y516102D03*
Y526102D03*
Y536102D03*
Y546102D03*
Y556102D03*
Y566102D03*
Y576102D03*
Y586102D03*
Y596102D03*
Y606102D03*
Y616102D03*
Y626102D03*
Y636102D03*
Y646102D03*
Y656102D03*
Y666102D03*
Y676102D03*
Y714134D03*
Y724134D03*
Y734134D03*
Y744134D03*
Y754134D03*
Y764134D03*
Y774134D03*
Y784134D03*
Y794134D03*
Y804134D03*
Y814134D03*
Y824134D03*
Y834134D03*
Y844134D03*
Y854134D03*
Y864134D03*
Y874134D03*
Y884134D03*
Y894134D03*
Y904134D03*
Y914134D03*
Y924134D03*
Y934134D03*
Y944134D03*
Y954134D03*
Y964134D03*
Y974134D03*
Y984134D03*
Y994134D03*
Y1004134D03*
Y1014134D03*
Y1024134D03*
Y1062165D03*
Y1072165D03*
Y1082165D03*
Y1092165D03*
Y1102165D03*
Y1112165D03*
Y1122165D03*
Y1132165D03*
Y1142165D03*
Y1152165D03*
Y1162165D03*
Y1172165D03*
Y1182165D03*
Y1192165D03*
Y1202165D03*
Y1212165D03*
Y1222165D03*
Y1232165D03*
Y1242165D03*
Y1252165D03*
Y1262165D03*
Y1272165D03*
Y1282165D03*
Y1292165D03*
Y1302165D03*
Y1312165D03*
Y1322165D03*
Y1332165D03*
Y1342165D03*
Y1352165D03*
Y1362165D03*
Y1372165D03*
Y1410197D03*
Y1420197D03*
Y1430197D03*
Y1440197D03*
Y1450197D03*
Y1460197D03*
Y1470197D03*
Y1480197D03*
Y1490197D03*
Y1500197D03*
Y1510197D03*
Y1520197D03*
Y1530197D03*
Y1540197D03*
Y1550197D03*
Y1560197D03*
Y1570197D03*
Y1580197D03*
Y1590197D03*
Y1600197D03*
Y1610197D03*
Y1620197D03*
Y1630197D03*
Y1640197D03*
Y1650197D03*
Y1660197D03*
Y1670197D03*
Y1680197D03*
Y1690197D03*
Y1700197D03*
Y1710197D03*
Y1720197D03*
Y1758228D03*
Y1768228D03*
Y1778228D03*
Y1788228D03*
Y1798228D03*
Y1808228D03*
Y1818228D03*
Y1828228D03*
Y1838228D03*
Y1848228D03*
Y1858228D03*
Y1868228D03*
Y1878228D03*
Y1888228D03*
Y1898228D03*
Y1908228D03*
Y1918228D03*
Y1928228D03*
Y1938228D03*
Y1948228D03*
Y1958228D03*
Y1968228D03*
Y1978228D03*
Y1988228D03*
Y1998228D03*
Y2008228D03*
Y2018228D03*
Y2028228D03*
Y2038228D03*
Y2048228D03*
Y2058228D03*
Y2068228D03*
X139920Y28071D03*
Y18071D03*
Y58071D03*
Y48071D03*
Y38071D03*
Y78071D03*
Y68071D03*
Y98071D03*
Y88071D03*
Y128071D03*
Y118071D03*
Y108071D03*
Y148071D03*
Y138071D03*
Y178071D03*
Y168071D03*
Y158071D03*
Y198071D03*
Y188071D03*
Y228071D03*
Y218071D03*
Y208071D03*
Y248071D03*
Y238071D03*
Y268071D03*
Y258071D03*
Y298071D03*
Y288071D03*
Y278071D03*
Y318071D03*
Y308071D03*
Y328071D03*
Y366102D03*
Y396102D03*
Y386102D03*
Y376102D03*
Y416102D03*
Y406102D03*
Y436102D03*
Y426102D03*
Y466102D03*
Y456102D03*
Y446102D03*
Y486102D03*
Y476102D03*
Y516102D03*
Y506102D03*
Y496102D03*
Y536102D03*
Y526102D03*
Y566102D03*
Y556102D03*
Y546102D03*
Y586102D03*
Y576102D03*
Y606102D03*
Y596102D03*
Y636102D03*
Y626102D03*
Y616102D03*
Y656102D03*
Y646102D03*
Y676102D03*
Y666102D03*
Y734134D03*
Y724134D03*
Y714134D03*
Y754134D03*
Y744134D03*
Y774134D03*
Y764134D03*
Y804134D03*
Y794134D03*
Y784134D03*
Y824134D03*
Y814134D03*
Y854134D03*
Y844134D03*
Y834134D03*
Y874134D03*
Y864134D03*
Y904134D03*
Y894134D03*
Y884134D03*
Y924134D03*
Y914134D03*
Y944134D03*
Y934134D03*
Y974134D03*
Y964134D03*
Y954134D03*
Y994134D03*
Y984134D03*
Y1024134D03*
Y1014134D03*
Y1004134D03*
Y1072165D03*
Y1062165D03*
Y1092165D03*
Y1082165D03*
Y1122165D03*
Y1112165D03*
Y1102165D03*
Y1142165D03*
Y1132165D03*
Y1162165D03*
Y1152165D03*
Y1192165D03*
Y1182165D03*
Y1172165D03*
Y1212165D03*
Y1202165D03*
Y1242165D03*
Y1232165D03*
Y1222165D03*
Y1262165D03*
Y1252165D03*
Y1282165D03*
Y1272165D03*
Y1312165D03*
Y1302165D03*
Y1292165D03*
Y1332165D03*
Y1322165D03*
Y1362165D03*
Y1352165D03*
Y1342165D03*
Y1372165D03*
Y1410197D03*
Y1430197D03*
Y1420197D03*
Y1460197D03*
Y1450197D03*
Y1440197D03*
Y1480197D03*
Y1470197D03*
Y1500197D03*
Y1490197D03*
Y1530197D03*
Y1520197D03*
Y1510197D03*
Y1550197D03*
Y1540197D03*
Y1580197D03*
Y1570197D03*
Y1560197D03*
Y1600197D03*
Y1590197D03*
Y1620197D03*
Y1610197D03*
Y1650197D03*
Y1640197D03*
Y1630197D03*
Y1670197D03*
Y1660197D03*
Y1700197D03*
Y1690197D03*
Y1680197D03*
Y1720197D03*
Y1710197D03*
Y1768228D03*
Y1758228D03*
Y1798228D03*
Y1788228D03*
Y1778228D03*
Y1818228D03*
Y1808228D03*
Y1838228D03*
Y1828228D03*
Y1868228D03*
Y1858228D03*
Y1848228D03*
Y1888228D03*
Y1878228D03*
Y1918228D03*
Y1908228D03*
Y1898228D03*
Y1938228D03*
Y1928228D03*
Y1958228D03*
Y1948228D03*
Y1988228D03*
Y1978228D03*
Y1968228D03*
Y2008228D03*
Y1998228D03*
Y2038228D03*
Y2028228D03*
Y2018228D03*
Y2058228D03*
Y2048228D03*
Y2068228D03*
X553766Y582546D03*
G54D15*
X15547Y707364D03*
X25389D03*
X7673Y703427D03*
X15547Y715238D03*
Y723112D03*
Y730986D03*
X25389Y715238D03*
Y723112D03*
Y730986D03*
X7673Y711301D03*
Y719175D03*
Y727049D03*
X15547Y738860D03*
Y746734D03*
Y754608D03*
X25389Y738860D03*
Y746734D03*
Y754608D03*
X7673Y734923D03*
Y742797D03*
Y750671D03*
Y758545D03*
X15547Y762483D03*
Y770357D03*
Y778231D03*
X25389Y762483D03*
Y770357D03*
Y778231D03*
X7673Y766419D03*
Y774293D03*
Y782167D03*
X15547Y786105D03*
Y793979D03*
Y801853D03*
X25389Y786105D03*
Y793979D03*
Y801853D03*
X7673Y790041D03*
Y797915D03*
Y805790D03*
X15547Y809727D03*
Y817601D03*
Y825475D03*
X25389Y809727D03*
Y817601D03*
Y825475D03*
X7673Y813664D03*
Y821538D03*
Y829412D03*
X15547Y833349D03*
Y841223D03*
Y849097D03*
X25389Y833349D03*
Y841223D03*
Y849097D03*
X7673Y837286D03*
Y845160D03*
Y853034D03*
X15547Y856971D03*
Y864845D03*
Y872719D03*
X25389Y856971D03*
Y864845D03*
Y872719D03*
X7673Y860908D03*
Y868782D03*
Y876656D03*
X15547Y880593D03*
Y888467D03*
Y896341D03*
X25389Y880593D03*
Y888467D03*
Y896341D03*
X7673Y884530D03*
Y892404D03*
Y900278D03*
X15547Y904215D03*
Y912089D03*
Y919963D03*
X25389Y904215D03*
Y912089D03*
Y919963D03*
X7673Y908152D03*
Y916026D03*
Y923900D03*
X15547Y927837D03*
Y935711D03*
Y943585D03*
Y951459D03*
X25389Y927837D03*
Y935711D03*
Y943585D03*
Y951459D03*
X7673Y931774D03*
Y939648D03*
Y947522D03*
X15547Y959333D03*
Y967207D03*
Y975081D03*
X25389Y959333D03*
Y967207D03*
Y975081D03*
X7673Y955396D03*
Y963270D03*
Y971144D03*
Y979018D03*
Y994766D03*
X15547Y990829D03*
Y998703D03*
X25389Y990829D03*
Y998703D03*
X7673Y1002640D03*
Y1010514D03*
Y1018388D03*
X15547Y1006577D03*
Y1014451D03*
Y1022325D03*
X25389Y1006577D03*
Y1014451D03*
Y1022325D03*
X7673Y1026262D03*
X15547Y1030199D03*
X25389D03*
X15551Y1065629D03*
X25393D03*
X7677Y1061692D03*
Y1069566D03*
X15551Y1073503D03*
Y1081377D03*
Y1089251D03*
X25393Y1073503D03*
Y1081377D03*
Y1089251D03*
X7677Y1077440D03*
Y1085314D03*
Y1093188D03*
X15551Y1097125D03*
Y1104999D03*
Y1112873D03*
Y1120748D03*
X25393Y1097125D03*
Y1104999D03*
Y1112873D03*
Y1120748D03*
X7677Y1101062D03*
Y1108936D03*
Y1116810D03*
X15551Y1128622D03*
Y1136496D03*
Y1144370D03*
X25393Y1128622D03*
Y1136496D03*
Y1144370D03*
X7677Y1124684D03*
Y1132558D03*
Y1140432D03*
X15551Y1152244D03*
Y1160118D03*
Y1167992D03*
X25393Y1152244D03*
Y1160118D03*
Y1167992D03*
X7677Y1148306D03*
Y1156180D03*
Y1164055D03*
X15551Y1175866D03*
Y1183740D03*
Y1191614D03*
X25393Y1175866D03*
Y1183740D03*
Y1191614D03*
X7677Y1171929D03*
Y1179803D03*
Y1187677D03*
X15551Y1199488D03*
Y1207362D03*
Y1215236D03*
X25393Y1199488D03*
Y1207362D03*
Y1215236D03*
X7677Y1195551D03*
Y1203425D03*
Y1211299D03*
X15551Y1223110D03*
Y1230984D03*
Y1238858D03*
X25393Y1223110D03*
Y1230984D03*
Y1238858D03*
X7677Y1219173D03*
Y1227047D03*
Y1234921D03*
X15551Y1246732D03*
Y1254606D03*
Y1262480D03*
X25393Y1246732D03*
Y1254606D03*
Y1262480D03*
X7677Y1242795D03*
Y1250669D03*
Y1258543D03*
X15551Y1270354D03*
Y1278228D03*
Y1286102D03*
X25393Y1270354D03*
Y1278228D03*
Y1286102D03*
X7677Y1266417D03*
Y1274291D03*
Y1282165D03*
X15551Y1293976D03*
Y1301850D03*
Y1309724D03*
X25393Y1293976D03*
Y1301850D03*
Y1309724D03*
X7677Y1290039D03*
Y1297913D03*
Y1305787D03*
Y1313661D03*
X15551Y1317598D03*
Y1325472D03*
Y1333346D03*
X25393Y1317598D03*
Y1325472D03*
Y1333346D03*
X7677Y1321535D03*
Y1329409D03*
Y1337283D03*
Y1353031D03*
Y1360905D03*
X15551Y1349094D03*
Y1356968D03*
X25393Y1349094D03*
Y1356968D03*
X7677Y1368779D03*
Y1376653D03*
Y1384527D03*
X15551Y1364842D03*
Y1372716D03*
Y1380590D03*
X25393Y1364842D03*
Y1372716D03*
Y1380590D03*
X15551Y1388464D03*
X25393D03*
X33263Y703427D03*
Y711301D03*
Y719175D03*
Y727049D03*
Y734923D03*
Y742797D03*
Y750671D03*
Y758545D03*
Y766419D03*
Y774293D03*
Y782167D03*
Y790041D03*
Y797915D03*
Y805790D03*
Y813664D03*
Y821538D03*
Y829412D03*
Y837286D03*
Y845160D03*
Y853034D03*
Y860908D03*
Y868782D03*
Y876656D03*
Y884530D03*
Y892404D03*
Y900278D03*
Y908152D03*
Y916026D03*
Y923900D03*
Y931774D03*
Y939648D03*
Y947522D03*
Y955396D03*
Y963270D03*
Y971144D03*
Y979018D03*
Y994766D03*
Y1002640D03*
Y1010514D03*
Y1018388D03*
Y1026262D03*
X33267Y1061692D03*
Y1069566D03*
Y1077440D03*
Y1085314D03*
Y1093188D03*
Y1101062D03*
Y1108936D03*
Y1116810D03*
Y1124684D03*
Y1132558D03*
Y1140432D03*
Y1148306D03*
Y1156180D03*
Y1164055D03*
Y1171929D03*
Y1179803D03*
Y1187677D03*
Y1195551D03*
Y1203425D03*
Y1211299D03*
Y1219173D03*
Y1227047D03*
Y1234921D03*
Y1242795D03*
Y1250669D03*
Y1258543D03*
Y1266417D03*
Y1274291D03*
Y1282165D03*
Y1290039D03*
Y1297913D03*
Y1305787D03*
Y1313661D03*
Y1321535D03*
Y1329409D03*
Y1337283D03*
Y1353031D03*
Y1360905D03*
Y1368779D03*
Y1376653D03*
Y1384527D03*
X173385Y32520D03*
Y21890D03*
X183385Y32520D03*
Y21890D03*
X193385Y32520D03*
Y21890D03*
X173385Y196890D03*
X183385D03*
X193385D03*
X173385Y207520D03*
X183385D03*
X193385D03*
X173385Y371890D03*
X183385D03*
X193385D03*
X173385Y382520D03*
X183385D03*
X193385D03*
X173386Y557520D03*
Y546890D03*
X183386Y557520D03*
Y546890D03*
X193386Y557520D03*
Y546890D03*
X173386Y732520D03*
Y721890D03*
X183386Y732520D03*
Y721890D03*
X193386Y732520D03*
Y721890D03*
X173385Y896890D03*
X183385D03*
X193385D03*
X173385Y907520D03*
X183385D03*
X193385D03*
X173385Y1071890D03*
X183385D03*
X193385D03*
X173385Y1082520D03*
X183385D03*
X193385D03*
X173385Y1257520D03*
Y1246890D03*
X183385Y1257520D03*
Y1246890D03*
X193385Y1257520D03*
Y1246890D03*
X173385Y1432520D03*
Y1421890D03*
X183385Y1432520D03*
Y1421890D03*
X193385Y1432520D03*
Y1421890D03*
X173385Y1596890D03*
X183385D03*
X193385D03*
X173385Y1607520D03*
X183385D03*
X193385D03*
X173385Y1771890D03*
X183385D03*
X193385D03*
X173385Y1782520D03*
X183385D03*
X193385D03*
X173385Y1957520D03*
Y1946890D03*
X183385Y1957520D03*
Y1946890D03*
X193385Y1957520D03*
Y1946890D03*
X203385Y32520D03*
Y21890D03*
X213385Y32520D03*
Y21890D03*
X203385Y196890D03*
X213385D03*
X203385Y207520D03*
X213385D03*
X203385Y371890D03*
X213385D03*
X203385Y382520D03*
X213385D03*
X203386Y557520D03*
Y546890D03*
X213386Y557520D03*
Y546890D03*
X203386Y732520D03*
Y721890D03*
X213386Y732520D03*
Y721890D03*
X203385Y896890D03*
X213385D03*
X203385Y907520D03*
X213385D03*
X203385Y1071890D03*
X213385D03*
X203385Y1082520D03*
X213385D03*
X203385Y1257520D03*
Y1246890D03*
X213385Y1257520D03*
Y1246890D03*
X203385Y1432520D03*
Y1421890D03*
X213385Y1432520D03*
Y1421890D03*
X203385Y1596890D03*
X213385D03*
X203385Y1607520D03*
X213385D03*
X203385Y1771890D03*
X213385D03*
X203385Y1782520D03*
X213385D03*
X203385Y1957520D03*
Y1946890D03*
X213385Y1957520D03*
Y1946890D03*
X223385Y32520D03*
Y21890D03*
X233385Y32520D03*
Y21890D03*
X243385Y32520D03*
Y21890D03*
X223385Y196890D03*
X233385D03*
X243385D03*
X223385Y207520D03*
X233385D03*
X243385D03*
X223385Y371890D03*
X233385D03*
X243385D03*
X223385Y382520D03*
X233385D03*
X243385D03*
X223386Y557520D03*
Y546890D03*
X233386Y557520D03*
Y546890D03*
X243386Y557520D03*
Y546890D03*
X223386Y732520D03*
Y721890D03*
X233386Y732520D03*
Y721890D03*
X243386Y732520D03*
Y721890D03*
X223385Y896890D03*
X233385D03*
X243385D03*
X223385Y907520D03*
X233385D03*
X243385D03*
X223385Y1071890D03*
X233385D03*
X243385D03*
X223385Y1082520D03*
X233385D03*
X243385D03*
X223385Y1257520D03*
Y1246890D03*
X233385Y1257520D03*
Y1246890D03*
X243385Y1257520D03*
Y1246890D03*
X223385Y1432520D03*
Y1421890D03*
X233385Y1432520D03*
Y1421890D03*
X243385Y1432520D03*
Y1421890D03*
X223385Y1596890D03*
X233385D03*
X243385D03*
X223385Y1607520D03*
X233385D03*
X243385D03*
X223385Y1771890D03*
X233385D03*
X243385D03*
X223385Y1782520D03*
X233385D03*
X243385D03*
X223385Y1957520D03*
Y1946890D03*
X233385Y1957520D03*
Y1946890D03*
X243385Y1957520D03*
Y1946890D03*
X253385Y21890D03*
Y32520D03*
X263385Y21890D03*
Y32520D03*
X253385Y196890D03*
X263385D03*
X253385Y207520D03*
X263385D03*
X253385Y371890D03*
X263385D03*
X253385Y382520D03*
X263385D03*
X253386Y546890D03*
Y557520D03*
X263386Y546890D03*
Y557520D03*
X253386Y721890D03*
Y732520D03*
X263386Y721890D03*
Y732520D03*
X253385Y896890D03*
X263385D03*
X253385Y907520D03*
X263385D03*
X253385Y1071890D03*
X263385D03*
X253385Y1082520D03*
X263385D03*
X253385Y1246890D03*
Y1257520D03*
X263385Y1246890D03*
Y1257520D03*
X253385Y1421890D03*
Y1432520D03*
X263385Y1421890D03*
Y1432520D03*
X253385Y1596890D03*
X263385D03*
X253385Y1607520D03*
X263385D03*
X253385Y1771890D03*
X263385D03*
X253385Y1782520D03*
X263385D03*
X253385Y1946890D03*
Y1957520D03*
X263385Y1946890D03*
Y1957520D03*
X273385Y21890D03*
Y32520D03*
X283385Y21890D03*
Y32520D03*
X273385Y196890D03*
X283385D03*
X273385Y207520D03*
X283385D03*
X273385Y371890D03*
X283385D03*
X273385Y382520D03*
X283385D03*
X273386Y546890D03*
Y557520D03*
X283386Y546890D03*
Y557520D03*
X273386Y721890D03*
Y732520D03*
X283386Y721890D03*
Y732520D03*
X273385Y896890D03*
X283385D03*
X273385Y907520D03*
X283385D03*
X273385Y1071890D03*
X283385D03*
X273385Y1082520D03*
X283385D03*
X273385Y1246890D03*
Y1257520D03*
X283385Y1246890D03*
Y1257520D03*
X273385Y1421890D03*
Y1432520D03*
X283385Y1421890D03*
Y1432520D03*
X273385Y1596890D03*
X283385D03*
X273385Y1607520D03*
X283385D03*
X273385Y1771890D03*
X283385D03*
X273385Y1782520D03*
X283385D03*
X273385Y1946890D03*
Y1957520D03*
X283385Y1946890D03*
Y1957520D03*
X293385Y21890D03*
Y32520D03*
X303385Y21890D03*
Y32520D03*
X313385D03*
Y21890D03*
X293385Y196890D03*
X303385D03*
X313385D03*
X293385Y207520D03*
X303385D03*
X313385D03*
X293385Y371890D03*
X303385D03*
X313385D03*
X293385Y382520D03*
X303385D03*
X313385D03*
X293386Y546890D03*
Y557520D03*
X303386Y546890D03*
Y557520D03*
X313386D03*
Y546890D03*
X293386Y721890D03*
Y732520D03*
X303386Y721890D03*
Y732520D03*
X313386D03*
Y721890D03*
X293385Y896890D03*
X303385D03*
X313385D03*
X293385Y907520D03*
X303385D03*
X313385D03*
X293385Y1071890D03*
X303385D03*
X313385D03*
X293385Y1082520D03*
X303385D03*
X313385D03*
X293385Y1246890D03*
Y1257520D03*
X303385Y1246890D03*
Y1257520D03*
X313385D03*
Y1246890D03*
X293385Y1421890D03*
Y1432520D03*
X303385Y1421890D03*
Y1432520D03*
X313385D03*
Y1421890D03*
X293385Y1596890D03*
X303385D03*
X313385D03*
X293385Y1607520D03*
X303385D03*
X313385D03*
X293385Y1771890D03*
X303385D03*
X313385D03*
X293385Y1782520D03*
X303385D03*
X313385D03*
X293385Y1946890D03*
Y1957520D03*
X303385Y1946890D03*
Y1957520D03*
X313385D03*
Y1946890D03*
X337165Y24705D03*
X323385Y32520D03*
Y21890D03*
X337165Y34705D03*
Y199705D03*
X323385Y196890D03*
X337165Y209705D03*
X323385Y207520D03*
Y371890D03*
X337165Y374705D03*
Y384705D03*
X323385Y382520D03*
X337166Y549705D03*
Y559705D03*
X323386Y557520D03*
Y546890D03*
X337166Y724705D03*
X323386Y732520D03*
Y721890D03*
X337166Y734705D03*
X337165Y899705D03*
X323385Y896890D03*
X337165Y909705D03*
X323385Y907520D03*
Y1071890D03*
X337165Y1074705D03*
Y1084705D03*
X323385Y1082520D03*
X337165Y1249705D03*
Y1259705D03*
X323385Y1257520D03*
Y1246890D03*
X337165Y1424705D03*
Y1434705D03*
X323385Y1432520D03*
Y1421890D03*
X337165Y1599705D03*
X323385Y1596890D03*
X337165Y1609705D03*
X323385Y1607520D03*
Y1771890D03*
X337165Y1774705D03*
Y1784705D03*
X323385Y1782520D03*
X337165Y1949705D03*
Y1959705D03*
X323385Y1957520D03*
Y1946890D03*
X342165Y19705D03*
Y29705D03*
X347165Y24705D03*
X352165Y19705D03*
Y29705D03*
X357165Y24705D03*
X362165Y19705D03*
Y29705D03*
X347165Y34705D03*
X357165D03*
X342165Y194705D03*
X347165Y199705D03*
X352165Y194705D03*
X357165Y199705D03*
X362165Y194705D03*
X342165Y204705D03*
X347165Y209705D03*
X352165Y204705D03*
X357165Y209705D03*
X362165Y204705D03*
X342165Y369705D03*
X352165D03*
X362165D03*
X342165Y379705D03*
X347165Y374705D03*
Y384705D03*
X352165Y379705D03*
X357165Y374705D03*
Y384705D03*
X362165Y379705D03*
X342166Y544705D03*
Y554705D03*
X347166Y549705D03*
Y559705D03*
X352166Y544705D03*
Y554705D03*
X357166Y549705D03*
Y559705D03*
X362166Y544705D03*
Y554705D03*
X342166Y719705D03*
Y729705D03*
X347166Y724705D03*
X352166Y719705D03*
Y729705D03*
X357166Y724705D03*
X362166Y719705D03*
Y729705D03*
X347166Y734705D03*
X357166D03*
X342165Y894705D03*
X347165Y899705D03*
X352165Y894705D03*
X357165Y899705D03*
X362165Y894705D03*
X342165Y904705D03*
X347165Y909705D03*
X352165Y904705D03*
X357165Y909705D03*
X362165Y904705D03*
X342165Y1069705D03*
X352165D03*
X362165D03*
X342165Y1079705D03*
X347165Y1074705D03*
Y1084705D03*
X352165Y1079705D03*
X357165Y1074705D03*
Y1084705D03*
X362165Y1079705D03*
X342165Y1244705D03*
Y1254705D03*
X347165Y1249705D03*
Y1259705D03*
X352165Y1244705D03*
Y1254705D03*
X357165Y1249705D03*
Y1259705D03*
X362165Y1244705D03*
Y1254705D03*
X342165Y1419705D03*
Y1429705D03*
X347165Y1424705D03*
Y1434705D03*
X352165Y1419705D03*
Y1429705D03*
X357165Y1424705D03*
Y1434705D03*
X362165Y1419705D03*
Y1429705D03*
X342165Y1594705D03*
X347165Y1599705D03*
X352165Y1594705D03*
X357165Y1599705D03*
X362165Y1594705D03*
X342165Y1604705D03*
X347165Y1609705D03*
X352165Y1604705D03*
X357165Y1609705D03*
X362165Y1604705D03*
X342165Y1769705D03*
X352165D03*
X362165D03*
X342165Y1779705D03*
X347165Y1774705D03*
Y1784705D03*
X352165Y1779705D03*
X357165Y1774705D03*
Y1784705D03*
X362165Y1779705D03*
X342165Y1944705D03*
Y1954705D03*
X347165Y1949705D03*
Y1959705D03*
X352165Y1944705D03*
Y1954705D03*
X357165Y1949705D03*
Y1959705D03*
X362165Y1944705D03*
Y1954705D03*
X553766Y771546D03*
Y818796D03*
G54D25*
X163385Y27205D03*
Y202205D03*
Y377205D03*
X163386Y552205D03*
Y727205D03*
X163385Y902205D03*
Y1077205D03*
Y1252205D03*
Y1427205D03*
Y1602205D03*
Y1777205D03*
Y1952205D03*
X373385Y32520D03*
Y207520D03*
Y382520D03*
X373386Y557520D03*
Y732520D03*
X373385Y907520D03*
Y1082520D03*
Y1257520D03*
Y1432520D03*
Y1607520D03*
Y1782520D03*
Y1957520D03*
X553766Y346296D03*
G54D16*
X20468Y696341D03*
Y984333D03*
X20472Y1054606D03*
Y1342598D03*
X553766Y393546D03*
G54D17*
X23402Y1668874D03*
Y1685410D03*
Y1701945D03*
Y1718480D03*
Y1735016D03*
Y1751551D03*
Y1768087D03*
Y1784622D03*
Y1817693D03*
Y1801158D03*
X45056Y1668874D03*
Y1685410D03*
Y1701945D03*
Y1718480D03*
Y1735016D03*
Y1751551D03*
Y1768087D03*
Y1784622D03*
Y1817693D03*
Y1801158D03*
X553766Y535296D03*
G54D26*
X307086Y308267D03*
X553766Y157296D03*
G54D18*
X30473Y102007D03*
Y137440D03*
X30197Y305027D03*
Y352271D03*
X30473Y1855008D03*
Y1890441D03*
Y1937007D03*
Y1972440D03*
Y2012007D03*
Y2047440D03*
X553766Y440796D03*
G54D27*
X307086Y1883071D03*
X553766Y62796D03*
G54D19*
X45411Y505996D03*
Y568004D03*
Y1564000D03*
Y1626008D03*
X553766Y488046D03*
G54D28*
X359842Y78780D03*
Y253780D03*
Y428779D03*
Y603779D03*
Y778780D03*
Y953780D03*
Y1128779D03*
Y1303780D03*
Y1478780D03*
Y1653780D03*
Y1828779D03*
Y2003780D03*
X553766Y110046D03*
G54D29*
G01X-723776Y2987387D02*
Y-376795D01*
Y-489221D01*
X1782976D01*
Y-376795D01*
Y2987387D01*
X-723776D01*
G01X-95126Y0D02*
X-226725D01*
G01X-223725Y1064812D02*
Y0D01*
G01X-224725Y5000D02*
X-223725Y0D01*
X-222725Y5000D01*
X-224725D01*
G01X-223725Y1123662D02*
Y2086614D01*
G01X-222725Y2081614D02*
X-223725Y2086614D01*
X-224725Y2081614D01*
X-222725D01*
G01X-95126Y2086614D02*
X-226725D01*
G01X-96280Y2392259D02*
X-108780D01*
X-106280Y2390399D01*
G01X-96280D02*
Y2394119D01*
G01X-108780Y2404659D02*
X-108363Y2403419D01*
X-107322Y2402489D01*
X-106072Y2401869D01*
X-104405Y2401404D01*
X-102530Y2401249D01*
X-100655Y2401404D01*
X-98988Y2401869D01*
X-97738Y2402489D01*
X-96697Y2403419D01*
X-96280Y2404659D01*
X-96697Y2405899D01*
X-97738Y2406829D01*
X-98988Y2407449D01*
X-100655Y2407914D01*
X-102530Y2408069D01*
X-104405Y2407914D01*
X-106072Y2407449D01*
X-107322Y2406829D01*
X-108363Y2405899D01*
X-108780Y2404659D01*
G01X-96280Y2413029D02*
X-108780D01*
X-98363Y2417059D01*
X-108780Y2421089D01*
X-96280D01*
G01Y2425429D02*
X-108780D01*
X-98363Y2429459D01*
X-108780Y2433489D01*
X-96280D01*
G01X7874Y0D02*
X-92126D01*
G01X3000D02*
X-85641D01*
G01X-92126Y2086614D02*
X7874D01*
G01X-87421Y2397079D02*
Y2365583D01*
G01D02*
Y2416764D01*
G01X-21191Y2397079D02*
X-95295D01*
G01X-87421Y2467945D02*
Y2416764D01*
G01Y2436449D02*
Y2467945D01*
G01X-22045Y2436449D02*
X-95295D01*
G01X-62751Y2483687D02*
X-75251D01*
X-66293Y2477952D01*
Y2485702D01*
G01X-62751Y2490197D02*
X-75251D01*
X-64834Y2494227D01*
X-75251Y2498257D01*
X-62751D01*
G01Y2502597D02*
X-75251D01*
X-64834Y2506627D01*
X-75251Y2510657D01*
X-62751D01*
G01X-69451Y2628627D02*
X-67451D01*
Y2626227D01*
X-68051Y2625427D01*
X-68751Y2624894D01*
X-69751Y2624627D01*
X-70751Y2624894D01*
X-71451Y2625427D01*
X-72051Y2626227D01*
X-72451Y2627160D01*
X-72651Y2628227D01*
Y2629160D01*
X-72451Y2629960D01*
X-72051Y2630894D01*
X-71451Y2631694D01*
X-70851Y2632227D01*
X-70051Y2632627D01*
X-69351D01*
X-68551Y2632360D01*
X-67951Y2631827D01*
G01X-64051Y2624627D02*
Y2632627D01*
X-61551D01*
X-60751Y2632227D01*
X-60251Y2631694D01*
X-60051Y2630627D01*
X-60251Y2629560D01*
X-60851Y2628894D01*
X-61551Y2628494D01*
X-64051D01*
G01X-61551D02*
X-60051Y2624627D01*
G01X-54051D02*
X-54851Y2624760D01*
X-55551Y2625294D01*
X-56151Y2626094D01*
X-56551Y2627027D01*
X-56751Y2628094D01*
Y2629160D01*
X-56551Y2630227D01*
X-56151Y2631160D01*
X-55551Y2631960D01*
X-54851Y2632494D01*
X-54051Y2632627D01*
X-53251Y2632494D01*
X-52551Y2631960D01*
X-51951Y2631160D01*
X-51551Y2630227D01*
X-51351Y2629160D01*
Y2628094D01*
X-51551Y2627027D01*
X-51951Y2626094D01*
X-52551Y2625294D01*
X-53251Y2624760D01*
X-54051Y2624627D01*
G01X-48251Y2632627D02*
Y2626894D01*
X-47851Y2625693D01*
X-47051Y2624894D01*
X-46051Y2624627D01*
X-45051Y2624894D01*
X-44251Y2625693D01*
X-43851Y2626894D01*
Y2632627D01*
G01X-40051Y2624627D02*
Y2632627D01*
X-37651D01*
X-36851Y2632227D01*
X-36251Y2631294D01*
X-36051Y2630227D01*
X-36251Y2629160D01*
X-36751Y2628360D01*
X-37651Y2627960D01*
X-40051D01*
G01X-32151Y2625693D02*
X-31351Y2625027D01*
X-30451Y2624627D01*
X-29651D01*
X-28851Y2625027D01*
X-28251Y2625693D01*
X-27951Y2626627D01*
X-28151Y2627560D01*
X-28651Y2628360D01*
X-29551Y2628894D01*
X-30751Y2629160D01*
X-31451Y2629694D01*
X-31751Y2630627D01*
X-31551Y2631560D01*
X-31051Y2632227D01*
X-30351Y2632627D01*
X-29651D01*
X-28951Y2632360D01*
X-28351Y2631694D01*
G01X-16551Y2624627D02*
X-14051Y2632627D01*
X-11551Y2624627D01*
G01X-12451Y2627427D02*
X-15651D01*
G01X-551Y2624627D02*
X1949Y2632627D01*
X4449Y2624627D01*
G01X3549Y2627427D02*
X349D01*
G01X7649Y2624627D02*
Y2632627D01*
X12249Y2624627D01*
Y2632627D01*
G01X15749Y2624627D02*
Y2632627D01*
X17749D01*
X18549Y2632227D01*
X19149Y2631694D01*
X19649Y2630894D01*
X20049Y2629960D01*
X20149Y2628627D01*
X20049Y2627294D01*
X19649Y2626360D01*
X19149Y2625560D01*
X18549Y2625027D01*
X17749Y2624627D01*
X15749D01*
G01X34749Y2628894D02*
X35149Y2629294D01*
X35449Y2629960D01*
X35649Y2630894D01*
X35449Y2631694D01*
X35049Y2632227D01*
X34349Y2632627D01*
X31649D01*
Y2624627D01*
X34949D01*
X35649Y2625160D01*
X36049Y2625960D01*
X36249Y2626894D01*
X36049Y2627827D01*
X35449Y2628627D01*
X34749Y2628894D01*
X31649D01*
G01X41749Y2623160D02*
X42149Y2624894D01*
G01X49949Y2632627D02*
Y2624627D01*
G01X47649Y2632627D02*
X52249D01*
G01X55849Y2624627D02*
Y2632627D01*
G01X60049D02*
Y2624627D01*
G01Y2628627D02*
X55849D01*
G01X67949Y2624627D02*
X63949D01*
Y2632627D01*
X67949D01*
G01X66349Y2628760D02*
X63949D01*
G01X71649Y2624627D02*
Y2632627D01*
X76249Y2624627D01*
Y2632627D01*
G01X90549Y2628627D02*
X92549D01*
Y2626227D01*
X91949Y2625427D01*
X91249Y2624894D01*
X90249Y2624627D01*
X89249Y2624894D01*
X88549Y2625427D01*
X87949Y2626227D01*
X87549Y2627160D01*
X87349Y2628227D01*
Y2629160D01*
X87549Y2629960D01*
X87949Y2630894D01*
X88549Y2631694D01*
X89149Y2632227D01*
X89949Y2632627D01*
X90649D01*
X91449Y2632360D01*
X92049Y2631827D01*
G01X95949Y2624627D02*
Y2632627D01*
X98449D01*
X99249Y2632227D01*
X99749Y2631694D01*
X99949Y2630627D01*
X99749Y2629560D01*
X99149Y2628894D01*
X98449Y2628494D01*
X95949D01*
G01X98449D02*
X99949Y2624627D01*
G01X105949D02*
X105149Y2624760D01*
X104449Y2625294D01*
X103849Y2626094D01*
X103449Y2627027D01*
X103249Y2628094D01*
Y2629160D01*
X103449Y2630227D01*
X103849Y2631160D01*
X104449Y2631960D01*
X105149Y2632494D01*
X105949Y2632627D01*
X106749Y2632494D01*
X107449Y2631960D01*
X108049Y2631160D01*
X108449Y2630227D01*
X108649Y2629160D01*
Y2628094D01*
X108449Y2627027D01*
X108049Y2626094D01*
X107449Y2625294D01*
X106749Y2624760D01*
X105949Y2624627D01*
G01X111749Y2632627D02*
Y2626894D01*
X112149Y2625693D01*
X112949Y2624894D01*
X113949Y2624627D01*
X114949Y2624894D01*
X115749Y2625693D01*
X116149Y2626894D01*
Y2632627D01*
G01X119949Y2624627D02*
Y2632627D01*
X122349D01*
X123149Y2632227D01*
X123749Y2631294D01*
X123949Y2630227D01*
X123749Y2629160D01*
X123249Y2628360D01*
X122349Y2627960D01*
X119949D01*
G01X135449Y2624627D02*
X137949Y2632627D01*
X140449Y2624627D01*
G01X139549Y2627427D02*
X136349D01*
G01X156149Y2631960D02*
X155549Y2632360D01*
X154849Y2632627D01*
X154049D01*
X153149Y2632227D01*
X152449Y2631560D01*
X151949Y2630760D01*
X151549Y2629427D01*
X151449Y2628227D01*
X151649Y2627027D01*
X151949Y2626227D01*
X152549Y2625427D01*
X153249Y2624894D01*
X153949Y2624627D01*
X154649D01*
X155349Y2624894D01*
X155949Y2625294D01*
X156449Y2625827D01*
G01X159449Y2624627D02*
X161949Y2632627D01*
X164449Y2624627D01*
G01X163549Y2627427D02*
X160349D01*
G01X167649Y2624627D02*
Y2632627D01*
X172249Y2624627D01*
Y2632627D01*
G01X186749Y2628894D02*
X187149Y2629294D01*
X187449Y2629960D01*
X187649Y2630894D01*
X187449Y2631694D01*
X187049Y2632227D01*
X186349Y2632627D01*
X183649D01*
Y2624627D01*
X186949D01*
X187649Y2625160D01*
X188049Y2625960D01*
X188249Y2626894D01*
X188049Y2627827D01*
X187449Y2628627D01*
X186749Y2628894D01*
X183649D01*
G01X195949Y2624627D02*
X191949D01*
Y2632627D01*
X195949D01*
G01X194349Y2628760D02*
X191949D01*
G01X207949Y2624627D02*
Y2632627D01*
X210349D01*
X211149Y2632227D01*
X211749Y2631294D01*
X211949Y2630227D01*
X211749Y2629160D01*
X211249Y2628360D01*
X210349Y2627960D01*
X207949D01*
G01X215949Y2632627D02*
Y2624627D01*
X219949D01*
G01X223449D02*
X225949Y2632627D01*
X228449Y2624627D01*
G01X227549Y2627427D02*
X224349D01*
G01X236149Y2631960D02*
X235549Y2632360D01*
X234849Y2632627D01*
X234049D01*
X233149Y2632227D01*
X232449Y2631560D01*
X231949Y2630760D01*
X231549Y2629427D01*
X231449Y2628227D01*
X231649Y2627027D01*
X231949Y2626227D01*
X232549Y2625427D01*
X233249Y2624894D01*
X233949Y2624627D01*
X234649D01*
X235349Y2624894D01*
X235949Y2625294D01*
X236449Y2625827D01*
G01X243949Y2624627D02*
X239949D01*
Y2632627D01*
X243949D01*
G01X242349Y2628760D02*
X239949D01*
G01X247749Y2624627D02*
Y2632627D01*
X249749D01*
X250549Y2632227D01*
X251149Y2631694D01*
X251649Y2630894D01*
X252049Y2629960D01*
X252149Y2628627D01*
X252049Y2627294D01*
X251649Y2626360D01*
X251149Y2625560D01*
X250549Y2625027D01*
X249749Y2624627D01*
X247749D01*
G01X263849Y2625693D02*
X264649Y2625027D01*
X265549Y2624627D01*
X266349D01*
X267149Y2625027D01*
X267749Y2625693D01*
X268049Y2626627D01*
X267849Y2627560D01*
X267349Y2628360D01*
X266449Y2628894D01*
X265249Y2629160D01*
X264549Y2629694D01*
X264249Y2630627D01*
X264449Y2631560D01*
X264949Y2632227D01*
X265649Y2632627D01*
X266349D01*
X267049Y2632360D01*
X267649Y2631694D01*
G01X275949Y2624627D02*
X271949D01*
Y2632627D01*
X275949D01*
G01X274349Y2628760D02*
X271949D01*
G01X279949Y2624627D02*
Y2632627D01*
X282349D01*
X283149Y2632227D01*
X283749Y2631294D01*
X283949Y2630227D01*
X283749Y2629160D01*
X283249Y2628360D01*
X282349Y2627960D01*
X279949D01*
G01X287449Y2624627D02*
X289949Y2632627D01*
X292449Y2624627D01*
G01X291549Y2627427D02*
X288349D01*
G01X295949Y2624627D02*
Y2632627D01*
X298449D01*
X299249Y2632227D01*
X299749Y2631694D01*
X299949Y2630627D01*
X299749Y2629560D01*
X299149Y2628894D01*
X298449Y2628494D01*
X295949D01*
G01X298449D02*
X299949Y2624627D01*
G01X303449D02*
X305949Y2632627D01*
X308449Y2624627D01*
G01X307549Y2627427D02*
X304349D01*
G01X313949Y2632627D02*
Y2624627D01*
G01X311649Y2632627D02*
X316249D01*
G01X323949Y2624627D02*
X319949D01*
Y2632627D01*
X323949D01*
G01X322349Y2628760D02*
X319949D01*
G01X327949Y2632627D02*
Y2624627D01*
X331949D01*
G01X337949D02*
Y2628227D01*
X335949Y2632627D01*
G01X339949D02*
X337949Y2628227D01*
G01X352049Y2624627D02*
Y2632627D01*
X355849D01*
G01X354449Y2628760D02*
X352049D01*
G01X359949Y2624627D02*
Y2632627D01*
X362449D01*
X363249Y2632227D01*
X363749Y2631694D01*
X363949Y2630627D01*
X363749Y2629560D01*
X363149Y2628894D01*
X362449Y2628494D01*
X359949D01*
G01X362449D02*
X363949Y2624627D01*
G01X369949D02*
X369149Y2624760D01*
X368449Y2625294D01*
X367849Y2626094D01*
X367449Y2627027D01*
X367249Y2628094D01*
Y2629160D01*
X367449Y2630227D01*
X367849Y2631160D01*
X368449Y2631960D01*
X369149Y2632494D01*
X369949Y2632627D01*
X370749Y2632494D01*
X371449Y2631960D01*
X372049Y2631160D01*
X372449Y2630227D01*
X372649Y2629160D01*
Y2628094D01*
X372449Y2627027D01*
X372049Y2626094D01*
X371449Y2625294D01*
X370749Y2624760D01*
X369949Y2624627D01*
G01X375349D02*
Y2632627D01*
X377949Y2625960D01*
X380549Y2632627D01*
Y2624627D01*
G01X394549Y2628627D02*
X396549D01*
Y2626227D01*
X395949Y2625427D01*
X395249Y2624894D01*
X394249Y2624627D01*
X393249Y2624894D01*
X392549Y2625427D01*
X391949Y2626227D01*
X391549Y2627160D01*
X391349Y2628227D01*
Y2629160D01*
X391549Y2629960D01*
X391949Y2630894D01*
X392549Y2631694D01*
X393149Y2632227D01*
X393949Y2632627D01*
X394649D01*
X395449Y2632360D01*
X396049Y2631827D01*
G01X399949Y2624627D02*
Y2632627D01*
X402449D01*
X403249Y2632227D01*
X403749Y2631694D01*
X403949Y2630627D01*
X403749Y2629560D01*
X403149Y2628894D01*
X402449Y2628494D01*
X399949D01*
G01X402449D02*
X403949Y2624627D01*
G01X409949D02*
X409149Y2624760D01*
X408449Y2625294D01*
X407849Y2626094D01*
X407449Y2627027D01*
X407249Y2628094D01*
Y2629160D01*
X407449Y2630227D01*
X407849Y2631160D01*
X408449Y2631960D01*
X409149Y2632494D01*
X409949Y2632627D01*
X410749Y2632494D01*
X411449Y2631960D01*
X412049Y2631160D01*
X412449Y2630227D01*
X412649Y2629160D01*
Y2628094D01*
X412449Y2627027D01*
X412049Y2626094D01*
X411449Y2625294D01*
X410749Y2624760D01*
X409949Y2624627D01*
G01X415749Y2632627D02*
Y2626894D01*
X416149Y2625693D01*
X416949Y2624894D01*
X417949Y2624627D01*
X418949Y2624894D01*
X419749Y2625693D01*
X420149Y2626894D01*
Y2632627D01*
G01X423949Y2624627D02*
Y2632627D01*
X426349D01*
X427149Y2632227D01*
X427749Y2631294D01*
X427949Y2630227D01*
X427749Y2629160D01*
X427249Y2628360D01*
X426349Y2627960D01*
X423949D01*
G01X442749Y2628894D02*
X443149Y2629294D01*
X443449Y2629960D01*
X443649Y2630894D01*
X443449Y2631694D01*
X443049Y2632227D01*
X442349Y2632627D01*
X439649D01*
Y2624627D01*
X442949D01*
X443649Y2625160D01*
X444049Y2625960D01*
X444249Y2626894D01*
X444049Y2627827D01*
X443449Y2628627D01*
X442749Y2628894D01*
X439649D01*
G01X449949Y2624360D02*
X449749Y2624494D01*
Y2624760D01*
X449949Y2624894D01*
X450149Y2624760D01*
Y2624494D01*
X449949Y2624360D01*
G01X-70051Y2647627D02*
Y2639627D01*
G01X-72351Y2647627D02*
X-67751D01*
G01X-62051Y2639627D02*
X-62851Y2639760D01*
X-63551Y2640294D01*
X-64151Y2641094D01*
X-64551Y2642027D01*
X-64751Y2643094D01*
Y2644160D01*
X-64551Y2645227D01*
X-64151Y2646160D01*
X-63551Y2646960D01*
X-62851Y2647494D01*
X-62051Y2647627D01*
X-61251Y2647494D01*
X-60551Y2646960D01*
X-59951Y2646160D01*
X-59551Y2645227D01*
X-59351Y2644160D01*
Y2643094D01*
X-59551Y2642027D01*
X-59951Y2641094D01*
X-60551Y2640294D01*
X-61251Y2639760D01*
X-62051Y2639627D01*
G01X-46051Y2647627D02*
Y2639627D01*
G01X-48351Y2647627D02*
X-43751D01*
G01X-40151Y2639627D02*
Y2647627D01*
G01X-35951D02*
Y2639627D01*
G01Y2643627D02*
X-40151D01*
G01X-28051Y2639627D02*
X-32051D01*
Y2647627D01*
X-28051D01*
G01X-29651Y2643760D02*
X-32051D01*
G01X-13251Y2643894D02*
X-12851Y2644294D01*
X-12551Y2644960D01*
X-12351Y2645894D01*
X-12551Y2646694D01*
X-12951Y2647227D01*
X-13651Y2647627D01*
X-16351D01*
Y2639627D01*
X-13051D01*
X-12351Y2640160D01*
X-11951Y2640960D01*
X-11751Y2641894D01*
X-11951Y2642827D01*
X-12551Y2643627D01*
X-13251Y2643894D01*
X-16351D01*
G01X-6051Y2639627D02*
X-6851Y2639760D01*
X-7551Y2640294D01*
X-8151Y2641094D01*
X-8551Y2642027D01*
X-8751Y2643094D01*
Y2644160D01*
X-8551Y2645227D01*
X-8151Y2646160D01*
X-7551Y2646960D01*
X-6851Y2647494D01*
X-6051Y2647627D01*
X-5251Y2647494D01*
X-4551Y2646960D01*
X-3951Y2646160D01*
X-3551Y2645227D01*
X-3351Y2644160D01*
Y2643094D01*
X-3551Y2642027D01*
X-3951Y2641094D01*
X-4551Y2640294D01*
X-5251Y2639760D01*
X-6051Y2639627D01*
G01X-551D02*
X1949Y2647627D01*
X4449Y2639627D01*
G01X3549Y2642427D02*
X349D01*
G01X7949Y2639627D02*
Y2647627D01*
X10449D01*
X11249Y2647227D01*
X11749Y2646694D01*
X11949Y2645627D01*
X11749Y2644560D01*
X11149Y2643894D01*
X10449Y2643494D01*
X7949D01*
G01X10449D02*
X11949Y2639627D01*
G01X15749D02*
Y2647627D01*
X17749D01*
X18549Y2647227D01*
X19149Y2646694D01*
X19649Y2645894D01*
X20049Y2644960D01*
X20149Y2643627D01*
X20049Y2642294D01*
X19649Y2641360D01*
X19149Y2640560D01*
X18549Y2640027D01*
X17749Y2639627D01*
X15749D01*
G01X36149Y2646960D02*
X35549Y2647360D01*
X34849Y2647627D01*
X34049D01*
X33149Y2647227D01*
X32449Y2646560D01*
X31949Y2645760D01*
X31549Y2644427D01*
X31449Y2643227D01*
X31649Y2642027D01*
X31949Y2641227D01*
X32549Y2640427D01*
X33249Y2639894D01*
X33949Y2639627D01*
X34649D01*
X35349Y2639894D01*
X35949Y2640294D01*
X36449Y2640827D01*
G01X41949Y2639627D02*
X41149Y2639760D01*
X40449Y2640294D01*
X39849Y2641094D01*
X39449Y2642027D01*
X39249Y2643094D01*
Y2644160D01*
X39449Y2645227D01*
X39849Y2646160D01*
X40449Y2646960D01*
X41149Y2647494D01*
X41949Y2647627D01*
X42749Y2647494D01*
X43449Y2646960D01*
X44049Y2646160D01*
X44449Y2645227D01*
X44649Y2644160D01*
Y2643094D01*
X44449Y2642027D01*
X44049Y2641094D01*
X43449Y2640294D01*
X42749Y2639760D01*
X41949Y2639627D01*
G01X47749Y2647627D02*
Y2641894D01*
X48149Y2640693D01*
X48949Y2639894D01*
X49949Y2639627D01*
X50949Y2639894D01*
X51749Y2640693D01*
X52149Y2641894D01*
Y2647627D01*
G01X55949Y2639627D02*
Y2647627D01*
X58349D01*
X59149Y2647227D01*
X59749Y2646294D01*
X59949Y2645227D01*
X59749Y2644160D01*
X59249Y2643360D01*
X58349Y2642960D01*
X55949D01*
G01X65949Y2639627D02*
X65149Y2639760D01*
X64449Y2640294D01*
X63849Y2641094D01*
X63449Y2642027D01*
X63249Y2643094D01*
Y2644160D01*
X63449Y2645227D01*
X63849Y2646160D01*
X64449Y2646960D01*
X65149Y2647494D01*
X65949Y2647627D01*
X66749Y2647494D01*
X67449Y2646960D01*
X68049Y2646160D01*
X68449Y2645227D01*
X68649Y2644160D01*
Y2643094D01*
X68449Y2642027D01*
X68049Y2641094D01*
X67449Y2640294D01*
X66749Y2639760D01*
X65949Y2639627D01*
G01X71649D02*
Y2647627D01*
X76249Y2639627D01*
Y2647627D01*
G01X79849Y2640693D02*
X80649Y2640027D01*
X81549Y2639627D01*
X82349D01*
X83149Y2640027D01*
X83749Y2640693D01*
X84049Y2641627D01*
X83849Y2642560D01*
X83349Y2643360D01*
X82449Y2643894D01*
X81249Y2644160D01*
X80549Y2644694D01*
X80249Y2645627D01*
X80449Y2646560D01*
X80949Y2647227D01*
X81649Y2647627D01*
X82349D01*
X83049Y2647360D01*
X83649Y2646694D01*
G01X89949Y2639360D02*
X89749Y2639494D01*
Y2639760D01*
X89949Y2639894D01*
X90149Y2639760D01*
Y2639494D01*
X89949Y2639360D01*
G01X96749Y2647627D02*
X99149D01*
G01X97949D02*
Y2639627D01*
G01X96749D02*
X99149D01*
G01X104049D02*
Y2647627D01*
X107849D01*
G01X106449Y2643760D02*
X104049D01*
G01X120749Y2647627D02*
X123149D01*
G01X121949D02*
Y2639627D01*
G01X120749D02*
X123149D01*
G01X129949Y2647627D02*
Y2639627D01*
G01X127649Y2647627D02*
X132249D01*
G01X144749D02*
X147149D01*
G01X145949D02*
Y2639627D01*
G01X144749D02*
X147149D01*
G01X151849Y2640693D02*
X152649Y2640027D01*
X153549Y2639627D01*
X154349D01*
X155149Y2640027D01*
X155749Y2640693D01*
X156049Y2641627D01*
X155849Y2642560D01*
X155349Y2643360D01*
X154449Y2643894D01*
X153249Y2644160D01*
X152549Y2644694D01*
X152249Y2645627D01*
X152449Y2646560D01*
X152949Y2647227D01*
X153649Y2647627D01*
X154349D01*
X155049Y2647360D01*
X155649Y2646694D01*
G01X167649Y2639627D02*
Y2647627D01*
X172249Y2639627D01*
Y2647627D01*
G01X177949Y2639627D02*
X177149Y2639760D01*
X176449Y2640294D01*
X175849Y2641094D01*
X175449Y2642027D01*
X175249Y2643094D01*
Y2644160D01*
X175449Y2645227D01*
X175849Y2646160D01*
X176449Y2646960D01*
X177149Y2647494D01*
X177949Y2647627D01*
X178749Y2647494D01*
X179449Y2646960D01*
X180049Y2646160D01*
X180449Y2645227D01*
X180649Y2644160D01*
Y2643094D01*
X180449Y2642027D01*
X180049Y2641094D01*
X179449Y2640294D01*
X178749Y2639760D01*
X177949Y2639627D01*
G01X185949Y2647627D02*
Y2639627D01*
G01X183649Y2647627D02*
X188249D01*
G01X199949Y2639627D02*
Y2647627D01*
X202349D01*
X203149Y2647227D01*
X203749Y2646294D01*
X203949Y2645227D01*
X203749Y2644160D01*
X203249Y2643360D01*
X202349Y2642960D01*
X199949D01*
G01X209949Y2639627D02*
X209149Y2639760D01*
X208449Y2640294D01*
X207849Y2641094D01*
X207449Y2642027D01*
X207249Y2643094D01*
Y2644160D01*
X207449Y2645227D01*
X207849Y2646160D01*
X208449Y2646960D01*
X209149Y2647494D01*
X209949Y2647627D01*
X210749Y2647494D01*
X211449Y2646960D01*
X212049Y2646160D01*
X212449Y2645227D01*
X212649Y2644160D01*
Y2643094D01*
X212449Y2642027D01*
X212049Y2641094D01*
X211449Y2640294D01*
X210749Y2639760D01*
X209949Y2639627D01*
G01X215849Y2640693D02*
X216649Y2640027D01*
X217549Y2639627D01*
X218349D01*
X219149Y2640027D01*
X219749Y2640693D01*
X220049Y2641627D01*
X219849Y2642560D01*
X219349Y2643360D01*
X218449Y2643894D01*
X217249Y2644160D01*
X216549Y2644694D01*
X216249Y2645627D01*
X216449Y2646560D01*
X216949Y2647227D01*
X217649Y2647627D01*
X218349D01*
X219049Y2647360D01*
X219649Y2646694D01*
G01X223849Y2640693D02*
X224649Y2640027D01*
X225549Y2639627D01*
X226349D01*
X227149Y2640027D01*
X227749Y2640693D01*
X228049Y2641627D01*
X227849Y2642560D01*
X227349Y2643360D01*
X226449Y2643894D01*
X225249Y2644160D01*
X224549Y2644694D01*
X224249Y2645627D01*
X224449Y2646560D01*
X224949Y2647227D01*
X225649Y2647627D01*
X226349D01*
X227049Y2647360D01*
X227649Y2646694D01*
G01X232749Y2647627D02*
X235149D01*
G01X233949D02*
Y2639627D01*
G01X232749D02*
X235149D01*
G01X242749Y2643894D02*
X243149Y2644294D01*
X243449Y2644960D01*
X243649Y2645894D01*
X243449Y2646694D01*
X243049Y2647227D01*
X242349Y2647627D01*
X239649D01*
Y2639627D01*
X242949D01*
X243649Y2640160D01*
X244049Y2640960D01*
X244249Y2641894D01*
X244049Y2642827D01*
X243449Y2643627D01*
X242749Y2643894D01*
X239649D01*
G01X247949Y2647627D02*
Y2639627D01*
X251949D01*
G01X259949D02*
X255949D01*
Y2647627D01*
X259949D01*
G01X258349Y2643760D02*
X255949D01*
G01X273949Y2647627D02*
Y2639627D01*
G01X271649Y2647627D02*
X276249D01*
G01X281949Y2639627D02*
X281149Y2639760D01*
X280449Y2640294D01*
X279849Y2641094D01*
X279449Y2642027D01*
X279249Y2643094D01*
Y2644160D01*
X279449Y2645227D01*
X279849Y2646160D01*
X280449Y2646960D01*
X281149Y2647494D01*
X281949Y2647627D01*
X282749Y2647494D01*
X283449Y2646960D01*
X284049Y2646160D01*
X284449Y2645227D01*
X284649Y2644160D01*
Y2643094D01*
X284449Y2642027D01*
X284049Y2641094D01*
X283449Y2640294D01*
X282749Y2639760D01*
X281949Y2639627D01*
G01X296049D02*
Y2647627D01*
X299849D01*
G01X298449Y2643760D02*
X296049D01*
G01X303949Y2647627D02*
Y2639627D01*
X307949D01*
G01X311949Y2647627D02*
Y2639627D01*
X315949D01*
G01X321949D02*
X321149Y2639760D01*
X320449Y2640294D01*
X319849Y2641094D01*
X319449Y2642027D01*
X319249Y2643094D01*
Y2644160D01*
X319449Y2645227D01*
X319849Y2646160D01*
X320449Y2646960D01*
X321149Y2647494D01*
X321949Y2647627D01*
X322749Y2647494D01*
X323449Y2646960D01*
X324049Y2646160D01*
X324449Y2645227D01*
X324649Y2644160D01*
Y2643094D01*
X324449Y2642027D01*
X324049Y2641094D01*
X323449Y2640294D01*
X322749Y2639760D01*
X321949Y2639627D01*
G01X326949Y2647627D02*
X328349Y2639627D01*
X329949Y2647627D01*
X331549Y2639627D01*
X332949Y2647627D01*
G01X339949Y2639627D02*
X335949D01*
Y2647627D01*
X339949D01*
G01X338349Y2643760D02*
X335949D01*
G01X343949Y2639627D02*
Y2647627D01*
X346449D01*
X347249Y2647227D01*
X347749Y2646694D01*
X347949Y2645627D01*
X347749Y2644560D01*
X347149Y2643894D01*
X346449Y2643494D01*
X343949D01*
G01X346449D02*
X347949Y2639627D01*
G01X361949Y2647627D02*
Y2639627D01*
G01X359649Y2647627D02*
X364249D01*
G01X367849Y2639627D02*
Y2647627D01*
G01X372049D02*
Y2639627D01*
G01Y2643627D02*
X367849D01*
G01X379949Y2639627D02*
X375949D01*
Y2647627D01*
X379949D01*
G01X378349Y2643760D02*
X375949D01*
G01X391949Y2647627D02*
Y2639627D01*
X395949D01*
G01X401949D02*
X401149Y2639760D01*
X400449Y2640294D01*
X399849Y2641094D01*
X399449Y2642027D01*
X399249Y2643094D01*
Y2644160D01*
X399449Y2645227D01*
X399849Y2646160D01*
X400449Y2646960D01*
X401149Y2647494D01*
X401949Y2647627D01*
X402749Y2647494D01*
X403449Y2646960D01*
X404049Y2646160D01*
X404449Y2645227D01*
X404649Y2644160D01*
Y2643094D01*
X404449Y2642027D01*
X404049Y2641094D01*
X403449Y2640294D01*
X402749Y2639760D01*
X401949Y2639627D01*
G01X412149Y2646960D02*
X411549Y2647360D01*
X410849Y2647627D01*
X410049D01*
X409149Y2647227D01*
X408449Y2646560D01*
X407949Y2645760D01*
X407549Y2644427D01*
X407449Y2643227D01*
X407649Y2642027D01*
X407949Y2641227D01*
X408549Y2640427D01*
X409249Y2639894D01*
X409949Y2639627D01*
X410649D01*
X411349Y2639894D01*
X411949Y2640294D01*
X412449Y2640827D01*
G01X415449Y2639627D02*
X417949Y2647627D01*
X420449Y2639627D01*
G01X419549Y2642427D02*
X416349D01*
G01X425949Y2647627D02*
Y2639627D01*
G01X423649Y2647627D02*
X428249D01*
G01X432749D02*
X435149D01*
G01X433949D02*
Y2639627D01*
G01X432749D02*
X435149D01*
G01X441949D02*
X441149Y2639760D01*
X440449Y2640294D01*
X439849Y2641094D01*
X439449Y2642027D01*
X439249Y2643094D01*
Y2644160D01*
X439449Y2645227D01*
X439849Y2646160D01*
X440449Y2646960D01*
X441149Y2647494D01*
X441949Y2647627D01*
X442749Y2647494D01*
X443449Y2646960D01*
X444049Y2646160D01*
X444449Y2645227D01*
X444649Y2644160D01*
Y2643094D01*
X444449Y2642027D01*
X444049Y2641094D01*
X443449Y2640294D01*
X442749Y2639760D01*
X441949Y2639627D01*
G01X447649D02*
Y2647627D01*
X452249Y2639627D01*
Y2647627D01*
G01X455849Y2640693D02*
X456649Y2640027D01*
X457549Y2639627D01*
X458349D01*
X459149Y2640027D01*
X459749Y2640693D01*
X460049Y2641627D01*
X459849Y2642560D01*
X459349Y2643360D01*
X458449Y2643894D01*
X457249Y2644160D01*
X456549Y2644694D01*
X456249Y2645627D01*
X456449Y2646560D01*
X456949Y2647227D01*
X457649Y2647627D01*
X458349D01*
X459049Y2647360D01*
X459649Y2646694D01*
G01X472049Y2639627D02*
Y2647627D01*
X475849D01*
G01X474449Y2643760D02*
X472049D01*
G01X481949Y2639627D02*
X481149Y2639760D01*
X480449Y2640294D01*
X479849Y2641094D01*
X479449Y2642027D01*
X479249Y2643094D01*
Y2644160D01*
X479449Y2645227D01*
X479849Y2646160D01*
X480449Y2646960D01*
X481149Y2647494D01*
X481949Y2647627D01*
X482749Y2647494D01*
X483449Y2646960D01*
X484049Y2646160D01*
X484449Y2645227D01*
X484649Y2644160D01*
Y2643094D01*
X484449Y2642027D01*
X484049Y2641094D01*
X483449Y2640294D01*
X482749Y2639760D01*
X481949Y2639627D01*
G01X487949D02*
Y2647627D01*
X490449D01*
X491249Y2647227D01*
X491749Y2646694D01*
X491949Y2645627D01*
X491749Y2644560D01*
X491149Y2643894D01*
X490449Y2643494D01*
X487949D01*
G01X490449D02*
X491949Y2639627D01*
G01X506749Y2643894D02*
X507149Y2644294D01*
X507449Y2644960D01*
X507649Y2645894D01*
X507449Y2646694D01*
X507049Y2647227D01*
X506349Y2647627D01*
X503649D01*
Y2639627D01*
X506949D01*
X507649Y2640160D01*
X508049Y2640960D01*
X508249Y2641894D01*
X508049Y2642827D01*
X507449Y2643627D01*
X506749Y2643894D01*
X503649D01*
G01X513949Y2639627D02*
X513149Y2639760D01*
X512449Y2640294D01*
X511849Y2641094D01*
X511449Y2642027D01*
X511249Y2643094D01*
Y2644160D01*
X511449Y2645227D01*
X511849Y2646160D01*
X512449Y2646960D01*
X513149Y2647494D01*
X513949Y2647627D01*
X514749Y2647494D01*
X515449Y2646960D01*
X516049Y2646160D01*
X516449Y2645227D01*
X516649Y2644160D01*
Y2643094D01*
X516449Y2642027D01*
X516049Y2641094D01*
X515449Y2640294D01*
X514749Y2639760D01*
X513949Y2639627D01*
G01X521949Y2647627D02*
Y2639627D01*
G01X519649Y2647627D02*
X524249D01*
G01X527849Y2639627D02*
Y2647627D01*
G01X532049D02*
Y2639627D01*
G01Y2643627D02*
X527849D01*
G01X-72051Y2654627D02*
Y2662627D01*
X-69651D01*
X-68851Y2662227D01*
X-68251Y2661294D01*
X-68051Y2660227D01*
X-68251Y2659160D01*
X-68751Y2658360D01*
X-69651Y2657960D01*
X-72051D01*
G01X-64051Y2662627D02*
Y2654627D01*
X-60051D01*
G01X-52051D02*
X-56051D01*
Y2662627D01*
X-52051D01*
G01X-53651Y2658760D02*
X-56051D01*
G01X-48551Y2654627D02*
X-46051Y2662627D01*
X-43551Y2654627D01*
G01X-44451Y2657427D02*
X-47651D01*
G01X-40151Y2655693D02*
X-39351Y2655027D01*
X-38451Y2654627D01*
X-37651D01*
X-36851Y2655027D01*
X-36251Y2655693D01*
X-35951Y2656627D01*
X-36151Y2657560D01*
X-36651Y2658360D01*
X-37551Y2658894D01*
X-38751Y2659160D01*
X-39451Y2659694D01*
X-39751Y2660627D01*
X-39551Y2661560D01*
X-39051Y2662227D01*
X-38351Y2662627D01*
X-37651D01*
X-36951Y2662360D01*
X-36351Y2661694D01*
G01X-28051Y2654627D02*
X-32051D01*
Y2662627D01*
X-28051D01*
G01X-29651Y2658760D02*
X-32051D01*
G01X-15951Y2654627D02*
Y2662627D01*
X-12151D01*
G01X-13551Y2658760D02*
X-15951D01*
G01X-6051Y2654627D02*
X-6851Y2654760D01*
X-7551Y2655294D01*
X-8151Y2656094D01*
X-8551Y2657027D01*
X-8751Y2658094D01*
Y2659160D01*
X-8551Y2660227D01*
X-8151Y2661160D01*
X-7551Y2661960D01*
X-6851Y2662494D01*
X-6051Y2662627D01*
X-5251Y2662494D01*
X-4551Y2661960D01*
X-3951Y2661160D01*
X-3551Y2660227D01*
X-3351Y2659160D01*
Y2658094D01*
X-3551Y2657027D01*
X-3951Y2656094D01*
X-4551Y2655294D01*
X-5251Y2654760D01*
X-6051Y2654627D01*
G01X-51Y2662627D02*
Y2654627D01*
X3949D01*
G01X7949Y2662627D02*
Y2654627D01*
X11949D01*
G01X17949D02*
X17149Y2654760D01*
X16449Y2655294D01*
X15849Y2656094D01*
X15449Y2657027D01*
X15249Y2658094D01*
Y2659160D01*
X15449Y2660227D01*
X15849Y2661160D01*
X16449Y2661960D01*
X17149Y2662494D01*
X17949Y2662627D01*
X18749Y2662494D01*
X19449Y2661960D01*
X20049Y2661160D01*
X20449Y2660227D01*
X20649Y2659160D01*
Y2658094D01*
X20449Y2657027D01*
X20049Y2656094D01*
X19449Y2655294D01*
X18749Y2654760D01*
X17949Y2654627D01*
G01X22949Y2662627D02*
X24349Y2654627D01*
X25949Y2662627D01*
X27549Y2654627D01*
X28949Y2662627D01*
G01X41949D02*
Y2654627D01*
G01X39649Y2662627D02*
X44249D01*
G01X47849Y2654627D02*
Y2662627D01*
G01X52049D02*
Y2654627D01*
G01Y2658627D02*
X47849D01*
G01X59949Y2654627D02*
X55949D01*
Y2662627D01*
X59949D01*
G01X58349Y2658760D02*
X55949D01*
G01X71849Y2655693D02*
X72649Y2655027D01*
X73549Y2654627D01*
X74349D01*
X75149Y2655027D01*
X75749Y2655693D01*
X76049Y2656627D01*
X75849Y2657560D01*
X75349Y2658360D01*
X74449Y2658894D01*
X73249Y2659160D01*
X72549Y2659694D01*
X72249Y2660627D01*
X72449Y2661560D01*
X72949Y2662227D01*
X73649Y2662627D01*
X74349D01*
X75049Y2662360D01*
X75649Y2661694D01*
G01X79949Y2662627D02*
Y2654627D01*
X83949D01*
G01X88749Y2662627D02*
X91149D01*
G01X89949D02*
Y2654627D01*
G01X88749D02*
X91149D01*
G01X95749D02*
Y2662627D01*
X97749D01*
X98549Y2662227D01*
X99149Y2661694D01*
X99649Y2660894D01*
X100049Y2659960D01*
X100149Y2658627D01*
X100049Y2657294D01*
X99649Y2656360D01*
X99149Y2655560D01*
X98549Y2655027D01*
X97749Y2654627D01*
X95749D01*
G01X107949D02*
X103949D01*
Y2662627D01*
X107949D01*
G01X106349Y2658760D02*
X103949D01*
G01X111849Y2655693D02*
X112649Y2655027D01*
X113549Y2654627D01*
X114349D01*
X115149Y2655027D01*
X115749Y2655693D01*
X116049Y2656627D01*
X115849Y2657560D01*
X115349Y2658360D01*
X114449Y2658894D01*
X113249Y2659160D01*
X112549Y2659694D01*
X112249Y2660627D01*
X112449Y2661560D01*
X112949Y2662227D01*
X113649Y2662627D01*
X114349D01*
X115049Y2662360D01*
X115649Y2661694D01*
G01X129949Y2662627D02*
Y2654627D01*
G01X127649Y2662627D02*
X132249D01*
G01X137949Y2654627D02*
X137149Y2654760D01*
X136449Y2655294D01*
X135849Y2656094D01*
X135449Y2657027D01*
X135249Y2658094D01*
Y2659160D01*
X135449Y2660227D01*
X135849Y2661160D01*
X136449Y2661960D01*
X137149Y2662494D01*
X137949Y2662627D01*
X138749Y2662494D01*
X139449Y2661960D01*
X140049Y2661160D01*
X140449Y2660227D01*
X140649Y2659160D01*
Y2658094D01*
X140449Y2657027D01*
X140049Y2656094D01*
X139449Y2655294D01*
X138749Y2654760D01*
X137949Y2654627D01*
G01X154549Y2658627D02*
X156549D01*
Y2656227D01*
X155949Y2655427D01*
X155249Y2654894D01*
X154249Y2654627D01*
X153249Y2654894D01*
X152549Y2655427D01*
X151949Y2656227D01*
X151549Y2657160D01*
X151349Y2658227D01*
Y2659160D01*
X151549Y2659960D01*
X151949Y2660894D01*
X152549Y2661694D01*
X153149Y2662227D01*
X153949Y2662627D01*
X154649D01*
X155449Y2662360D01*
X156049Y2661827D01*
G01X163949Y2654627D02*
X159949D01*
Y2662627D01*
X163949D01*
G01X162349Y2658760D02*
X159949D01*
G01X167649Y2654627D02*
Y2662627D01*
X172249Y2654627D01*
Y2662627D01*
G01X179949Y2654627D02*
X175949D01*
Y2662627D01*
X179949D01*
G01X178349Y2658760D02*
X175949D01*
G01X183949Y2654627D02*
Y2662627D01*
X186449D01*
X187249Y2662227D01*
X187749Y2661694D01*
X187949Y2660627D01*
X187749Y2659560D01*
X187149Y2658894D01*
X186449Y2658494D01*
X183949D01*
G01X186449D02*
X187949Y2654627D01*
G01X191449D02*
X193949Y2662627D01*
X196449Y2654627D01*
G01X195549Y2657427D02*
X192349D01*
G01X201949Y2662627D02*
Y2654627D01*
G01X199649Y2662627D02*
X204249D01*
G01X211949Y2654627D02*
X207949D01*
Y2662627D01*
X211949D01*
G01X210349Y2658760D02*
X207949D01*
G01X225949Y2662627D02*
Y2654627D01*
G01X223649Y2662627D02*
X228249D01*
G01X231849Y2654627D02*
Y2662627D01*
G01X236049D02*
Y2654627D01*
G01Y2658627D02*
X231849D01*
G01X243949Y2654627D02*
X239949D01*
Y2662627D01*
X243949D01*
G01X242349Y2658760D02*
X239949D01*
G01X255949Y2654627D02*
Y2662627D01*
X258349D01*
X259149Y2662227D01*
X259749Y2661294D01*
X259949Y2660227D01*
X259749Y2659160D01*
X259249Y2658360D01*
X258349Y2657960D01*
X255949D01*
G01X263449Y2654627D02*
X265949Y2662627D01*
X268449Y2654627D01*
G01X267549Y2657427D02*
X264349D01*
G01X271749Y2654627D02*
Y2662627D01*
X273749D01*
X274549Y2662227D01*
X275149Y2661694D01*
X275649Y2660894D01*
X276049Y2659960D01*
X276149Y2658627D01*
X276049Y2657294D01*
X275649Y2656360D01*
X275149Y2655560D01*
X274549Y2655027D01*
X273749Y2654627D01*
X271749D01*
G01X279849Y2655693D02*
X280649Y2655027D01*
X281549Y2654627D01*
X282349D01*
X283149Y2655027D01*
X283749Y2655693D01*
X284049Y2656627D01*
X283849Y2657560D01*
X283349Y2658360D01*
X282449Y2658894D01*
X281249Y2659160D01*
X280549Y2659694D01*
X280249Y2660627D01*
X280449Y2661560D01*
X280949Y2662227D01*
X281649Y2662627D01*
X282349D01*
X283049Y2662360D01*
X283649Y2661694D01*
G01X295449Y2654627D02*
X297949Y2662627D01*
X300449Y2654627D01*
G01X299549Y2657427D02*
X296349D01*
G01X303649Y2654627D02*
Y2662627D01*
X308249Y2654627D01*
Y2662627D01*
G01X311749Y2654627D02*
Y2662627D01*
X313749D01*
X314549Y2662227D01*
X315149Y2661694D01*
X315649Y2660894D01*
X316049Y2659960D01*
X316149Y2658627D01*
X316049Y2657294D01*
X315649Y2656360D01*
X315149Y2655560D01*
X314549Y2655027D01*
X313749Y2654627D01*
X311749D01*
G01X327349D02*
Y2662627D01*
X329949Y2655960D01*
X332549Y2662627D01*
Y2654627D01*
G01X335449D02*
X337949Y2662627D01*
X340449Y2654627D01*
G01X339549Y2657427D02*
X336349D01*
G01X343849Y2655693D02*
X344649Y2655027D01*
X345549Y2654627D01*
X346349D01*
X347149Y2655027D01*
X347749Y2655693D01*
X348049Y2656627D01*
X347849Y2657560D01*
X347349Y2658360D01*
X346449Y2658894D01*
X345249Y2659160D01*
X344549Y2659694D01*
X344249Y2660627D01*
X344449Y2661560D01*
X344949Y2662227D01*
X345649Y2662627D01*
X346349D01*
X347049Y2662360D01*
X347649Y2661694D01*
G01X351749Y2654627D02*
Y2662627D01*
G01X355549D02*
X351749Y2657693D01*
G01X356149Y2654627D02*
X353449Y2659960D01*
G01X367449Y2654627D02*
X369949Y2662627D01*
X372449Y2654627D01*
G01X371549Y2657427D02*
X368349D01*
G01X375649Y2654627D02*
Y2662627D01*
X380249Y2654627D01*
Y2662627D01*
G01X383749Y2654627D02*
Y2662627D01*
X385749D01*
X386549Y2662227D01*
X387149Y2661694D01*
X387649Y2660894D01*
X388049Y2659960D01*
X388149Y2658627D01*
X388049Y2657294D01*
X387649Y2656360D01*
X387149Y2655560D01*
X386549Y2655027D01*
X385749Y2654627D01*
X383749D01*
G01X399449D02*
X401949Y2662627D01*
X404449Y2654627D01*
G01X403549Y2657427D02*
X400349D01*
G01X407749Y2654627D02*
Y2662627D01*
X409749D01*
X410549Y2662227D01*
X411149Y2661694D01*
X411649Y2660894D01*
X412049Y2659960D01*
X412149Y2658627D01*
X412049Y2657294D01*
X411649Y2656360D01*
X411149Y2655560D01*
X410549Y2655027D01*
X409749Y2654627D01*
X407749D01*
G01X415749D02*
Y2662627D01*
X417749D01*
X418549Y2662227D01*
X419149Y2661694D01*
X419649Y2660894D01*
X420049Y2659960D01*
X420149Y2658627D01*
X420049Y2657294D01*
X419649Y2656360D01*
X419149Y2655560D01*
X418549Y2655027D01*
X417749Y2654627D01*
X415749D01*
G01X433949Y2662627D02*
Y2654627D01*
G01X431649Y2662627D02*
X436249D01*
G01X439849Y2654627D02*
Y2662627D01*
G01X444049D02*
Y2654627D01*
G01Y2658627D02*
X439849D01*
G01X451949Y2654627D02*
X447949D01*
Y2662627D01*
X451949D01*
G01X450349Y2658760D02*
X447949D01*
G01X465949Y2662627D02*
Y2654627D01*
G01X463649Y2662627D02*
X468249D01*
G01X475949Y2654627D02*
X471949D01*
Y2662627D01*
X475949D01*
G01X474349Y2658760D02*
X471949D01*
G01X479849Y2655693D02*
X480649Y2655027D01*
X481549Y2654627D01*
X482349D01*
X483149Y2655027D01*
X483749Y2655693D01*
X484049Y2656627D01*
X483849Y2657560D01*
X483349Y2658360D01*
X482449Y2658894D01*
X481249Y2659160D01*
X480549Y2659694D01*
X480249Y2660627D01*
X480449Y2661560D01*
X480949Y2662227D01*
X481649Y2662627D01*
X482349D01*
X483049Y2662360D01*
X483649Y2661694D01*
G01X489949Y2662627D02*
Y2654627D01*
G01X487649Y2662627D02*
X492249D01*
G01X503949Y2654627D02*
Y2662627D01*
X506349D01*
X507149Y2662227D01*
X507749Y2661294D01*
X507949Y2660227D01*
X507749Y2659160D01*
X507249Y2658360D01*
X506349Y2657960D01*
X503949D01*
G01X511449Y2654627D02*
X513949Y2662627D01*
X516449Y2654627D01*
G01X515549Y2657427D02*
X512349D01*
G01X519749Y2654627D02*
Y2662627D01*
X521749D01*
X522549Y2662227D01*
X523149Y2661694D01*
X523649Y2660894D01*
X524049Y2659960D01*
X524149Y2658627D01*
X524049Y2657294D01*
X523649Y2656360D01*
X523149Y2655560D01*
X522549Y2655027D01*
X521749Y2654627D01*
X519749D01*
G01X527849Y2655693D02*
X528649Y2655027D01*
X529549Y2654627D01*
X530349D01*
X531149Y2655027D01*
X531749Y2655693D01*
X532049Y2656627D01*
X531849Y2657560D01*
X531349Y2658360D01*
X530449Y2658894D01*
X529249Y2659160D01*
X528549Y2659694D01*
X528249Y2660627D01*
X528449Y2661560D01*
X528949Y2662227D01*
X529649Y2662627D01*
X530349D01*
X531049Y2662360D01*
X531649Y2661694D01*
G01X-87251Y2670827D02*
X-86651Y2670160D01*
X-85951Y2669760D01*
X-85051Y2669627D01*
X-84151Y2669894D01*
X-83451Y2670427D01*
X-82951Y2671360D01*
X-82851Y2672427D01*
X-83051Y2673494D01*
X-83551Y2674160D01*
X-84251Y2674694D01*
X-84951Y2674827D01*
X-85651Y2674694D01*
X-86551Y2674160D01*
X-86251Y2677627D01*
X-83551D01*
G01X-77051Y2669360D02*
X-77251Y2669494D01*
Y2669760D01*
X-77051Y2669894D01*
X-76851Y2669760D01*
Y2669494D01*
X-77051Y2669360D01*
G01X-71051Y2669627D02*
Y2677627D01*
X-68651D01*
X-67851Y2677227D01*
X-67251Y2676294D01*
X-67051Y2675227D01*
X-67251Y2674160D01*
X-67751Y2673360D01*
X-68651Y2672960D01*
X-71051D01*
G01X-59051Y2669627D02*
X-63051D01*
Y2677627D01*
X-59051D01*
G01X-60651Y2673760D02*
X-63051D01*
G01X-51051Y2669627D02*
X-55051D01*
Y2677627D01*
X-51051D01*
G01X-52651Y2673760D02*
X-55051D01*
G01X-47051Y2677627D02*
Y2669627D01*
X-43051D01*
G01X-38251Y2677627D02*
X-35851D01*
G01X-37051D02*
Y2669627D01*
G01X-38251D02*
X-35851D01*
G01X-31351D02*
Y2677627D01*
X-26751Y2669627D01*
Y2677627D01*
G01X-20451Y2673627D02*
X-18451D01*
Y2671227D01*
X-19051Y2670427D01*
X-19751Y2669894D01*
X-20751Y2669627D01*
X-21751Y2669894D01*
X-22451Y2670427D01*
X-23051Y2671227D01*
X-23451Y2672160D01*
X-23651Y2673227D01*
Y2674160D01*
X-23451Y2674960D01*
X-23051Y2675894D01*
X-22451Y2676694D01*
X-21851Y2677227D01*
X-21051Y2677627D01*
X-20351D01*
X-19551Y2677360D01*
X-18951Y2676827D01*
G01X-7151Y2670693D02*
X-6351Y2670027D01*
X-5451Y2669627D01*
X-4651D01*
X-3851Y2670027D01*
X-3251Y2670693D01*
X-2951Y2671627D01*
X-3151Y2672560D01*
X-3651Y2673360D01*
X-4551Y2673894D01*
X-5751Y2674160D01*
X-6451Y2674694D01*
X-6751Y2675627D01*
X-6551Y2676560D01*
X-6051Y2677227D01*
X-5351Y2677627D01*
X-4651D01*
X-3951Y2677360D01*
X-3351Y2676694D01*
G01X2949Y2677627D02*
Y2669627D01*
G01X649Y2677627D02*
X5249D01*
G01X8949Y2669627D02*
Y2677627D01*
X11449D01*
X12249Y2677227D01*
X12749Y2676694D01*
X12949Y2675627D01*
X12749Y2674560D01*
X12149Y2673894D01*
X11449Y2673494D01*
X8949D01*
G01X11449D02*
X12949Y2669627D01*
G01X20949D02*
X16949D01*
Y2677627D01*
X20949D01*
G01X19349Y2673760D02*
X16949D01*
G01X24649Y2669627D02*
Y2677627D01*
X29249Y2669627D01*
Y2677627D01*
G01X35549Y2673627D02*
X37549D01*
Y2671227D01*
X36949Y2670427D01*
X36249Y2669894D01*
X35249Y2669627D01*
X34249Y2669894D01*
X33549Y2670427D01*
X32949Y2671227D01*
X32549Y2672160D01*
X32349Y2673227D01*
Y2674160D01*
X32549Y2674960D01*
X32949Y2675894D01*
X33549Y2676694D01*
X34149Y2677227D01*
X34949Y2677627D01*
X35649D01*
X36449Y2677360D01*
X37049Y2676827D01*
G01X42949Y2677627D02*
Y2669627D01*
G01X40649Y2677627D02*
X45249D01*
G01X48849Y2669627D02*
Y2677627D01*
G01X53049D02*
Y2669627D01*
G01Y2673627D02*
X48849D01*
G01X64449Y2669627D02*
X66949Y2677627D01*
X69449Y2669627D01*
G01X68549Y2672427D02*
X65349D01*
G01X72649Y2669627D02*
Y2677627D01*
X77249Y2669627D01*
Y2677627D01*
G01X80749Y2669627D02*
Y2677627D01*
X82749D01*
X83549Y2677227D01*
X84149Y2676694D01*
X84649Y2675894D01*
X85049Y2674960D01*
X85149Y2673627D01*
X85049Y2672294D01*
X84649Y2671360D01*
X84149Y2670560D01*
X83549Y2670027D01*
X82749Y2669627D01*
X80749D01*
G01X99749Y2673894D02*
X100149Y2674294D01*
X100449Y2674960D01*
X100649Y2675894D01*
X100449Y2676694D01*
X100049Y2677227D01*
X99349Y2677627D01*
X96649D01*
Y2669627D01*
X99949D01*
X100649Y2670160D01*
X101049Y2670960D01*
X101249Y2671894D01*
X101049Y2672827D01*
X100449Y2673627D01*
X99749Y2673894D01*
X96649D01*
G01X107549Y2673627D02*
X109549D01*
Y2671227D01*
X108949Y2670427D01*
X108249Y2669894D01*
X107249Y2669627D01*
X106249Y2669894D01*
X105549Y2670427D01*
X104949Y2671227D01*
X104549Y2672160D01*
X104349Y2673227D01*
Y2674160D01*
X104549Y2674960D01*
X104949Y2675894D01*
X105549Y2676694D01*
X106149Y2677227D01*
X106949Y2677627D01*
X107649D01*
X108449Y2677360D01*
X109049Y2676827D01*
G01X112449Y2669627D02*
X114949Y2677627D01*
X117449Y2669627D01*
G01X116549Y2672427D02*
X113349D01*
G01X128949Y2669627D02*
Y2677627D01*
X131349D01*
X132149Y2677227D01*
X132749Y2676294D01*
X132949Y2675227D01*
X132749Y2674160D01*
X132249Y2673360D01*
X131349Y2672960D01*
X128949D01*
G01X136449Y2669627D02*
X138949Y2677627D01*
X141449Y2669627D01*
G01X140549Y2672427D02*
X137349D01*
G01X144749Y2669627D02*
Y2677627D01*
X146749D01*
X147549Y2677227D01*
X148149Y2676694D01*
X148649Y2675894D01*
X149049Y2674960D01*
X149149Y2673627D01*
X149049Y2672294D01*
X148649Y2671360D01*
X148149Y2670560D01*
X147549Y2670027D01*
X146749Y2669627D01*
X144749D01*
G01X152849Y2670693D02*
X153649Y2670027D01*
X154549Y2669627D01*
X155349D01*
X156149Y2670027D01*
X156749Y2670693D01*
X157049Y2671627D01*
X156849Y2672560D01*
X156349Y2673360D01*
X155449Y2673894D01*
X154249Y2674160D01*
X153549Y2674694D01*
X153249Y2675627D01*
X153449Y2676560D01*
X153949Y2677227D01*
X154649Y2677627D01*
X155349D01*
X156049Y2677360D01*
X156649Y2676694D01*
G01X168449Y2669627D02*
X170949Y2677627D01*
X173449Y2669627D01*
G01X172549Y2672427D02*
X169349D01*
G01X176749Y2669627D02*
Y2677627D01*
X178749D01*
X179549Y2677227D01*
X180149Y2676694D01*
X180649Y2675894D01*
X181049Y2674960D01*
X181149Y2673627D01*
X181049Y2672294D01*
X180649Y2671360D01*
X180149Y2670560D01*
X179549Y2670027D01*
X178749Y2669627D01*
X176749D01*
G01X184849D02*
Y2677627D01*
G01X189049D02*
Y2669627D01*
G01Y2673627D02*
X184849D01*
G01X196949Y2669627D02*
X192949D01*
Y2677627D01*
X196949D01*
G01X195349Y2673760D02*
X192949D01*
G01X200849Y2670693D02*
X201649Y2670027D01*
X202549Y2669627D01*
X203349D01*
X204149Y2670027D01*
X204749Y2670693D01*
X205049Y2671627D01*
X204849Y2672560D01*
X204349Y2673360D01*
X203449Y2673894D01*
X202249Y2674160D01*
X201549Y2674694D01*
X201249Y2675627D01*
X201449Y2676560D01*
X201949Y2677227D01*
X202649Y2677627D01*
X203349D01*
X204049Y2677360D01*
X204649Y2676694D01*
G01X209749Y2677627D02*
X212149D01*
G01X210949D02*
Y2669627D01*
G01X209749D02*
X212149D01*
G01X218949D02*
X218149Y2669760D01*
X217449Y2670294D01*
X216849Y2671094D01*
X216449Y2672027D01*
X216249Y2673094D01*
Y2674160D01*
X216449Y2675227D01*
X216849Y2676160D01*
X217449Y2676960D01*
X218149Y2677494D01*
X218949Y2677627D01*
X219749Y2677494D01*
X220449Y2676960D01*
X221049Y2676160D01*
X221449Y2675227D01*
X221649Y2674160D01*
Y2673094D01*
X221449Y2672027D01*
X221049Y2671094D01*
X220449Y2670294D01*
X219749Y2669760D01*
X218949Y2669627D01*
G01X224649D02*
Y2677627D01*
X229249Y2669627D01*
Y2677627D01*
G01X242949D02*
Y2669627D01*
G01X240649Y2677627D02*
X245249D01*
G01X252949Y2669627D02*
X248949D01*
Y2677627D01*
X252949D01*
G01X251349Y2673760D02*
X248949D01*
G01X256849Y2670693D02*
X257649Y2670027D01*
X258549Y2669627D01*
X259349D01*
X260149Y2670027D01*
X260749Y2670693D01*
X261049Y2671627D01*
X260849Y2672560D01*
X260349Y2673360D01*
X259449Y2673894D01*
X258249Y2674160D01*
X257549Y2674694D01*
X257249Y2675627D01*
X257449Y2676560D01*
X257949Y2677227D01*
X258649Y2677627D01*
X259349D01*
X260049Y2677360D01*
X260649Y2676694D01*
G01X266949Y2677627D02*
Y2669627D01*
G01X264649Y2677627D02*
X269249D01*
G01X280949Y2669627D02*
Y2677627D01*
X283349D01*
X284149Y2677227D01*
X284749Y2676294D01*
X284949Y2675227D01*
X284749Y2674160D01*
X284249Y2673360D01*
X283349Y2672960D01*
X280949D01*
G01X288449Y2669627D02*
X290949Y2677627D01*
X293449Y2669627D01*
G01X292549Y2672427D02*
X289349D01*
G01X298949Y2677627D02*
Y2669627D01*
G01X296649Y2677627D02*
X301249D01*
G01X306949D02*
Y2669627D01*
G01X304649Y2677627D02*
X309249D01*
G01X316949Y2669627D02*
X312949D01*
Y2677627D01*
X316949D01*
G01X315349Y2673760D02*
X312949D01*
G01X320949Y2669627D02*
Y2677627D01*
X323449D01*
X324249Y2677227D01*
X324749Y2676694D01*
X324949Y2675627D01*
X324749Y2674560D01*
X324149Y2673894D01*
X323449Y2673494D01*
X320949D01*
G01X323449D02*
X324949Y2669627D01*
G01X328649D02*
Y2677627D01*
X333249Y2669627D01*
Y2677627D01*
G01X336849Y2670693D02*
X337649Y2670027D01*
X338549Y2669627D01*
X339349D01*
X340149Y2670027D01*
X340749Y2670693D01*
X341049Y2671627D01*
X340849Y2672560D01*
X340349Y2673360D01*
X339449Y2673894D01*
X338249Y2674160D01*
X337549Y2674694D01*
X337249Y2675627D01*
X337449Y2676560D01*
X337949Y2677227D01*
X338649Y2677627D01*
X339349D01*
X340049Y2677360D01*
X340649Y2676694D01*
G01X346949Y2669360D02*
X346749Y2669494D01*
Y2669760D01*
X346949Y2669894D01*
X347149Y2669760D01*
Y2669494D01*
X346949Y2669360D01*
G01X-83851Y2759627D02*
Y2767627D01*
X-87551Y2761894D01*
X-82551D01*
G01X-77051Y2759360D02*
X-77251Y2759494D01*
Y2759760D01*
X-77051Y2759894D01*
X-76851Y2759760D01*
Y2759494D01*
X-77051Y2759360D01*
G01X-66851Y2766960D02*
X-67451Y2767360D01*
X-68151Y2767627D01*
X-68951D01*
X-69851Y2767227D01*
X-70551Y2766560D01*
X-71051Y2765760D01*
X-71451Y2764427D01*
X-71551Y2763227D01*
X-71351Y2762027D01*
X-71051Y2761227D01*
X-70451Y2760427D01*
X-69751Y2759894D01*
X-69051Y2759627D01*
X-68351D01*
X-67651Y2759894D01*
X-67051Y2760294D01*
X-66551Y2760827D01*
G01X-61051Y2759627D02*
X-61851Y2759760D01*
X-62551Y2760294D01*
X-63151Y2761094D01*
X-63551Y2762027D01*
X-63751Y2763094D01*
Y2764160D01*
X-63551Y2765227D01*
X-63151Y2766160D01*
X-62551Y2766960D01*
X-61851Y2767494D01*
X-61051Y2767627D01*
X-60251Y2767494D01*
X-59551Y2766960D01*
X-58951Y2766160D01*
X-58551Y2765227D01*
X-58351Y2764160D01*
Y2763094D01*
X-58551Y2762027D01*
X-58951Y2761094D01*
X-59551Y2760294D01*
X-60251Y2759760D01*
X-61051Y2759627D01*
G01X-55351D02*
Y2767627D01*
X-50751Y2759627D01*
Y2767627D01*
G01X-45051D02*
Y2759627D01*
G01X-47351Y2767627D02*
X-42751D01*
G01X-39051Y2759627D02*
Y2767627D01*
X-36551D01*
X-35751Y2767227D01*
X-35251Y2766694D01*
X-35051Y2765627D01*
X-35251Y2764560D01*
X-35851Y2763894D01*
X-36551Y2763494D01*
X-39051D01*
G01X-36551D02*
X-35051Y2759627D01*
G01X-29051D02*
X-29851Y2759760D01*
X-30551Y2760294D01*
X-31151Y2761094D01*
X-31551Y2762027D01*
X-31751Y2763094D01*
Y2764160D01*
X-31551Y2765227D01*
X-31151Y2766160D01*
X-30551Y2766960D01*
X-29851Y2767494D01*
X-29051Y2767627D01*
X-28251Y2767494D01*
X-27551Y2766960D01*
X-26951Y2766160D01*
X-26551Y2765227D01*
X-26351Y2764160D01*
Y2763094D01*
X-26551Y2762027D01*
X-26951Y2761094D01*
X-27551Y2760294D01*
X-28251Y2759760D01*
X-29051Y2759627D01*
G01X-23051Y2767627D02*
Y2759627D01*
X-19051D01*
G01X-15051Y2767627D02*
Y2759627D01*
X-11051D01*
G01X-3051D02*
X-7051D01*
Y2767627D01*
X-3051D01*
G01X-4651Y2763760D02*
X-7051D01*
G01X749Y2759627D02*
Y2767627D01*
X2749D01*
X3549Y2767227D01*
X4149Y2766694D01*
X4649Y2765894D01*
X5049Y2764960D01*
X5149Y2763627D01*
X5049Y2762294D01*
X4649Y2761360D01*
X4149Y2760560D01*
X3549Y2760027D01*
X2749Y2759627D01*
X749D01*
G01X17749Y2767627D02*
X20149D01*
G01X18949D02*
Y2759627D01*
G01X17749D02*
X20149D01*
G01X24349D02*
Y2767627D01*
X26949Y2760960D01*
X29549Y2767627D01*
Y2759627D01*
G01X32949D02*
Y2767627D01*
X35349D01*
X36149Y2767227D01*
X36749Y2766294D01*
X36949Y2765227D01*
X36749Y2764160D01*
X36249Y2763360D01*
X35349Y2762960D01*
X32949D01*
G01X44949Y2759627D02*
X40949D01*
Y2767627D01*
X44949D01*
G01X43349Y2763760D02*
X40949D01*
G01X48749Y2759627D02*
Y2767627D01*
X50749D01*
X51549Y2767227D01*
X52149Y2766694D01*
X52649Y2765894D01*
X53049Y2764960D01*
X53149Y2763627D01*
X53049Y2762294D01*
X52649Y2761360D01*
X52149Y2760560D01*
X51549Y2760027D01*
X50749Y2759627D01*
X48749D01*
G01X56449D02*
X58949Y2767627D01*
X61449Y2759627D01*
G01X60549Y2762427D02*
X57349D01*
G01X64649Y2759627D02*
Y2767627D01*
X69249Y2759627D01*
Y2767627D01*
G01X77149Y2766960D02*
X76549Y2767360D01*
X75849Y2767627D01*
X75049D01*
X74149Y2767227D01*
X73449Y2766560D01*
X72949Y2765760D01*
X72549Y2764427D01*
X72449Y2763227D01*
X72649Y2762027D01*
X72949Y2761227D01*
X73549Y2760427D01*
X74249Y2759894D01*
X74949Y2759627D01*
X75649D01*
X76349Y2759894D01*
X76949Y2760294D01*
X77449Y2760827D01*
G01X84949Y2759627D02*
X80949D01*
Y2767627D01*
X84949D01*
G01X83349Y2763760D02*
X80949D01*
G01X99749Y2763894D02*
X100149Y2764294D01*
X100449Y2764960D01*
X100649Y2765894D01*
X100449Y2766694D01*
X100049Y2767227D01*
X99349Y2767627D01*
X96649D01*
Y2759627D01*
X99949D01*
X100649Y2760160D01*
X101049Y2760960D01*
X101249Y2761894D01*
X101049Y2762827D01*
X100449Y2763627D01*
X99749Y2763894D01*
X96649D01*
G01X106949Y2759627D02*
X106149Y2759760D01*
X105449Y2760294D01*
X104849Y2761094D01*
X104449Y2762027D01*
X104249Y2763094D01*
Y2764160D01*
X104449Y2765227D01*
X104849Y2766160D01*
X105449Y2766960D01*
X106149Y2767494D01*
X106949Y2767627D01*
X107749Y2767494D01*
X108449Y2766960D01*
X109049Y2766160D01*
X109449Y2765227D01*
X109649Y2764160D01*
Y2763094D01*
X109449Y2762027D01*
X109049Y2761094D01*
X108449Y2760294D01*
X107749Y2759760D01*
X106949Y2759627D01*
G01X112449D02*
X114949Y2767627D01*
X117449Y2759627D01*
G01X116549Y2762427D02*
X113349D01*
G01X120949Y2759627D02*
Y2767627D01*
X123449D01*
X124249Y2767227D01*
X124749Y2766694D01*
X124949Y2765627D01*
X124749Y2764560D01*
X124149Y2763894D01*
X123449Y2763494D01*
X120949D01*
G01X123449D02*
X124949Y2759627D01*
G01X128749D02*
Y2767627D01*
X130749D01*
X131549Y2767227D01*
X132149Y2766694D01*
X132649Y2765894D01*
X133049Y2764960D01*
X133149Y2763627D01*
X133049Y2762294D01*
X132649Y2761360D01*
X132149Y2760560D01*
X131549Y2760027D01*
X130749Y2759627D01*
X128749D01*
G01X138949Y2759360D02*
X138749Y2759494D01*
Y2759760D01*
X138949Y2759894D01*
X139149Y2759760D01*
Y2759494D01*
X138949Y2759360D01*
G01X152849Y2760693D02*
X153649Y2760027D01*
X154549Y2759627D01*
X155349D01*
X156149Y2760027D01*
X156749Y2760693D01*
X157049Y2761627D01*
X156849Y2762560D01*
X156349Y2763360D01*
X155449Y2763894D01*
X154249Y2764160D01*
X153549Y2764694D01*
X153249Y2765627D01*
X153449Y2766560D01*
X153949Y2767227D01*
X154649Y2767627D01*
X155349D01*
X156049Y2767360D01*
X156649Y2766694D01*
G01X164949Y2759627D02*
X160949D01*
Y2767627D01*
X164949D01*
G01X163349Y2763760D02*
X160949D01*
G01X172949Y2759627D02*
X168949D01*
Y2767627D01*
X172949D01*
G01X171349Y2763760D02*
X168949D01*
G01X184949Y2767627D02*
Y2759627D01*
X188949D01*
G01X192449D02*
X194949Y2767627D01*
X197449Y2759627D01*
G01X196549Y2762427D02*
X193349D01*
G01X202949Y2759627D02*
Y2763227D01*
X200949Y2767627D01*
G01X204949D02*
X202949Y2763227D01*
G01X212949Y2759627D02*
X208949D01*
Y2767627D01*
X212949D01*
G01X211349Y2763760D02*
X208949D01*
G01X216949Y2759627D02*
Y2767627D01*
X219449D01*
X220249Y2767227D01*
X220749Y2766694D01*
X220949Y2765627D01*
X220749Y2764560D01*
X220149Y2763894D01*
X219449Y2763494D01*
X216949D01*
G01X219449D02*
X220949Y2759627D01*
G01X232849Y2760693D02*
X233649Y2760027D01*
X234549Y2759627D01*
X235349D01*
X236149Y2760027D01*
X236749Y2760693D01*
X237049Y2761627D01*
X236849Y2762560D01*
X236349Y2763360D01*
X235449Y2763894D01*
X234249Y2764160D01*
X233549Y2764694D01*
X233249Y2765627D01*
X233449Y2766560D01*
X233949Y2767227D01*
X234649Y2767627D01*
X235349D01*
X236049Y2767360D01*
X236649Y2766694D01*
G01X242949Y2767627D02*
Y2759627D01*
G01X240649Y2767627D02*
X245249D01*
G01X248449Y2759627D02*
X250949Y2767627D01*
X253449Y2759627D01*
G01X252549Y2762427D02*
X249349D01*
G01X261149Y2766960D02*
X260549Y2767360D01*
X259849Y2767627D01*
X259049D01*
X258149Y2767227D01*
X257449Y2766560D01*
X256949Y2765760D01*
X256549Y2764427D01*
X256449Y2763227D01*
X256649Y2762027D01*
X256949Y2761227D01*
X257549Y2760427D01*
X258249Y2759894D01*
X258949Y2759627D01*
X259649D01*
X260349Y2759894D01*
X260949Y2760294D01*
X261449Y2760827D01*
G01X264749Y2759627D02*
Y2767627D01*
G01X268549D02*
X264749Y2762693D01*
G01X269149Y2759627D02*
X266449Y2764960D01*
G01X272749Y2767627D02*
Y2761894D01*
X273149Y2760693D01*
X273949Y2759894D01*
X274949Y2759627D01*
X275949Y2759894D01*
X276749Y2760693D01*
X277149Y2761894D01*
Y2767627D01*
G01X280949Y2759627D02*
Y2767627D01*
X283349D01*
X284149Y2767227D01*
X284749Y2766294D01*
X284949Y2765227D01*
X284749Y2764160D01*
X284249Y2763360D01*
X283349Y2762960D01*
X280949D01*
G01X296449Y2759627D02*
X298949Y2767627D01*
X301449Y2759627D01*
G01X300549Y2762427D02*
X297349D01*
G01X304649Y2759627D02*
Y2767627D01*
X309249Y2759627D01*
Y2767627D01*
G01X312749Y2759627D02*
Y2767627D01*
X314749D01*
X315549Y2767227D01*
X316149Y2766694D01*
X316649Y2765894D01*
X317049Y2764960D01*
X317149Y2763627D01*
X317049Y2762294D01*
X316649Y2761360D01*
X316149Y2760560D01*
X315549Y2760027D01*
X314749Y2759627D01*
X312749D01*
G01X329749Y2767627D02*
X332149D01*
G01X330949D02*
Y2759627D01*
G01X329749D02*
X332149D01*
G01X336349D02*
Y2767627D01*
X338949Y2760960D01*
X341549Y2767627D01*
Y2759627D01*
G01X344949D02*
Y2767627D01*
X347349D01*
X348149Y2767227D01*
X348749Y2766294D01*
X348949Y2765227D01*
X348749Y2764160D01*
X348249Y2763360D01*
X347349Y2762960D01*
X344949D01*
G01X356949Y2759627D02*
X352949D01*
Y2767627D01*
X356949D01*
G01X355349Y2763760D02*
X352949D01*
G01X360749Y2759627D02*
Y2767627D01*
X362749D01*
X363549Y2767227D01*
X364149Y2766694D01*
X364649Y2765894D01*
X365049Y2764960D01*
X365149Y2763627D01*
X365049Y2762294D01*
X364649Y2761360D01*
X364149Y2760560D01*
X363549Y2760027D01*
X362749Y2759627D01*
X360749D01*
G01X368449D02*
X370949Y2767627D01*
X373449Y2759627D01*
G01X372549Y2762427D02*
X369349D01*
G01X376649Y2759627D02*
Y2767627D01*
X381249Y2759627D01*
Y2767627D01*
G01X389149Y2766960D02*
X388549Y2767360D01*
X387849Y2767627D01*
X387049D01*
X386149Y2767227D01*
X385449Y2766560D01*
X384949Y2765760D01*
X384549Y2764427D01*
X384449Y2763227D01*
X384649Y2762027D01*
X384949Y2761227D01*
X385549Y2760427D01*
X386249Y2759894D01*
X386949Y2759627D01*
X387649D01*
X388349Y2759894D01*
X388949Y2760294D01*
X389449Y2760827D01*
G01X396949Y2759627D02*
X392949D01*
Y2767627D01*
X396949D01*
G01X395349Y2763760D02*
X392949D01*
G01X-64451Y2778627D02*
X-62451D01*
Y2776227D01*
X-63051Y2775427D01*
X-63751Y2774894D01*
X-64751Y2774627D01*
X-65751Y2774894D01*
X-66451Y2775427D01*
X-67051Y2776227D01*
X-67451Y2777160D01*
X-67651Y2778227D01*
Y2779160D01*
X-67451Y2779960D01*
X-67051Y2780894D01*
X-66451Y2781694D01*
X-65851Y2782227D01*
X-65051Y2782627D01*
X-64351D01*
X-63551Y2782360D01*
X-62951Y2781827D01*
G01X-57051Y2774360D02*
X-57251Y2774494D01*
Y2774760D01*
X-57051Y2774894D01*
X-56851Y2774760D01*
Y2774494D01*
X-57051Y2774360D01*
G01X-51351Y2774627D02*
Y2782627D01*
X-46751Y2774627D01*
Y2782627D01*
G01X-39051Y2774627D02*
X-43051D01*
Y2782627D01*
X-39051D01*
G01X-40651Y2778760D02*
X-43051D01*
G01X-31051Y2774627D02*
X-35051D01*
Y2782627D01*
X-31051D01*
G01X-32651Y2778760D02*
X-35051D01*
G01X-27251Y2774627D02*
Y2782627D01*
X-25251D01*
X-24451Y2782227D01*
X-23851Y2781694D01*
X-23351Y2780894D01*
X-22951Y2779960D01*
X-22851Y2778627D01*
X-22951Y2777294D01*
X-23351Y2776360D01*
X-23851Y2775560D01*
X-24451Y2775027D01*
X-25251Y2774627D01*
X-27251D01*
G01X-11251Y2782627D02*
Y2776894D01*
X-10851Y2775693D01*
X-10051Y2774894D01*
X-9051Y2774627D01*
X-8051Y2774894D01*
X-7251Y2775693D01*
X-6851Y2776894D01*
Y2782627D01*
G01X-3051D02*
Y2774627D01*
X949D01*
G01X12349D02*
Y2782627D01*
X14949Y2775960D01*
X17549Y2782627D01*
Y2774627D01*
G01X20449D02*
X22949Y2782627D01*
X25449Y2774627D01*
G01X24549Y2777427D02*
X21349D01*
G01X28949Y2774627D02*
Y2782627D01*
X31449D01*
X32249Y2782227D01*
X32749Y2781694D01*
X32949Y2780627D01*
X32749Y2779560D01*
X32149Y2778894D01*
X31449Y2778494D01*
X28949D01*
G01X31449D02*
X32949Y2774627D01*
G01X36749D02*
Y2782627D01*
G01X40549D02*
X36749Y2777693D01*
G01X41149Y2774627D02*
X38449Y2779960D01*
G01X52449Y2774627D02*
X54949Y2782627D01*
X57449Y2774627D01*
G01X56549Y2777427D02*
X53349D01*
G01X60649Y2774627D02*
Y2782627D01*
X65249Y2774627D01*
Y2782627D01*
G01X68749Y2774627D02*
Y2782627D01*
X70749D01*
X71549Y2782227D01*
X72149Y2781694D01*
X72649Y2780894D01*
X73049Y2779960D01*
X73149Y2778627D01*
X73049Y2777294D01*
X72649Y2776360D01*
X72149Y2775560D01*
X71549Y2775027D01*
X70749Y2774627D01*
X68749D01*
G01X84749D02*
Y2782627D01*
X86749D01*
X87549Y2782227D01*
X88149Y2781694D01*
X88649Y2780894D01*
X89049Y2779960D01*
X89149Y2778627D01*
X89049Y2777294D01*
X88649Y2776360D01*
X88149Y2775560D01*
X87549Y2775027D01*
X86749Y2774627D01*
X84749D01*
G01X92449D02*
X94949Y2782627D01*
X97449Y2774627D01*
G01X96549Y2777427D02*
X93349D01*
G01X102949Y2782627D02*
Y2774627D01*
G01X100649Y2782627D02*
X105249D01*
G01X112949Y2774627D02*
X108949D01*
Y2782627D01*
X112949D01*
G01X111349Y2778760D02*
X108949D01*
G01X129149Y2781960D02*
X128549Y2782360D01*
X127849Y2782627D01*
X127049D01*
X126149Y2782227D01*
X125449Y2781560D01*
X124949Y2780760D01*
X124549Y2779427D01*
X124449Y2778227D01*
X124649Y2777027D01*
X124949Y2776227D01*
X125549Y2775427D01*
X126249Y2774894D01*
X126949Y2774627D01*
X127649D01*
X128349Y2774894D01*
X128949Y2775294D01*
X129449Y2775827D01*
G01X134949Y2774627D02*
X134149Y2774760D01*
X133449Y2775294D01*
X132849Y2776094D01*
X132449Y2777027D01*
X132249Y2778094D01*
Y2779160D01*
X132449Y2780227D01*
X132849Y2781160D01*
X133449Y2781960D01*
X134149Y2782494D01*
X134949Y2782627D01*
X135749Y2782494D01*
X136449Y2781960D01*
X137049Y2781160D01*
X137449Y2780227D01*
X137649Y2779160D01*
Y2778094D01*
X137449Y2777027D01*
X137049Y2776094D01*
X136449Y2775294D01*
X135749Y2774760D01*
X134949Y2774627D01*
G01X140749D02*
Y2782627D01*
X142749D01*
X143549Y2782227D01*
X144149Y2781694D01*
X144649Y2780894D01*
X145049Y2779960D01*
X145149Y2778627D01*
X145049Y2777294D01*
X144649Y2776360D01*
X144149Y2775560D01*
X143549Y2775027D01*
X142749Y2774627D01*
X140749D01*
G01X152949D02*
X148949D01*
Y2782627D01*
X152949D01*
G01X151349Y2778760D02*
X148949D01*
G01X166449Y2771960D02*
X165449Y2773294D01*
X164949Y2774627D01*
Y2779960D01*
X165449Y2781294D01*
X166449Y2782627D01*
G01X172849Y2775693D02*
X173649Y2775027D01*
X174549Y2774627D01*
X175349D01*
X176149Y2775027D01*
X176749Y2775693D01*
X177049Y2776627D01*
X176849Y2777560D01*
X176349Y2778360D01*
X175449Y2778894D01*
X174249Y2779160D01*
X173549Y2779694D01*
X173249Y2780627D01*
X173449Y2781560D01*
X173949Y2782227D01*
X174649Y2782627D01*
X175349D01*
X176049Y2782360D01*
X176649Y2781694D01*
G01X181749Y2782627D02*
X184149D01*
G01X182949D02*
Y2774627D01*
G01X181749D02*
X184149D01*
G01X188949Y2782627D02*
Y2774627D01*
X192949D01*
G01X196749D02*
Y2782627D01*
G01X200549D02*
X196749Y2777693D01*
G01X201149Y2774627D02*
X198449Y2779960D01*
G01X204849Y2775693D02*
X205649Y2775027D01*
X206549Y2774627D01*
X207349D01*
X208149Y2775027D01*
X208749Y2775693D01*
X209049Y2776627D01*
X208849Y2777560D01*
X208349Y2778360D01*
X207449Y2778894D01*
X206249Y2779160D01*
X205549Y2779694D01*
X205249Y2780627D01*
X205449Y2781560D01*
X205949Y2782227D01*
X206649Y2782627D01*
X207349D01*
X208049Y2782360D01*
X208649Y2781694D01*
G01X217149Y2781960D02*
X216549Y2782360D01*
X215849Y2782627D01*
X215049D01*
X214149Y2782227D01*
X213449Y2781560D01*
X212949Y2780760D01*
X212549Y2779427D01*
X212449Y2778227D01*
X212649Y2777027D01*
X212949Y2776227D01*
X213549Y2775427D01*
X214249Y2774894D01*
X214949Y2774627D01*
X215649D01*
X216349Y2774894D01*
X216949Y2775294D01*
X217449Y2775827D01*
G01X220949Y2774627D02*
Y2782627D01*
X223449D01*
X224249Y2782227D01*
X224749Y2781694D01*
X224949Y2780627D01*
X224749Y2779560D01*
X224149Y2778894D01*
X223449Y2778494D01*
X220949D01*
G01X223449D02*
X224949Y2774627D01*
G01X232949D02*
X228949D01*
Y2782627D01*
X232949D01*
G01X231349Y2778760D02*
X228949D01*
G01X240949Y2774627D02*
X236949D01*
Y2782627D01*
X240949D01*
G01X239349Y2778760D02*
X236949D01*
G01X244649Y2774627D02*
Y2782627D01*
X249249Y2774627D01*
Y2782627D01*
G01X254749Y2773160D02*
X255149Y2774894D01*
G01X262949Y2782627D02*
Y2774627D01*
G01X260649Y2782627D02*
X265249D01*
G01X270949Y2774627D02*
X270149Y2774760D01*
X269449Y2775294D01*
X268849Y2776094D01*
X268449Y2777027D01*
X268249Y2778094D01*
Y2779160D01*
X268449Y2780227D01*
X268849Y2781160D01*
X269449Y2781960D01*
X270149Y2782494D01*
X270949Y2782627D01*
X271749Y2782494D01*
X272449Y2781960D01*
X273049Y2781160D01*
X273449Y2780227D01*
X273649Y2779160D01*
Y2778094D01*
X273449Y2777027D01*
X273049Y2776094D01*
X272449Y2775294D01*
X271749Y2774760D01*
X270949Y2774627D01*
G01X276949D02*
Y2782627D01*
X279349D01*
X280149Y2782227D01*
X280749Y2781294D01*
X280949Y2780227D01*
X280749Y2779160D01*
X280249Y2778360D01*
X279349Y2777960D01*
X276949D01*
G01X292849Y2775693D02*
X293649Y2775027D01*
X294549Y2774627D01*
X295349D01*
X296149Y2775027D01*
X296749Y2775693D01*
X297049Y2776627D01*
X296849Y2777560D01*
X296349Y2778360D01*
X295449Y2778894D01*
X294249Y2779160D01*
X293549Y2779694D01*
X293249Y2780627D01*
X293449Y2781560D01*
X293949Y2782227D01*
X294649Y2782627D01*
X295349D01*
X296049Y2782360D01*
X296649Y2781694D01*
G01X301749Y2782627D02*
X304149D01*
G01X302949D02*
Y2774627D01*
G01X301749D02*
X304149D01*
G01X308749D02*
Y2782627D01*
X310749D01*
X311549Y2782227D01*
X312149Y2781694D01*
X312649Y2780894D01*
X313049Y2779960D01*
X313149Y2778627D01*
X313049Y2777294D01*
X312649Y2776360D01*
X312149Y2775560D01*
X311549Y2775027D01*
X310749Y2774627D01*
X308749D01*
G01X320949D02*
X316949D01*
Y2782627D01*
X320949D01*
G01X319349Y2778760D02*
X316949D01*
G01X326749Y2773160D02*
X327149Y2774894D01*
G01X339949Y2782627D02*
X341349Y2774627D01*
X342949Y2782627D01*
X344549Y2774627D01*
X345949Y2782627D01*
G01X347949D02*
X349349Y2774627D01*
X350949Y2782627D01*
X352549Y2774627D01*
X353949Y2782627D01*
G01X358949Y2774627D02*
Y2778227D01*
X356949Y2782627D01*
G01X360949D02*
X358949Y2778227D01*
G01X366949Y2774627D02*
Y2778227D01*
X364949Y2782627D01*
G01X368949D02*
X366949Y2778227D01*
G01X375449Y2771960D02*
X376449Y2773294D01*
X376949Y2774627D01*
Y2779960D01*
X376449Y2781294D01*
X375449Y2782627D01*
G01X-63051Y2804627D02*
X-67051D01*
Y2812627D01*
X-63051D01*
G01X-64651Y2808760D02*
X-67051D01*
G01X-57051Y2804360D02*
X-57251Y2804494D01*
Y2804760D01*
X-57051Y2804894D01*
X-56851Y2804760D01*
Y2804494D01*
X-57051Y2804360D01*
G01X-51051Y2804627D02*
Y2812627D01*
X-48651D01*
X-47851Y2812227D01*
X-47251Y2811294D01*
X-47051Y2810227D01*
X-47251Y2809160D01*
X-47751Y2808360D01*
X-48651Y2807960D01*
X-51051D01*
G01X-43051Y2804627D02*
Y2812627D01*
X-40551D01*
X-39751Y2812227D01*
X-39251Y2811694D01*
X-39051Y2810627D01*
X-39251Y2809560D01*
X-39851Y2808894D01*
X-40551Y2808494D01*
X-43051D01*
G01X-40551D02*
X-39051Y2804627D01*
G01X-33051D02*
X-33851Y2804760D01*
X-34551Y2805294D01*
X-35151Y2806094D01*
X-35551Y2807027D01*
X-35751Y2808094D01*
Y2809160D01*
X-35551Y2810227D01*
X-35151Y2811160D01*
X-34551Y2811960D01*
X-33851Y2812494D01*
X-33051Y2812627D01*
X-32251Y2812494D01*
X-31551Y2811960D01*
X-30951Y2811160D01*
X-30551Y2810227D01*
X-30351Y2809160D01*
Y2808094D01*
X-30551Y2807027D01*
X-30951Y2806094D01*
X-31551Y2805294D01*
X-32251Y2804760D01*
X-33051Y2804627D01*
G01X-27551Y2812627D02*
X-25051Y2804627D01*
X-22551Y2812627D01*
G01X-18251D02*
X-15851D01*
G01X-17051D02*
Y2804627D01*
G01X-18251D02*
X-15851D01*
G01X-11251D02*
Y2812627D01*
X-9251D01*
X-8451Y2812227D01*
X-7851Y2811694D01*
X-7351Y2810894D01*
X-6951Y2809960D01*
X-6851Y2808627D01*
X-6951Y2807294D01*
X-7351Y2806360D01*
X-7851Y2805560D01*
X-8451Y2805027D01*
X-9251Y2804627D01*
X-11251D01*
G01X949D02*
X-3051D01*
Y2812627D01*
X949D01*
G01X-651Y2808760D02*
X-3051D01*
G01X12949Y2804627D02*
Y2812627D01*
X15349D01*
X16149Y2812227D01*
X16749Y2811294D01*
X16949Y2810227D01*
X16749Y2809160D01*
X16249Y2808360D01*
X15349Y2807960D01*
X12949D01*
G01X25149Y2811960D02*
X24549Y2812360D01*
X23849Y2812627D01*
X23049D01*
X22149Y2812227D01*
X21449Y2811560D01*
X20949Y2810760D01*
X20549Y2809427D01*
X20449Y2808227D01*
X20649Y2807027D01*
X20949Y2806227D01*
X21549Y2805427D01*
X22249Y2804894D01*
X22949Y2804627D01*
X23649D01*
X24349Y2804894D01*
X24949Y2805294D01*
X25449Y2805827D01*
G01X31749Y2808894D02*
X32149Y2809294D01*
X32449Y2809960D01*
X32649Y2810894D01*
X32449Y2811694D01*
X32049Y2812227D01*
X31349Y2812627D01*
X28649D01*
Y2804627D01*
X31949D01*
X32649Y2805160D01*
X33049Y2805960D01*
X33249Y2806894D01*
X33049Y2807827D01*
X32449Y2808627D01*
X31749Y2808894D01*
X28649D01*
G01X45049Y2804627D02*
Y2812627D01*
X48849D01*
G01X47449Y2808760D02*
X45049D01*
G01X53749Y2812627D02*
X56149D01*
G01X54949D02*
Y2804627D01*
G01X53749D02*
X56149D01*
G01X60949Y2812627D02*
Y2804627D01*
X64949D01*
G01X68349D02*
Y2812627D01*
X70949Y2805960D01*
X73549Y2812627D01*
Y2804627D01*
G01X-66951Y2789627D02*
Y2797627D01*
X-63151D01*
G01X-64551Y2793760D02*
X-66951D01*
G01X-57051Y2789360D02*
X-57251Y2789494D01*
Y2789760D01*
X-57051Y2789894D01*
X-56851Y2789760D01*
Y2789494D01*
X-57051Y2789360D01*
G01X-51351Y2789627D02*
Y2797627D01*
X-46751Y2789627D01*
Y2797627D01*
G01X-39051Y2789627D02*
X-43051D01*
Y2797627D01*
X-39051D01*
G01X-40651Y2793760D02*
X-43051D01*
G01X-31051Y2789627D02*
X-35051D01*
Y2797627D01*
X-31051D01*
G01X-32651Y2793760D02*
X-35051D01*
G01X-27251Y2789627D02*
Y2797627D01*
X-25251D01*
X-24451Y2797227D01*
X-23851Y2796694D01*
X-23351Y2795894D01*
X-22951Y2794960D01*
X-22851Y2793627D01*
X-22951Y2792294D01*
X-23351Y2791360D01*
X-23851Y2790560D01*
X-24451Y2790027D01*
X-25251Y2789627D01*
X-27251D01*
G01X-11051D02*
Y2797627D01*
X-8651D01*
X-7851Y2797227D01*
X-7251Y2796294D01*
X-7051Y2795227D01*
X-7251Y2794160D01*
X-7751Y2793360D01*
X-8651Y2792960D01*
X-11051D01*
G01X1149Y2796960D02*
X549Y2797360D01*
X-151Y2797627D01*
X-951D01*
X-1851Y2797227D01*
X-2551Y2796560D01*
X-3051Y2795760D01*
X-3451Y2794427D01*
X-3551Y2793227D01*
X-3351Y2792027D01*
X-3051Y2791227D01*
X-2451Y2790427D01*
X-1751Y2789894D01*
X-1051Y2789627D01*
X-351D01*
X349Y2789894D01*
X949Y2790294D01*
X1449Y2790827D01*
G01X7749Y2793894D02*
X8149Y2794294D01*
X8449Y2794960D01*
X8649Y2795894D01*
X8449Y2796694D01*
X8049Y2797227D01*
X7349Y2797627D01*
X4649D01*
Y2789627D01*
X7949D01*
X8649Y2790160D01*
X9049Y2790960D01*
X9249Y2791894D01*
X9049Y2792827D01*
X8449Y2793627D01*
X7749Y2793894D01*
X4649D01*
G01X20349Y2789627D02*
Y2797627D01*
X22949Y2790960D01*
X25549Y2797627D01*
Y2789627D01*
G01X28449D02*
X30949Y2797627D01*
X33449Y2789627D01*
G01X32549Y2792427D02*
X29349D01*
G01X36749Y2789627D02*
Y2797627D01*
G01X40549D02*
X36749Y2792693D01*
G01X41149Y2789627D02*
X38449Y2794960D01*
G01X48949Y2789627D02*
X44949D01*
Y2797627D01*
X48949D01*
G01X47349Y2793760D02*
X44949D01*
G01X52949Y2789627D02*
Y2797627D01*
X55449D01*
X56249Y2797227D01*
X56749Y2796694D01*
X56949Y2795627D01*
X56749Y2794560D01*
X56149Y2793894D01*
X55449Y2793494D01*
X52949D01*
G01X55449D02*
X56949Y2789627D01*
G01X60849Y2790693D02*
X61649Y2790027D01*
X62549Y2789627D01*
X63349D01*
X64149Y2790027D01*
X64749Y2790693D01*
X65049Y2791627D01*
X64849Y2792560D01*
X64349Y2793360D01*
X63449Y2793894D01*
X62249Y2794160D01*
X61549Y2794694D01*
X61249Y2795627D01*
X61449Y2796560D01*
X61949Y2797227D01*
X62649Y2797627D01*
X63349D01*
X64049Y2797360D01*
X64649Y2796694D01*
G01X78449Y2786960D02*
X77449Y2788294D01*
X76949Y2789627D01*
Y2794960D01*
X77449Y2796294D01*
X78449Y2797627D01*
G01X84849Y2790693D02*
X85649Y2790027D01*
X86549Y2789627D01*
X87349D01*
X88149Y2790027D01*
X88749Y2790693D01*
X89049Y2791627D01*
X88849Y2792560D01*
X88349Y2793360D01*
X87449Y2793894D01*
X86249Y2794160D01*
X85549Y2794694D01*
X85249Y2795627D01*
X85449Y2796560D01*
X85949Y2797227D01*
X86649Y2797627D01*
X87349D01*
X88049Y2797360D01*
X88649Y2796694D01*
G01X93749Y2797627D02*
X96149D01*
G01X94949D02*
Y2789627D01*
G01X93749D02*
X96149D01*
G01X100949Y2797627D02*
Y2789627D01*
X104949D01*
G01X108749D02*
Y2797627D01*
G01X112549D02*
X108749Y2792693D01*
G01X113149Y2789627D02*
X110449Y2794960D01*
G01X116849Y2790693D02*
X117649Y2790027D01*
X118549Y2789627D01*
X119349D01*
X120149Y2790027D01*
X120749Y2790693D01*
X121049Y2791627D01*
X120849Y2792560D01*
X120349Y2793360D01*
X119449Y2793894D01*
X118249Y2794160D01*
X117549Y2794694D01*
X117249Y2795627D01*
X117449Y2796560D01*
X117949Y2797227D01*
X118649Y2797627D01*
X119349D01*
X120049Y2797360D01*
X120649Y2796694D01*
G01X129149Y2796960D02*
X128549Y2797360D01*
X127849Y2797627D01*
X127049D01*
X126149Y2797227D01*
X125449Y2796560D01*
X124949Y2795760D01*
X124549Y2794427D01*
X124449Y2793227D01*
X124649Y2792027D01*
X124949Y2791227D01*
X125549Y2790427D01*
X126249Y2789894D01*
X126949Y2789627D01*
X127649D01*
X128349Y2789894D01*
X128949Y2790294D01*
X129449Y2790827D01*
G01X132949Y2789627D02*
Y2797627D01*
X135449D01*
X136249Y2797227D01*
X136749Y2796694D01*
X136949Y2795627D01*
X136749Y2794560D01*
X136149Y2793894D01*
X135449Y2793494D01*
X132949D01*
G01X135449D02*
X136949Y2789627D01*
G01X144949D02*
X140949D01*
Y2797627D01*
X144949D01*
G01X143349Y2793760D02*
X140949D01*
G01X152949Y2789627D02*
X148949D01*
Y2797627D01*
X152949D01*
G01X151349Y2793760D02*
X148949D01*
G01X156649Y2789627D02*
Y2797627D01*
X161249Y2789627D01*
Y2797627D01*
G01X166949Y2789360D02*
X166749Y2789494D01*
Y2789760D01*
X166949Y2789894D01*
X167149Y2789760D01*
Y2789494D01*
X166949Y2789360D01*
G01X174949Y2797627D02*
Y2789627D01*
G01X172649Y2797627D02*
X177249D01*
G01X182949Y2789627D02*
X182149Y2789760D01*
X181449Y2790294D01*
X180849Y2791094D01*
X180449Y2792027D01*
X180249Y2793094D01*
Y2794160D01*
X180449Y2795227D01*
X180849Y2796160D01*
X181449Y2796960D01*
X182149Y2797494D01*
X182949Y2797627D01*
X183749Y2797494D01*
X184449Y2796960D01*
X185049Y2796160D01*
X185449Y2795227D01*
X185649Y2794160D01*
Y2793094D01*
X185449Y2792027D01*
X185049Y2791094D01*
X184449Y2790294D01*
X183749Y2789760D01*
X182949Y2789627D01*
G01X188949D02*
Y2797627D01*
X191349D01*
X192149Y2797227D01*
X192749Y2796294D01*
X192949Y2795227D01*
X192749Y2794160D01*
X192249Y2793360D01*
X191349Y2792960D01*
X188949D01*
G01X204849Y2790693D02*
X205649Y2790027D01*
X206549Y2789627D01*
X207349D01*
X208149Y2790027D01*
X208749Y2790693D01*
X209049Y2791627D01*
X208849Y2792560D01*
X208349Y2793360D01*
X207449Y2793894D01*
X206249Y2794160D01*
X205549Y2794694D01*
X205249Y2795627D01*
X205449Y2796560D01*
X205949Y2797227D01*
X206649Y2797627D01*
X207349D01*
X208049Y2797360D01*
X208649Y2796694D01*
G01X213749Y2797627D02*
X216149D01*
G01X214949D02*
Y2789627D01*
G01X213749D02*
X216149D01*
G01X220749D02*
Y2797627D01*
X222749D01*
X223549Y2797227D01*
X224149Y2796694D01*
X224649Y2795894D01*
X225049Y2794960D01*
X225149Y2793627D01*
X225049Y2792294D01*
X224649Y2791360D01*
X224149Y2790560D01*
X223549Y2790027D01*
X222749Y2789627D01*
X220749D01*
G01X232949D02*
X228949D01*
Y2797627D01*
X232949D01*
G01X231349Y2793760D02*
X228949D01*
G01X239449Y2786960D02*
X240449Y2788294D01*
X240949Y2789627D01*
Y2794960D01*
X240449Y2796294D01*
X239449Y2797627D01*
G01X-62851Y2841960D02*
X-63451Y2842360D01*
X-64151Y2842627D01*
X-64951D01*
X-65851Y2842227D01*
X-66551Y2841560D01*
X-67051Y2840760D01*
X-67451Y2839427D01*
X-67551Y2838227D01*
X-67351Y2837027D01*
X-67051Y2836227D01*
X-66451Y2835427D01*
X-65751Y2834894D01*
X-65051Y2834627D01*
X-64351D01*
X-63651Y2834894D01*
X-63051Y2835294D01*
X-62551Y2835827D01*
G01X-57051Y2834360D02*
X-57251Y2834494D01*
Y2834760D01*
X-57051Y2834894D01*
X-56851Y2834760D01*
Y2834494D01*
X-57051Y2834360D01*
G01X-51351Y2834627D02*
Y2842627D01*
X-46751Y2834627D01*
Y2842627D01*
G01X-41051Y2834627D02*
X-41851Y2834760D01*
X-42551Y2835294D01*
X-43151Y2836094D01*
X-43551Y2837027D01*
X-43751Y2838094D01*
Y2839160D01*
X-43551Y2840227D01*
X-43151Y2841160D01*
X-42551Y2841960D01*
X-41851Y2842494D01*
X-41051Y2842627D01*
X-40251Y2842494D01*
X-39551Y2841960D01*
X-38951Y2841160D01*
X-38551Y2840227D01*
X-38351Y2839160D01*
Y2838094D01*
X-38551Y2837027D01*
X-38951Y2836094D01*
X-39551Y2835294D01*
X-40251Y2834760D01*
X-41051Y2834627D01*
G01X-27351D02*
Y2842627D01*
X-22751Y2834627D01*
Y2842627D01*
G01X-15051Y2834627D02*
X-19051D01*
Y2842627D01*
X-15051D01*
G01X-16651Y2838760D02*
X-19051D01*
G01X-7051Y2834627D02*
X-11051D01*
Y2842627D01*
X-7051D01*
G01X-8651Y2838760D02*
X-11051D01*
G01X-3251Y2834627D02*
Y2842627D01*
X-1251D01*
X-451Y2842227D01*
X149Y2841694D01*
X649Y2840894D01*
X1049Y2839960D01*
X1149Y2838627D01*
X1049Y2837294D01*
X649Y2836360D01*
X149Y2835560D01*
X-451Y2835027D01*
X-1251Y2834627D01*
X-3251D01*
G01X14949Y2842627D02*
Y2834627D01*
G01X12649Y2842627D02*
X17249D01*
G01X22949Y2834627D02*
X22149Y2834760D01*
X21449Y2835294D01*
X20849Y2836094D01*
X20449Y2837027D01*
X20249Y2838094D01*
Y2839160D01*
X20449Y2840227D01*
X20849Y2841160D01*
X21449Y2841960D01*
X22149Y2842494D01*
X22949Y2842627D01*
X23749Y2842494D01*
X24449Y2841960D01*
X25049Y2841160D01*
X25449Y2840227D01*
X25649Y2839160D01*
Y2838094D01*
X25449Y2837027D01*
X25049Y2836094D01*
X24449Y2835294D01*
X23749Y2834760D01*
X22949Y2834627D01*
G01X36949D02*
Y2842627D01*
X39349D01*
X40149Y2842227D01*
X40749Y2841294D01*
X40949Y2840227D01*
X40749Y2839160D01*
X40249Y2838360D01*
X39349Y2837960D01*
X36949D01*
G01X44949Y2842627D02*
Y2834627D01*
X48949D01*
G01X52749Y2842627D02*
Y2836894D01*
X53149Y2835693D01*
X53949Y2834894D01*
X54949Y2834627D01*
X55949Y2834894D01*
X56749Y2835693D01*
X57149Y2836894D01*
Y2842627D01*
G01X63549Y2838627D02*
X65549D01*
Y2836227D01*
X64949Y2835427D01*
X64249Y2834894D01*
X63249Y2834627D01*
X62249Y2834894D01*
X61549Y2835427D01*
X60949Y2836227D01*
X60549Y2837160D01*
X60349Y2838227D01*
Y2839160D01*
X60549Y2839960D01*
X60949Y2840894D01*
X61549Y2841694D01*
X62149Y2842227D01*
X62949Y2842627D01*
X63649D01*
X64449Y2842360D01*
X65049Y2841827D01*
G01X78949Y2834627D02*
X79649Y2834760D01*
X80449Y2835160D01*
X80949Y2835827D01*
X81149Y2836760D01*
X80949Y2837693D01*
X80349Y2838494D01*
X79449Y2838894D01*
X78449D01*
X77849Y2839160D01*
X77349Y2839827D01*
X77149Y2840760D01*
X77449Y2841694D01*
X78149Y2842360D01*
X78949Y2842627D01*
X79749Y2842360D01*
X80449Y2841694D01*
X80749Y2840760D01*
X80549Y2839827D01*
X80049Y2839160D01*
X79449Y2838894D01*
X78449D01*
X77549Y2838494D01*
X76949Y2837693D01*
X76749Y2836760D01*
X76949Y2835827D01*
X77449Y2835160D01*
X78249Y2834760D01*
X78949Y2834627D01*
G01X92849D02*
Y2842627D01*
G01X97049D02*
Y2834627D01*
G01Y2838627D02*
X92849D01*
G01X102949Y2834627D02*
X102149Y2834760D01*
X101449Y2835294D01*
X100849Y2836094D01*
X100449Y2837027D01*
X100249Y2838094D01*
Y2839160D01*
X100449Y2840227D01*
X100849Y2841160D01*
X101449Y2841960D01*
X102149Y2842494D01*
X102949Y2842627D01*
X103749Y2842494D01*
X104449Y2841960D01*
X105049Y2841160D01*
X105449Y2840227D01*
X105649Y2839160D01*
Y2838094D01*
X105449Y2837027D01*
X105049Y2836094D01*
X104449Y2835294D01*
X103749Y2834760D01*
X102949Y2834627D01*
G01X108949Y2842627D02*
Y2834627D01*
X112949D01*
G01X120949D02*
X116949D01*
Y2842627D01*
X120949D01*
G01X119349Y2838760D02*
X116949D01*
G01X124849Y2835693D02*
X125649Y2835027D01*
X126549Y2834627D01*
X127349D01*
X128149Y2835027D01*
X128749Y2835693D01*
X129049Y2836627D01*
X128849Y2837560D01*
X128349Y2838360D01*
X127449Y2838894D01*
X126249Y2839160D01*
X125549Y2839694D01*
X125249Y2840627D01*
X125449Y2841560D01*
X125949Y2842227D01*
X126649Y2842627D01*
X127349D01*
X128049Y2842360D01*
X128649Y2841694D01*
G01X140849Y2835693D02*
X141649Y2835027D01*
X142549Y2834627D01*
X143349D01*
X144149Y2835027D01*
X144749Y2835693D01*
X145049Y2836627D01*
X144849Y2837560D01*
X144349Y2838360D01*
X143449Y2838894D01*
X142249Y2839160D01*
X141549Y2839694D01*
X141249Y2840627D01*
X141449Y2841560D01*
X141949Y2842227D01*
X142649Y2842627D01*
X143349D01*
X144049Y2842360D01*
X144649Y2841694D01*
G01X148749Y2842627D02*
Y2836894D01*
X149149Y2835693D01*
X149949Y2834894D01*
X150949Y2834627D01*
X151949Y2834894D01*
X152749Y2835693D01*
X153149Y2836894D01*
Y2842627D01*
G01X156949Y2834627D02*
Y2842627D01*
X159449D01*
X160249Y2842227D01*
X160749Y2841694D01*
X160949Y2840627D01*
X160749Y2839560D01*
X160149Y2838894D01*
X159449Y2838494D01*
X156949D01*
G01X159449D02*
X160949Y2834627D01*
G01X164949D02*
Y2842627D01*
X167449D01*
X168249Y2842227D01*
X168749Y2841694D01*
X168949Y2840627D01*
X168749Y2839560D01*
X168149Y2838894D01*
X167449Y2838494D01*
X164949D01*
G01X167449D02*
X168949Y2834627D01*
G01X174949D02*
X174149Y2834760D01*
X173449Y2835294D01*
X172849Y2836094D01*
X172449Y2837027D01*
X172249Y2838094D01*
Y2839160D01*
X172449Y2840227D01*
X172849Y2841160D01*
X173449Y2841960D01*
X174149Y2842494D01*
X174949Y2842627D01*
X175749Y2842494D01*
X176449Y2841960D01*
X177049Y2841160D01*
X177449Y2840227D01*
X177649Y2839160D01*
Y2838094D01*
X177449Y2837027D01*
X177049Y2836094D01*
X176449Y2835294D01*
X175749Y2834760D01*
X174949Y2834627D01*
G01X180749Y2842627D02*
Y2836894D01*
X181149Y2835693D01*
X181949Y2834894D01*
X182949Y2834627D01*
X183949Y2834894D01*
X184749Y2835693D01*
X185149Y2836894D01*
Y2842627D01*
G01X188649Y2834627D02*
Y2842627D01*
X193249Y2834627D01*
Y2842627D01*
G01X196749Y2834627D02*
Y2842627D01*
X198749D01*
X199549Y2842227D01*
X200149Y2841694D01*
X200649Y2840894D01*
X201049Y2839960D01*
X201149Y2838627D01*
X201049Y2837294D01*
X200649Y2836360D01*
X200149Y2835560D01*
X199549Y2835027D01*
X198749Y2834627D01*
X196749D01*
G01X205749Y2842627D02*
X208149D01*
G01X206949D02*
Y2834627D01*
G01X205749D02*
X208149D01*
G01X212649D02*
Y2842627D01*
X217249Y2834627D01*
Y2842627D01*
G01X223549Y2838627D02*
X225549D01*
Y2836227D01*
X224949Y2835427D01*
X224249Y2834894D01*
X223249Y2834627D01*
X222249Y2834894D01*
X221549Y2835427D01*
X220949Y2836227D01*
X220549Y2837160D01*
X220349Y2838227D01*
Y2839160D01*
X220549Y2839960D01*
X220949Y2840894D01*
X221549Y2841694D01*
X222149Y2842227D01*
X222949Y2842627D01*
X223649D01*
X224449Y2842360D01*
X225049Y2841827D01*
G01X236849Y2835693D02*
X237649Y2835027D01*
X238549Y2834627D01*
X239349D01*
X240149Y2835027D01*
X240749Y2835693D01*
X241049Y2836627D01*
X240849Y2837560D01*
X240349Y2838360D01*
X239449Y2838894D01*
X238249Y2839160D01*
X237549Y2839694D01*
X237249Y2840627D01*
X237449Y2841560D01*
X237949Y2842227D01*
X238649Y2842627D01*
X239349D01*
X240049Y2842360D01*
X240649Y2841694D01*
G01X249149Y2841960D02*
X248549Y2842360D01*
X247849Y2842627D01*
X247049D01*
X246149Y2842227D01*
X245449Y2841560D01*
X244949Y2840760D01*
X244549Y2839427D01*
X244449Y2838227D01*
X244649Y2837027D01*
X244949Y2836227D01*
X245549Y2835427D01*
X246249Y2834894D01*
X246949Y2834627D01*
X247649D01*
X248349Y2834894D01*
X248949Y2835294D01*
X249449Y2835827D01*
G01X252949Y2834627D02*
Y2842627D01*
X255449D01*
X256249Y2842227D01*
X256749Y2841694D01*
X256949Y2840627D01*
X256749Y2839560D01*
X256149Y2838894D01*
X255449Y2838494D01*
X252949D01*
G01X255449D02*
X256949Y2834627D01*
G01X264949D02*
X260949D01*
Y2842627D01*
X264949D01*
G01X263349Y2838760D02*
X260949D01*
G01X267949Y2842627D02*
X269349Y2834627D01*
X270949Y2842627D01*
X272549Y2834627D01*
X273949Y2842627D01*
G01X278949Y2834360D02*
X278749Y2834494D01*
Y2834760D01*
X278949Y2834894D01*
X279149Y2834760D01*
Y2834494D01*
X278949Y2834360D01*
G01X286449Y2831960D02*
X285449Y2833294D01*
X284949Y2834627D01*
Y2839960D01*
X285449Y2841294D01*
X286449Y2842627D01*
G01X292949Y2834627D02*
Y2842627D01*
X295349D01*
X296149Y2842227D01*
X296749Y2841294D01*
X296949Y2840227D01*
X296749Y2839160D01*
X296249Y2838360D01*
X295349Y2837960D01*
X292949D01*
G01X300949Y2842627D02*
Y2834627D01*
X304949D01*
G01X312949D02*
X308949D01*
Y2842627D01*
X312949D01*
G01X311349Y2838760D02*
X308949D01*
G01X316449Y2834627D02*
X318949Y2842627D01*
X321449Y2834627D01*
G01X320549Y2837427D02*
X317349D01*
G01X324849Y2835693D02*
X325649Y2835027D01*
X326549Y2834627D01*
X327349D01*
X328149Y2835027D01*
X328749Y2835693D01*
X329049Y2836627D01*
X328849Y2837560D01*
X328349Y2838360D01*
X327449Y2838894D01*
X326249Y2839160D01*
X325549Y2839694D01*
X325249Y2840627D01*
X325449Y2841560D01*
X325949Y2842227D01*
X326649Y2842627D01*
X327349D01*
X328049Y2842360D01*
X328649Y2841694D01*
G01X336949Y2834627D02*
X332949D01*
Y2842627D01*
X336949D01*
G01X335349Y2838760D02*
X332949D01*
G01X349749Y2842627D02*
X352149D01*
G01X350949D02*
Y2834627D01*
G01X349749D02*
X352149D01*
G01X359549Y2838627D02*
X361549D01*
Y2836227D01*
X360949Y2835427D01*
X360249Y2834894D01*
X359249Y2834627D01*
X358249Y2834894D01*
X357549Y2835427D01*
X356949Y2836227D01*
X356549Y2837160D01*
X356349Y2838227D01*
Y2839160D01*
X356549Y2839960D01*
X356949Y2840894D01*
X357549Y2841694D01*
X358149Y2842227D01*
X358949Y2842627D01*
X359649D01*
X360449Y2842360D01*
X361049Y2841827D01*
G01X364649Y2834627D02*
Y2842627D01*
X369249Y2834627D01*
Y2842627D01*
G01X374949Y2834627D02*
X374149Y2834760D01*
X373449Y2835294D01*
X372849Y2836094D01*
X372449Y2837027D01*
X372249Y2838094D01*
Y2839160D01*
X372449Y2840227D01*
X372849Y2841160D01*
X373449Y2841960D01*
X374149Y2842494D01*
X374949Y2842627D01*
X375749Y2842494D01*
X376449Y2841960D01*
X377049Y2841160D01*
X377449Y2840227D01*
X377649Y2839160D01*
Y2838094D01*
X377449Y2837027D01*
X377049Y2836094D01*
X376449Y2835294D01*
X375749Y2834760D01*
X374949Y2834627D01*
G01X380949D02*
Y2842627D01*
X383449D01*
X384249Y2842227D01*
X384749Y2841694D01*
X384949Y2840627D01*
X384749Y2839560D01*
X384149Y2838894D01*
X383449Y2838494D01*
X380949D01*
G01X383449D02*
X384949Y2834627D01*
G01X392949D02*
X388949D01*
Y2842627D01*
X392949D01*
G01X391349Y2838760D02*
X388949D01*
G01X406949Y2842627D02*
Y2834627D01*
G01X404649Y2842627D02*
X409249D01*
G01X412849Y2834627D02*
Y2842627D01*
G01X417049D02*
Y2834627D01*
G01Y2838627D02*
X412849D01*
G01X421749Y2842627D02*
X424149D01*
G01X422949D02*
Y2834627D01*
G01X421749D02*
X424149D01*
G01X428849Y2835693D02*
X429649Y2835027D01*
X430549Y2834627D01*
X431349D01*
X432149Y2835027D01*
X432749Y2835693D01*
X433049Y2836627D01*
X432849Y2837560D01*
X432349Y2838360D01*
X431449Y2838894D01*
X430249Y2839160D01*
X429549Y2839694D01*
X429249Y2840627D01*
X429449Y2841560D01*
X429949Y2842227D01*
X430649Y2842627D01*
X431349D01*
X432049Y2842360D01*
X432649Y2841694D01*
G01X445749Y2842627D02*
X448149D01*
G01X446949D02*
Y2834627D01*
G01X445749D02*
X448149D01*
G01X453049D02*
Y2842627D01*
X456849D01*
G01X455449Y2838760D02*
X453049D01*
G01X468649Y2834627D02*
Y2842627D01*
X473249Y2834627D01*
Y2842627D01*
G01X478949Y2834627D02*
X478149Y2834760D01*
X477449Y2835294D01*
X476849Y2836094D01*
X476449Y2837027D01*
X476249Y2838094D01*
Y2839160D01*
X476449Y2840227D01*
X476849Y2841160D01*
X477449Y2841960D01*
X478149Y2842494D01*
X478949Y2842627D01*
X479749Y2842494D01*
X480449Y2841960D01*
X481049Y2841160D01*
X481449Y2840227D01*
X481649Y2839160D01*
Y2838094D01*
X481449Y2837027D01*
X481049Y2836094D01*
X480449Y2835294D01*
X479749Y2834760D01*
X478949Y2834627D01*
G01X494949Y2842627D02*
Y2834627D01*
G01X492649Y2842627D02*
X497249D01*
G01X500849Y2834627D02*
Y2842627D01*
G01X505049D02*
Y2834627D01*
G01Y2838627D02*
X500849D01*
G01X509749Y2842627D02*
X512149D01*
G01X510949D02*
Y2834627D01*
G01X509749D02*
X512149D01*
G01X516849Y2835693D02*
X517649Y2835027D01*
X518549Y2834627D01*
X519349D01*
X520149Y2835027D01*
X520749Y2835693D01*
X521049Y2836627D01*
X520849Y2837560D01*
X520349Y2838360D01*
X519449Y2838894D01*
X518249Y2839160D01*
X517549Y2839694D01*
X517249Y2840627D01*
X517449Y2841560D01*
X517949Y2842227D01*
X518649Y2842627D01*
X519349D01*
X520049Y2842360D01*
X520649Y2841694D01*
G01X533749Y2842627D02*
X536149D01*
G01X534949D02*
Y2834627D01*
G01X533749D02*
X536149D01*
G01X542949Y2842627D02*
Y2834627D01*
G01X540649Y2842627D02*
X545249D01*
G01X552949Y2834627D02*
X548949D01*
Y2842627D01*
X552949D01*
G01X551349Y2838760D02*
X548949D01*
G01X556349Y2834627D02*
Y2842627D01*
X558949Y2835960D01*
X561549Y2842627D01*
Y2834627D01*
G01X573749Y2842627D02*
X576149D01*
G01X574949D02*
Y2834627D01*
G01X573749D02*
X576149D01*
G01X580649D02*
Y2842627D01*
X585249Y2834627D01*
Y2842627D01*
G01X599749Y2838894D02*
X600149Y2839294D01*
X600449Y2839960D01*
X600649Y2840894D01*
X600449Y2841694D01*
X600049Y2842227D01*
X599349Y2842627D01*
X596649D01*
Y2834627D01*
X599949D01*
X600649Y2835160D01*
X601049Y2835960D01*
X601249Y2836894D01*
X601049Y2837827D01*
X600449Y2838627D01*
X599749Y2838894D01*
X596649D01*
G01X606949Y2834627D02*
X606149Y2834760D01*
X605449Y2835294D01*
X604849Y2836094D01*
X604449Y2837027D01*
X604249Y2838094D01*
Y2839160D01*
X604449Y2840227D01*
X604849Y2841160D01*
X605449Y2841960D01*
X606149Y2842494D01*
X606949Y2842627D01*
X607749Y2842494D01*
X608449Y2841960D01*
X609049Y2841160D01*
X609449Y2840227D01*
X609649Y2839160D01*
Y2838094D01*
X609449Y2837027D01*
X609049Y2836094D01*
X608449Y2835294D01*
X607749Y2834760D01*
X606949Y2834627D01*
G01X612449D02*
X614949Y2842627D01*
X617449Y2834627D01*
G01X616549Y2837427D02*
X613349D01*
G01X620949Y2834627D02*
Y2842627D01*
X623449D01*
X624249Y2842227D01*
X624749Y2841694D01*
X624949Y2840627D01*
X624749Y2839560D01*
X624149Y2838894D01*
X623449Y2838494D01*
X620949D01*
G01X623449D02*
X624949Y2834627D01*
G01X628749D02*
Y2842627D01*
X630749D01*
X631549Y2842227D01*
X632149Y2841694D01*
X632649Y2840894D01*
X633049Y2839960D01*
X633149Y2838627D01*
X633049Y2837294D01*
X632649Y2836360D01*
X632149Y2835560D01*
X631549Y2835027D01*
X630749Y2834627D01*
X628749D01*
G01X645049D02*
Y2842627D01*
X648849D01*
G01X647449Y2838760D02*
X645049D01*
G01X653749Y2842627D02*
X656149D01*
G01X654949D02*
Y2834627D01*
G01X653749D02*
X656149D01*
G01X660949Y2842627D02*
Y2834627D01*
X664949D01*
G01X672949D02*
X668949D01*
Y2842627D01*
X672949D01*
G01X671349Y2838760D02*
X668949D01*
G01X679449Y2831960D02*
X680449Y2833294D01*
X680949Y2834627D01*
Y2839960D01*
X680449Y2841294D01*
X679449Y2842627D01*
G01X-67251Y2819627D02*
Y2827627D01*
X-65251D01*
X-64451Y2827227D01*
X-63851Y2826694D01*
X-63351Y2825894D01*
X-62951Y2824960D01*
X-62851Y2823627D01*
X-62951Y2822294D01*
X-63351Y2821360D01*
X-63851Y2820560D01*
X-64451Y2820027D01*
X-65251Y2819627D01*
X-67251D01*
G01X-57051Y2819360D02*
X-57251Y2819494D01*
Y2819760D01*
X-57051Y2819894D01*
X-56851Y2819760D01*
Y2819494D01*
X-57051Y2819360D01*
G01X-51051Y2819627D02*
Y2827627D01*
X-48651D01*
X-47851Y2827227D01*
X-47251Y2826294D01*
X-47051Y2825227D01*
X-47251Y2824160D01*
X-47751Y2823360D01*
X-48651Y2822960D01*
X-51051D01*
G01X-43051Y2819627D02*
Y2827627D01*
X-40551D01*
X-39751Y2827227D01*
X-39251Y2826694D01*
X-39051Y2825627D01*
X-39251Y2824560D01*
X-39851Y2823894D01*
X-40551Y2823494D01*
X-43051D01*
G01X-40551D02*
X-39051Y2819627D01*
G01X-33051D02*
X-33851Y2819760D01*
X-34551Y2820294D01*
X-35151Y2821094D01*
X-35551Y2822027D01*
X-35751Y2823094D01*
Y2824160D01*
X-35551Y2825227D01*
X-35151Y2826160D01*
X-34551Y2826960D01*
X-33851Y2827494D01*
X-33051Y2827627D01*
X-32251Y2827494D01*
X-31551Y2826960D01*
X-30951Y2826160D01*
X-30551Y2825227D01*
X-30351Y2824160D01*
Y2823094D01*
X-30551Y2822027D01*
X-30951Y2821094D01*
X-31551Y2820294D01*
X-32251Y2819760D01*
X-33051Y2819627D01*
G01X-27551Y2827627D02*
X-25051Y2819627D01*
X-22551Y2827627D01*
G01X-18251D02*
X-15851D01*
G01X-17051D02*
Y2819627D01*
G01X-18251D02*
X-15851D01*
G01X-11251D02*
Y2827627D01*
X-9251D01*
X-8451Y2827227D01*
X-7851Y2826694D01*
X-7351Y2825894D01*
X-6951Y2824960D01*
X-6851Y2823627D01*
X-6951Y2822294D01*
X-7351Y2821360D01*
X-7851Y2820560D01*
X-8451Y2820027D01*
X-9251Y2819627D01*
X-11251D01*
G01X949D02*
X-3051D01*
Y2827627D01*
X949D01*
G01X-651Y2823760D02*
X-3051D01*
G01X13749Y2827627D02*
X16149D01*
G01X14949D02*
Y2819627D01*
G01X13749D02*
X16149D01*
G01X20349D02*
Y2827627D01*
X22949Y2820960D01*
X25549Y2827627D01*
Y2819627D01*
G01X28949D02*
Y2827627D01*
X31349D01*
X32149Y2827227D01*
X32749Y2826294D01*
X32949Y2825227D01*
X32749Y2824160D01*
X32249Y2823360D01*
X31349Y2822960D01*
X28949D01*
G01X40949Y2819627D02*
X36949D01*
Y2827627D01*
X40949D01*
G01X39349Y2823760D02*
X36949D01*
G01X44749Y2819627D02*
Y2827627D01*
X46749D01*
X47549Y2827227D01*
X48149Y2826694D01*
X48649Y2825894D01*
X49049Y2824960D01*
X49149Y2823627D01*
X49049Y2822294D01*
X48649Y2821360D01*
X48149Y2820560D01*
X47549Y2820027D01*
X46749Y2819627D01*
X44749D01*
G01X52449D02*
X54949Y2827627D01*
X57449Y2819627D01*
G01X56549Y2822427D02*
X53349D01*
G01X60649Y2819627D02*
Y2827627D01*
X65249Y2819627D01*
Y2827627D01*
G01X73149Y2826960D02*
X72549Y2827360D01*
X71849Y2827627D01*
X71049D01*
X70149Y2827227D01*
X69449Y2826560D01*
X68949Y2825760D01*
X68549Y2824427D01*
X68449Y2823227D01*
X68649Y2822027D01*
X68949Y2821227D01*
X69549Y2820427D01*
X70249Y2819894D01*
X70949Y2819627D01*
X71649D01*
X72349Y2819894D01*
X72949Y2820294D01*
X73449Y2820827D01*
G01X80949Y2819627D02*
X76949D01*
Y2827627D01*
X80949D01*
G01X79349Y2823760D02*
X76949D01*
G01X97149Y2826960D02*
X96549Y2827360D01*
X95849Y2827627D01*
X95049D01*
X94149Y2827227D01*
X93449Y2826560D01*
X92949Y2825760D01*
X92549Y2824427D01*
X92449Y2823227D01*
X92649Y2822027D01*
X92949Y2821227D01*
X93549Y2820427D01*
X94249Y2819894D01*
X94949Y2819627D01*
X95649D01*
X96349Y2819894D01*
X96949Y2820294D01*
X97449Y2820827D01*
G01X102949Y2819627D02*
X102149Y2819760D01*
X101449Y2820294D01*
X100849Y2821094D01*
X100449Y2822027D01*
X100249Y2823094D01*
Y2824160D01*
X100449Y2825227D01*
X100849Y2826160D01*
X101449Y2826960D01*
X102149Y2827494D01*
X102949Y2827627D01*
X103749Y2827494D01*
X104449Y2826960D01*
X105049Y2826160D01*
X105449Y2825227D01*
X105649Y2824160D01*
Y2823094D01*
X105449Y2822027D01*
X105049Y2821094D01*
X104449Y2820294D01*
X103749Y2819760D01*
X102949Y2819627D01*
G01X108749Y2827627D02*
Y2821894D01*
X109149Y2820693D01*
X109949Y2819894D01*
X110949Y2819627D01*
X111949Y2819894D01*
X112749Y2820693D01*
X113149Y2821894D01*
Y2827627D01*
G01X116949Y2819627D02*
Y2827627D01*
X119349D01*
X120149Y2827227D01*
X120749Y2826294D01*
X120949Y2825227D01*
X120749Y2824160D01*
X120249Y2823360D01*
X119349Y2822960D01*
X116949D01*
G01X126949Y2819627D02*
X126149Y2819760D01*
X125449Y2820294D01*
X124849Y2821094D01*
X124449Y2822027D01*
X124249Y2823094D01*
Y2824160D01*
X124449Y2825227D01*
X124849Y2826160D01*
X125449Y2826960D01*
X126149Y2827494D01*
X126949Y2827627D01*
X127749Y2827494D01*
X128449Y2826960D01*
X129049Y2826160D01*
X129449Y2825227D01*
X129649Y2824160D01*
Y2823094D01*
X129449Y2822027D01*
X129049Y2821094D01*
X128449Y2820294D01*
X127749Y2819760D01*
X126949Y2819627D01*
G01X132649D02*
Y2827627D01*
X137249Y2819627D01*
Y2827627D01*
G01X148449Y2819627D02*
X150949Y2827627D01*
X153449Y2819627D01*
G01X152549Y2822427D02*
X149349D01*
G01X156649Y2819627D02*
Y2827627D01*
X161249Y2819627D01*
Y2827627D01*
G01X164749Y2819627D02*
Y2827627D01*
X166749D01*
X167549Y2827227D01*
X168149Y2826694D01*
X168649Y2825894D01*
X169049Y2824960D01*
X169149Y2823627D01*
X169049Y2822294D01*
X168649Y2821360D01*
X168149Y2820560D01*
X167549Y2820027D01*
X166749Y2819627D01*
X164749D01*
G01X180349D02*
Y2827627D01*
X182949Y2820960D01*
X185549Y2827627D01*
Y2819627D01*
G01X192949D02*
X188949D01*
Y2827627D01*
X192949D01*
G01X191349Y2823760D02*
X188949D01*
G01X196449Y2819627D02*
X198949Y2827627D01*
X201449Y2819627D01*
G01X200549Y2822427D02*
X197349D01*
G01X204849Y2820693D02*
X205649Y2820027D01*
X206549Y2819627D01*
X207349D01*
X208149Y2820027D01*
X208749Y2820693D01*
X209049Y2821627D01*
X208849Y2822560D01*
X208349Y2823360D01*
X207449Y2823894D01*
X206249Y2824160D01*
X205549Y2824694D01*
X205249Y2825627D01*
X205449Y2826560D01*
X205949Y2827227D01*
X206649Y2827627D01*
X207349D01*
X208049Y2827360D01*
X208649Y2826694D01*
G01X212749Y2827627D02*
Y2821894D01*
X213149Y2820693D01*
X213949Y2819894D01*
X214949Y2819627D01*
X215949Y2819894D01*
X216749Y2820693D01*
X217149Y2821894D01*
Y2827627D01*
G01X220949Y2819627D02*
Y2827627D01*
X223449D01*
X224249Y2827227D01*
X224749Y2826694D01*
X224949Y2825627D01*
X224749Y2824560D01*
X224149Y2823894D01*
X223449Y2823494D01*
X220949D01*
G01X223449D02*
X224949Y2819627D01*
G01X232949D02*
X228949D01*
Y2827627D01*
X232949D01*
G01X231349Y2823760D02*
X228949D01*
G01X236349Y2819627D02*
Y2827627D01*
X238949Y2820960D01*
X241549Y2827627D01*
Y2819627D01*
G01X248949D02*
X244949D01*
Y2827627D01*
X248949D01*
G01X247349Y2823760D02*
X244949D01*
G01X252649Y2819627D02*
Y2827627D01*
X257249Y2819627D01*
Y2827627D01*
G01X262949D02*
Y2819627D01*
G01X260649Y2827627D02*
X265249D01*
G01X276949Y2819627D02*
Y2827627D01*
X279449D01*
X280249Y2827227D01*
X280749Y2826694D01*
X280949Y2825627D01*
X280749Y2824560D01*
X280149Y2823894D01*
X279449Y2823494D01*
X276949D01*
G01X279449D02*
X280949Y2819627D01*
G01X288949D02*
X284949D01*
Y2827627D01*
X288949D01*
G01X287349Y2823760D02*
X284949D01*
G01X292949Y2819627D02*
Y2827627D01*
X295349D01*
X296149Y2827227D01*
X296749Y2826294D01*
X296949Y2825227D01*
X296749Y2824160D01*
X296249Y2823360D01*
X295349Y2822960D01*
X292949D01*
G01X302949Y2819627D02*
X302149Y2819760D01*
X301449Y2820294D01*
X300849Y2821094D01*
X300449Y2822027D01*
X300249Y2823094D01*
Y2824160D01*
X300449Y2825227D01*
X300849Y2826160D01*
X301449Y2826960D01*
X302149Y2827494D01*
X302949Y2827627D01*
X303749Y2827494D01*
X304449Y2826960D01*
X305049Y2826160D01*
X305449Y2825227D01*
X305649Y2824160D01*
Y2823094D01*
X305449Y2822027D01*
X305049Y2821094D01*
X304449Y2820294D01*
X303749Y2819760D01*
X302949Y2819627D01*
G01X308949D02*
Y2827627D01*
X311449D01*
X312249Y2827227D01*
X312749Y2826694D01*
X312949Y2825627D01*
X312749Y2824560D01*
X312149Y2823894D01*
X311449Y2823494D01*
X308949D01*
G01X311449D02*
X312949Y2819627D01*
G01X318949Y2827627D02*
Y2819627D01*
G01X316649Y2827627D02*
X321249D01*
G01X-64251Y2853894D02*
X-63851Y2854294D01*
X-63551Y2854960D01*
X-63351Y2855894D01*
X-63551Y2856694D01*
X-63951Y2857227D01*
X-64651Y2857627D01*
X-67351D01*
Y2849627D01*
X-64051D01*
X-63351Y2850160D01*
X-62951Y2850960D01*
X-62751Y2851894D01*
X-62951Y2852827D01*
X-63551Y2853627D01*
X-64251Y2853894D01*
X-67351D01*
G01X-57051Y2849360D02*
X-57251Y2849494D01*
Y2849760D01*
X-57051Y2849894D01*
X-56851Y2849760D01*
Y2849494D01*
X-57051Y2849360D01*
G01X-51551Y2849627D02*
X-49051Y2857627D01*
X-46551Y2849627D01*
G01X-47451Y2852427D02*
X-50651D01*
G01X-43051Y2857627D02*
Y2849627D01*
X-39051D01*
G01X-35051Y2857627D02*
Y2849627D01*
X-31051D01*
G01X-19551Y2857627D02*
X-17051Y2849627D01*
X-14551Y2857627D01*
G01X-10251D02*
X-7851D01*
G01X-9051D02*
Y2849627D01*
G01X-10251D02*
X-7851D01*
G01X-3551D02*
X-1051Y2857627D01*
X1449Y2849627D01*
G01X549Y2852427D02*
X-2651D01*
G01X4849Y2850693D02*
X5649Y2850027D01*
X6549Y2849627D01*
X7349D01*
X8149Y2850027D01*
X8749Y2850693D01*
X9049Y2851627D01*
X8849Y2852560D01*
X8349Y2853360D01*
X7449Y2853894D01*
X6249Y2854160D01*
X5549Y2854694D01*
X5249Y2855627D01*
X5449Y2856560D01*
X5949Y2857227D01*
X6649Y2857627D01*
X7349D01*
X8049Y2857360D01*
X8649Y2856694D01*
G01X20949Y2849627D02*
Y2857627D01*
X23349D01*
X24149Y2857227D01*
X24749Y2856294D01*
X24949Y2855227D01*
X24749Y2854160D01*
X24249Y2853360D01*
X23349Y2852960D01*
X20949D01*
G01X28949Y2857627D02*
Y2849627D01*
X32949D01*
G01X36749Y2857627D02*
Y2851894D01*
X37149Y2850693D01*
X37949Y2849894D01*
X38949Y2849627D01*
X39949Y2849894D01*
X40749Y2850693D01*
X41149Y2851894D01*
Y2857627D01*
G01X47549Y2853627D02*
X49549D01*
Y2851227D01*
X48949Y2850427D01*
X48249Y2849894D01*
X47249Y2849627D01*
X46249Y2849894D01*
X45549Y2850427D01*
X44949Y2851227D01*
X44549Y2852160D01*
X44349Y2853227D01*
Y2854160D01*
X44549Y2854960D01*
X44949Y2855894D01*
X45549Y2856694D01*
X46149Y2857227D01*
X46949Y2857627D01*
X47649D01*
X48449Y2857360D01*
X49049Y2856827D01*
G01X55549Y2853627D02*
X57549D01*
Y2851227D01*
X56949Y2850427D01*
X56249Y2849894D01*
X55249Y2849627D01*
X54249Y2849894D01*
X53549Y2850427D01*
X52949Y2851227D01*
X52549Y2852160D01*
X52349Y2853227D01*
Y2854160D01*
X52549Y2854960D01*
X52949Y2855894D01*
X53549Y2856694D01*
X54149Y2857227D01*
X54949Y2857627D01*
X55649D01*
X56449Y2857360D01*
X57049Y2856827D01*
G01X64949Y2849627D02*
X60949D01*
Y2857627D01*
X64949D01*
G01X63349Y2853760D02*
X60949D01*
G01X68749Y2849627D02*
Y2857627D01*
X70749D01*
X71549Y2857227D01*
X72149Y2856694D01*
X72649Y2855894D01*
X73049Y2854960D01*
X73149Y2853627D01*
X73049Y2852294D01*
X72649Y2851360D01*
X72149Y2850560D01*
X71549Y2850027D01*
X70749Y2849627D01*
X68749D01*
G01X88949D02*
X84949D01*
Y2857627D01*
X88949D01*
G01X87349Y2853760D02*
X84949D01*
G01X92849Y2849627D02*
X97049Y2857627D01*
G01X92849D02*
X97049Y2849627D01*
G01X105149Y2856960D02*
X104549Y2857360D01*
X103849Y2857627D01*
X103049D01*
X102149Y2857227D01*
X101449Y2856560D01*
X100949Y2855760D01*
X100549Y2854427D01*
X100449Y2853227D01*
X100649Y2852027D01*
X100949Y2851227D01*
X101549Y2850427D01*
X102249Y2849894D01*
X102949Y2849627D01*
X103649D01*
X104349Y2849894D01*
X104949Y2850294D01*
X105449Y2850827D01*
G01X112949Y2849627D02*
X108949D01*
Y2857627D01*
X112949D01*
G01X111349Y2853760D02*
X108949D01*
G01X116949Y2849627D02*
Y2857627D01*
X119349D01*
X120149Y2857227D01*
X120749Y2856294D01*
X120949Y2855227D01*
X120749Y2854160D01*
X120249Y2853360D01*
X119349Y2852960D01*
X116949D01*
G01X126949Y2857627D02*
Y2849627D01*
G01X124649Y2857627D02*
X129249D01*
G01X141049Y2849627D02*
Y2857627D01*
X144849D01*
G01X143449Y2853760D02*
X141049D01*
G01X150949Y2849627D02*
X150149Y2849760D01*
X149449Y2850294D01*
X148849Y2851094D01*
X148449Y2852027D01*
X148249Y2853094D01*
Y2854160D01*
X148449Y2855227D01*
X148849Y2856160D01*
X149449Y2856960D01*
X150149Y2857494D01*
X150949Y2857627D01*
X151749Y2857494D01*
X152449Y2856960D01*
X153049Y2856160D01*
X153449Y2855227D01*
X153649Y2854160D01*
Y2853094D01*
X153449Y2852027D01*
X153049Y2851094D01*
X152449Y2850294D01*
X151749Y2849760D01*
X150949Y2849627D01*
G01X156949D02*
Y2857627D01*
X159449D01*
X160249Y2857227D01*
X160749Y2856694D01*
X160949Y2855627D01*
X160749Y2854560D01*
X160149Y2853894D01*
X159449Y2853494D01*
X156949D01*
G01X159449D02*
X160949Y2849627D01*
G01X-67551Y2864627D02*
X-65051Y2872627D01*
X-62551Y2864627D01*
G01X-63451Y2867427D02*
X-66651D01*
G01X-57051Y2864360D02*
X-57251Y2864494D01*
Y2864760D01*
X-57051Y2864894D01*
X-56851Y2864760D01*
Y2864494D01*
X-57051Y2864360D01*
G01X-51551Y2872627D02*
X-49051Y2864627D01*
X-46551Y2872627D01*
G01X-42251D02*
X-39851D01*
G01X-41051D02*
Y2864627D01*
G01X-42251D02*
X-39851D01*
G01X-35551D02*
X-33051Y2872627D01*
X-30551Y2864627D01*
G01X-31451Y2867427D02*
X-34651D01*
G01X-17051Y2872627D02*
Y2864627D01*
G01X-19351Y2872627D02*
X-14751D01*
G01X-7051Y2864627D02*
X-11051D01*
Y2872627D01*
X-7051D01*
G01X-8651Y2868760D02*
X-11051D01*
G01X-3551Y2864627D02*
X-1051Y2872627D01*
X1449Y2864627D01*
G01X549Y2867427D02*
X-2651D01*
G01X4949Y2864627D02*
Y2872627D01*
X7449D01*
X8249Y2872227D01*
X8749Y2871694D01*
X8949Y2870627D01*
X8749Y2869560D01*
X8149Y2868894D01*
X7449Y2868494D01*
X4949D01*
G01X7449D02*
X8949Y2864627D01*
G01X20749D02*
Y2872627D01*
X22749D01*
X23549Y2872227D01*
X24149Y2871694D01*
X24649Y2870894D01*
X25049Y2869960D01*
X25149Y2868627D01*
X25049Y2867294D01*
X24649Y2866360D01*
X24149Y2865560D01*
X23549Y2865027D01*
X22749Y2864627D01*
X20749D01*
G01X28949D02*
Y2872627D01*
X31449D01*
X32249Y2872227D01*
X32749Y2871694D01*
X32949Y2870627D01*
X32749Y2869560D01*
X32149Y2868894D01*
X31449Y2868494D01*
X28949D01*
G01X31449D02*
X32949Y2864627D01*
G01X38949D02*
X38149Y2864760D01*
X37449Y2865294D01*
X36849Y2866094D01*
X36449Y2867027D01*
X36249Y2868094D01*
Y2869160D01*
X36449Y2870227D01*
X36849Y2871160D01*
X37449Y2871960D01*
X38149Y2872494D01*
X38949Y2872627D01*
X39749Y2872494D01*
X40449Y2871960D01*
X41049Y2871160D01*
X41449Y2870227D01*
X41649Y2869160D01*
Y2868094D01*
X41449Y2867027D01*
X41049Y2866094D01*
X40449Y2865294D01*
X39749Y2864760D01*
X38949Y2864627D01*
G01X44949D02*
Y2872627D01*
X47349D01*
X48149Y2872227D01*
X48749Y2871294D01*
X48949Y2870227D01*
X48749Y2869160D01*
X48249Y2868360D01*
X47349Y2867960D01*
X44949D01*
G01X62449Y2861960D02*
X61449Y2863294D01*
X60949Y2864627D01*
Y2869960D01*
X61449Y2871294D01*
X62449Y2872627D01*
G01X69049Y2864627D02*
Y2872627D01*
X72849D01*
G01X71449Y2868760D02*
X69049D01*
G01X78949Y2864627D02*
X78149Y2864760D01*
X77449Y2865294D01*
X76849Y2866094D01*
X76449Y2867027D01*
X76249Y2868094D01*
Y2869160D01*
X76449Y2870227D01*
X76849Y2871160D01*
X77449Y2871960D01*
X78149Y2872494D01*
X78949Y2872627D01*
X79749Y2872494D01*
X80449Y2871960D01*
X81049Y2871160D01*
X81449Y2870227D01*
X81649Y2869160D01*
Y2868094D01*
X81449Y2867027D01*
X81049Y2866094D01*
X80449Y2865294D01*
X79749Y2864760D01*
X78949Y2864627D01*
G01X84949D02*
Y2872627D01*
X87449D01*
X88249Y2872227D01*
X88749Y2871694D01*
X88949Y2870627D01*
X88749Y2869560D01*
X88149Y2868894D01*
X87449Y2868494D01*
X84949D01*
G01X87449D02*
X88949Y2864627D01*
G01X100449D02*
X102949Y2872627D01*
X105449Y2864627D01*
G01X104549Y2867427D02*
X101349D01*
G01X108949Y2872627D02*
Y2864627D01*
X112949D01*
G01X116949Y2872627D02*
Y2864627D01*
X120949D01*
G01X132449Y2872627D02*
X134949Y2864627D01*
X137449Y2872627D01*
G01X141749D02*
X144149D01*
G01X142949D02*
Y2864627D01*
G01X141749D02*
X144149D01*
G01X148449D02*
X150949Y2872627D01*
X153449Y2864627D01*
G01X152549Y2867427D02*
X149349D01*
G01X156849Y2865693D02*
X157649Y2865027D01*
X158549Y2864627D01*
X159349D01*
X160149Y2865027D01*
X160749Y2865693D01*
X161049Y2866627D01*
X160849Y2867560D01*
X160349Y2868360D01*
X159449Y2868894D01*
X158249Y2869160D01*
X157549Y2869694D01*
X157249Y2870627D01*
X157449Y2871560D01*
X157949Y2872227D01*
X158649Y2872627D01*
X159349D01*
X160049Y2872360D01*
X160649Y2871694D01*
G01X172449Y2864627D02*
X174949Y2872627D01*
X177449Y2864627D01*
G01X176549Y2867427D02*
X173349D01*
G01X180649Y2864627D02*
Y2872627D01*
X185249Y2864627D01*
Y2872627D01*
G01X188749Y2864627D02*
Y2872627D01*
X190749D01*
X191549Y2872227D01*
X192149Y2871694D01*
X192649Y2870894D01*
X193049Y2869960D01*
X193149Y2868627D01*
X193049Y2867294D01*
X192649Y2866360D01*
X192149Y2865560D01*
X191549Y2865027D01*
X190749Y2864627D01*
X188749D01*
G01X204949D02*
Y2872627D01*
X207349D01*
X208149Y2872227D01*
X208749Y2871294D01*
X208949Y2870227D01*
X208749Y2869160D01*
X208249Y2868360D01*
X207349Y2867960D01*
X204949D01*
G01X213749Y2872627D02*
X216149D01*
G01X214949D02*
Y2864627D01*
G01X213749D02*
X216149D01*
G01X220649D02*
Y2872627D01*
X225249Y2864627D01*
Y2872627D01*
G01X228849Y2865693D02*
X229649Y2865027D01*
X230549Y2864627D01*
X231349D01*
X232149Y2865027D01*
X232749Y2865693D01*
X233049Y2866627D01*
X232849Y2867560D01*
X232349Y2868360D01*
X231449Y2868894D01*
X230249Y2869160D01*
X229549Y2869694D01*
X229249Y2870627D01*
X229449Y2871560D01*
X229949Y2872227D01*
X230649Y2872627D01*
X231349D01*
X232049Y2872360D01*
X232649Y2871694D01*
G01X239449Y2861960D02*
X240449Y2863294D01*
X240949Y2864627D01*
Y2869960D01*
X240449Y2871294D01*
X239449Y2872627D01*
G01X246949Y2864360D02*
X246749Y2864494D01*
Y2864760D01*
X246949Y2864894D01*
X247149Y2864760D01*
Y2864494D01*
X246949Y2864360D01*
G01X-85251Y2881227D02*
X-84651Y2880294D01*
X-83851Y2879760D01*
X-82951Y2879627D01*
X-82151Y2879760D01*
X-81351Y2880427D01*
X-80851Y2881227D01*
X-80751Y2882027D01*
X-80951Y2882960D01*
X-81651Y2883627D01*
X-82351Y2883894D01*
X-83251D01*
G01X-82351D02*
X-81751Y2884294D01*
X-81251Y2884960D01*
X-81051Y2885760D01*
X-81251Y2886560D01*
X-81751Y2887227D01*
X-82651Y2887627D01*
X-83551Y2887494D01*
X-84451Y2886960D01*
G01X-75051Y2879360D02*
X-75251Y2879494D01*
Y2879760D01*
X-75051Y2879894D01*
X-74851Y2879760D01*
Y2879494D01*
X-75051Y2879360D01*
G01X-69051Y2879627D02*
Y2887627D01*
X-66651D01*
X-65851Y2887227D01*
X-65251Y2886294D01*
X-65051Y2885227D01*
X-65251Y2884160D01*
X-65751Y2883360D01*
X-66651Y2882960D01*
X-69051D01*
G01X-56851Y2886960D02*
X-57451Y2887360D01*
X-58151Y2887627D01*
X-58951D01*
X-59851Y2887227D01*
X-60551Y2886560D01*
X-61051Y2885760D01*
X-61451Y2884427D01*
X-61551Y2883227D01*
X-61351Y2882027D01*
X-61051Y2881227D01*
X-60451Y2880427D01*
X-59751Y2879894D01*
X-59051Y2879627D01*
X-58351D01*
X-57651Y2879894D01*
X-57051Y2880294D01*
X-56551Y2880827D01*
G01X-50251Y2883894D02*
X-49851Y2884294D01*
X-49551Y2884960D01*
X-49351Y2885894D01*
X-49551Y2886694D01*
X-49951Y2887227D01*
X-50651Y2887627D01*
X-53351D01*
Y2879627D01*
X-50051D01*
X-49351Y2880160D01*
X-48951Y2880960D01*
X-48751Y2881894D01*
X-48951Y2882827D01*
X-49551Y2883627D01*
X-50251Y2883894D01*
X-53351D01*
G01X-37051Y2879627D02*
Y2887627D01*
X-34651D01*
X-33851Y2887227D01*
X-33251Y2886294D01*
X-33051Y2885227D01*
X-33251Y2884160D01*
X-33751Y2883360D01*
X-34651Y2882960D01*
X-37051D01*
G01X-29051Y2879627D02*
Y2887627D01*
X-26551D01*
X-25751Y2887227D01*
X-25251Y2886694D01*
X-25051Y2885627D01*
X-25251Y2884560D01*
X-25851Y2883894D01*
X-26551Y2883494D01*
X-29051D01*
G01X-26551D02*
X-25051Y2879627D01*
G01X-19051D02*
X-19851Y2879760D01*
X-20551Y2880294D01*
X-21151Y2881094D01*
X-21551Y2882027D01*
X-21751Y2883094D01*
Y2884160D01*
X-21551Y2885227D01*
X-21151Y2886160D01*
X-20551Y2886960D01*
X-19851Y2887494D01*
X-19051Y2887627D01*
X-18251Y2887494D01*
X-17551Y2886960D01*
X-16951Y2886160D01*
X-16551Y2885227D01*
X-16351Y2884160D01*
Y2883094D01*
X-16551Y2882027D01*
X-16951Y2881094D01*
X-17551Y2880294D01*
X-18251Y2879760D01*
X-19051Y2879627D01*
G01X-8851Y2886960D02*
X-9451Y2887360D01*
X-10151Y2887627D01*
X-10951D01*
X-11851Y2887227D01*
X-12551Y2886560D01*
X-13051Y2885760D01*
X-13451Y2884427D01*
X-13551Y2883227D01*
X-13351Y2882027D01*
X-13051Y2881227D01*
X-12451Y2880427D01*
X-11751Y2879894D01*
X-11051Y2879627D01*
X-10351D01*
X-9651Y2879894D01*
X-9051Y2880294D01*
X-8551Y2880827D01*
G01X-1051Y2879627D02*
X-5051D01*
Y2887627D01*
X-1051D01*
G01X-2651Y2883760D02*
X-5051D01*
G01X2849Y2880693D02*
X3649Y2880027D01*
X4549Y2879627D01*
X5349D01*
X6149Y2880027D01*
X6749Y2880693D01*
X7049Y2881627D01*
X6849Y2882560D01*
X6349Y2883360D01*
X5449Y2883894D01*
X4249Y2884160D01*
X3549Y2884694D01*
X3249Y2885627D01*
X3449Y2886560D01*
X3949Y2887227D01*
X4649Y2887627D01*
X5349D01*
X6049Y2887360D01*
X6649Y2886694D01*
G01X10849Y2880693D02*
X11649Y2880027D01*
X12549Y2879627D01*
X13349D01*
X14149Y2880027D01*
X14749Y2880693D01*
X15049Y2881627D01*
X14849Y2882560D01*
X14349Y2883360D01*
X13449Y2883894D01*
X12249Y2884160D01*
X11549Y2884694D01*
X11249Y2885627D01*
X11449Y2886560D01*
X11949Y2887227D01*
X12649Y2887627D01*
X13349D01*
X14049Y2887360D01*
X14649Y2886694D01*
G01X20949Y2879360D02*
X20749Y2879494D01*
Y2879760D01*
X20949Y2879894D01*
X21149Y2879760D01*
Y2879494D01*
X20949Y2879360D01*
G01Y2882960D02*
X20749Y2883094D01*
Y2883360D01*
X20949Y2883494D01*
X21149Y2883360D01*
Y2883094D01*
X20949Y2882960D01*
G01X-84951Y2901294D02*
X-84351Y2902094D01*
X-83651Y2902494D01*
X-82851Y2902627D01*
X-81851Y2902360D01*
X-81151Y2901694D01*
X-80951Y2900894D01*
X-81051Y2900093D01*
X-81451Y2899427D01*
X-83451Y2898094D01*
X-84351Y2897160D01*
X-84951Y2895827D01*
X-85151Y2894627D01*
X-80951D01*
G01X-75051Y2894360D02*
X-75251Y2894494D01*
Y2894760D01*
X-75051Y2894894D01*
X-74851Y2894760D01*
Y2894494D01*
X-75051Y2894360D01*
G01X-68951Y2894627D02*
Y2902627D01*
X-65151D01*
G01X-66551Y2898760D02*
X-68951D01*
G01X-61551Y2894627D02*
X-59051Y2902627D01*
X-56551Y2894627D01*
G01X-57451Y2897427D02*
X-60651D01*
G01X-50251Y2898894D02*
X-49851Y2899294D01*
X-49551Y2899960D01*
X-49351Y2900894D01*
X-49551Y2901694D01*
X-49951Y2902227D01*
X-50651Y2902627D01*
X-53351D01*
Y2894627D01*
X-50051D01*
X-49351Y2895160D01*
X-48951Y2895960D01*
X-48751Y2896894D01*
X-48951Y2897827D01*
X-49551Y2898627D01*
X-50251Y2898894D01*
X-53351D01*
G01X-45051Y2894627D02*
Y2902627D01*
X-42551D01*
X-41751Y2902227D01*
X-41251Y2901694D01*
X-41051Y2900627D01*
X-41251Y2899560D01*
X-41851Y2898894D01*
X-42551Y2898494D01*
X-45051D01*
G01X-42551D02*
X-41051Y2894627D01*
G01X-36251Y2902627D02*
X-33851D01*
G01X-35051D02*
Y2894627D01*
G01X-36251D02*
X-33851D01*
G01X-24851Y2901960D02*
X-25451Y2902360D01*
X-26151Y2902627D01*
X-26951D01*
X-27851Y2902227D01*
X-28551Y2901560D01*
X-29051Y2900760D01*
X-29451Y2899427D01*
X-29551Y2898227D01*
X-29351Y2897027D01*
X-29051Y2896227D01*
X-28451Y2895427D01*
X-27751Y2894894D01*
X-27051Y2894627D01*
X-26351D01*
X-25651Y2894894D01*
X-25051Y2895294D01*
X-24551Y2895827D01*
G01X-21551Y2894627D02*
X-19051Y2902627D01*
X-16551Y2894627D01*
G01X-17451Y2897427D02*
X-20651D01*
G01X-11051Y2902627D02*
Y2894627D01*
G01X-13351Y2902627D02*
X-8751D01*
G01X-1051Y2894627D02*
X-5051D01*
Y2902627D01*
X-1051D01*
G01X-2651Y2898760D02*
X-5051D01*
G01X10949Y2894627D02*
Y2902627D01*
X13349D01*
X14149Y2902227D01*
X14749Y2901294D01*
X14949Y2900227D01*
X14749Y2899160D01*
X14249Y2898360D01*
X13349Y2897960D01*
X10949D01*
G01X22949Y2894627D02*
X18949D01*
Y2902627D01*
X22949D01*
G01X21349Y2898760D02*
X18949D01*
G01X26949Y2894627D02*
Y2902627D01*
X29449D01*
X30249Y2902227D01*
X30749Y2901694D01*
X30949Y2900627D01*
X30749Y2899560D01*
X30149Y2898894D01*
X29449Y2898494D01*
X26949D01*
G01X29449D02*
X30949Y2894627D01*
G01X44949D02*
X44149Y2894760D01*
X43449Y2895294D01*
X42849Y2896094D01*
X42449Y2897027D01*
X42249Y2898094D01*
Y2899160D01*
X42449Y2900227D01*
X42849Y2901160D01*
X43449Y2901960D01*
X44149Y2902494D01*
X44949Y2902627D01*
X45749Y2902494D01*
X46449Y2901960D01*
X47049Y2901160D01*
X47449Y2900227D01*
X47649Y2899160D01*
Y2898094D01*
X47449Y2897027D01*
X47049Y2896094D01*
X46449Y2895294D01*
X45749Y2894760D01*
X44949Y2894627D01*
G01X45749Y2896760D02*
X46949Y2894627D01*
G01X50749Y2902627D02*
Y2896894D01*
X51149Y2895693D01*
X51949Y2894894D01*
X52949Y2894627D01*
X53949Y2894894D01*
X54749Y2895693D01*
X55149Y2896894D01*
Y2902627D01*
G01X58449Y2894627D02*
X60949Y2902627D01*
X63449Y2894627D01*
G01X62549Y2897427D02*
X59349D01*
G01X66649Y2894627D02*
Y2902627D01*
X71249Y2894627D01*
Y2902627D01*
G01X76949D02*
Y2894627D01*
G01X74649Y2902627D02*
X79249D01*
G01X82449Y2894627D02*
X84949Y2902627D01*
X87449Y2894627D01*
G01X86549Y2897427D02*
X83349D01*
G01X98949Y2894627D02*
Y2902627D01*
X101349D01*
X102149Y2902227D01*
X102749Y2901294D01*
X102949Y2900227D01*
X102749Y2899160D01*
X102249Y2898360D01*
X101349Y2897960D01*
X98949D01*
G01X111149Y2901960D02*
X110549Y2902360D01*
X109849Y2902627D01*
X109049D01*
X108149Y2902227D01*
X107449Y2901560D01*
X106949Y2900760D01*
X106549Y2899427D01*
X106449Y2898227D01*
X106649Y2897027D01*
X106949Y2896227D01*
X107549Y2895427D01*
X108249Y2894894D01*
X108949Y2894627D01*
X109649D01*
X110349Y2894894D01*
X110949Y2895294D01*
X111449Y2895827D01*
G01X117749Y2898894D02*
X118149Y2899294D01*
X118449Y2899960D01*
X118649Y2900894D01*
X118449Y2901694D01*
X118049Y2902227D01*
X117349Y2902627D01*
X114649D01*
Y2894627D01*
X117949D01*
X118649Y2895160D01*
X119049Y2895960D01*
X119249Y2896894D01*
X119049Y2897827D01*
X118449Y2898627D01*
X117749Y2898894D01*
X114649D01*
G01X130849Y2895693D02*
X131649Y2895027D01*
X132549Y2894627D01*
X133349D01*
X134149Y2895027D01*
X134749Y2895693D01*
X135049Y2896627D01*
X134849Y2897560D01*
X134349Y2898360D01*
X133449Y2898894D01*
X132249Y2899160D01*
X131549Y2899694D01*
X131249Y2900627D01*
X131449Y2901560D01*
X131949Y2902227D01*
X132649Y2902627D01*
X133349D01*
X134049Y2902360D01*
X134649Y2901694D01*
G01X138949Y2894627D02*
Y2902627D01*
X141349D01*
X142149Y2902227D01*
X142749Y2901294D01*
X142949Y2900227D01*
X142749Y2899160D01*
X142249Y2898360D01*
X141349Y2897960D01*
X138949D01*
G01X150949Y2894627D02*
X146949D01*
Y2902627D01*
X150949D01*
G01X149349Y2898760D02*
X146949D01*
G01X159149Y2901960D02*
X158549Y2902360D01*
X157849Y2902627D01*
X157049D01*
X156149Y2902227D01*
X155449Y2901560D01*
X154949Y2900760D01*
X154549Y2899427D01*
X154449Y2898227D01*
X154649Y2897027D01*
X154949Y2896227D01*
X155549Y2895427D01*
X156249Y2894894D01*
X156949Y2894627D01*
X157649D01*
X158349Y2894894D01*
X158949Y2895294D01*
X159449Y2895827D01*
G01X163749Y2902627D02*
X166149D01*
G01X164949D02*
Y2894627D01*
G01X163749D02*
X166149D01*
G01X171049D02*
Y2902627D01*
X174849D01*
G01X173449Y2898760D02*
X171049D01*
G01X179749Y2902627D02*
X182149D01*
G01X180949D02*
Y2894627D01*
G01X179749D02*
X182149D01*
G01X191149Y2901960D02*
X190549Y2902360D01*
X189849Y2902627D01*
X189049D01*
X188149Y2902227D01*
X187449Y2901560D01*
X186949Y2900760D01*
X186549Y2899427D01*
X186449Y2898227D01*
X186649Y2897027D01*
X186949Y2896227D01*
X187549Y2895427D01*
X188249Y2894894D01*
X188949Y2894627D01*
X189649D01*
X190349Y2894894D01*
X190949Y2895294D01*
X191449Y2895827D01*
G01X194449Y2894627D02*
X196949Y2902627D01*
X199449Y2894627D01*
G01X198549Y2897427D02*
X195349D01*
G01X204949Y2902627D02*
Y2894627D01*
G01X202649Y2902627D02*
X207249D01*
G01X211749D02*
X214149D01*
G01X212949D02*
Y2894627D01*
G01X211749D02*
X214149D01*
G01X220949D02*
X220149Y2894760D01*
X219449Y2895294D01*
X218849Y2896094D01*
X218449Y2897027D01*
X218249Y2898094D01*
Y2899160D01*
X218449Y2900227D01*
X218849Y2901160D01*
X219449Y2901960D01*
X220149Y2902494D01*
X220949Y2902627D01*
X221749Y2902494D01*
X222449Y2901960D01*
X223049Y2901160D01*
X223449Y2900227D01*
X223649Y2899160D01*
Y2898094D01*
X223449Y2897027D01*
X223049Y2896094D01*
X222449Y2895294D01*
X221749Y2894760D01*
X220949Y2894627D01*
G01X226649D02*
Y2902627D01*
X231249Y2894627D01*
Y2902627D01*
G01X236949Y2894360D02*
X236749Y2894494D01*
Y2894760D01*
X236949Y2894894D01*
X237149Y2894760D01*
Y2894494D01*
X236949Y2894360D01*
G01X-85351Y2924627D02*
Y2932627D01*
X-80751Y2924627D01*
Y2932627D01*
G01X-75051Y2924627D02*
X-75851Y2924760D01*
X-76551Y2925294D01*
X-77151Y2926094D01*
X-77551Y2927027D01*
X-77751Y2928094D01*
Y2929160D01*
X-77551Y2930227D01*
X-77151Y2931160D01*
X-76551Y2931960D01*
X-75851Y2932494D01*
X-75051Y2932627D01*
X-74251Y2932494D01*
X-73551Y2931960D01*
X-72951Y2931160D01*
X-72551Y2930227D01*
X-72351Y2929160D01*
Y2928094D01*
X-72551Y2927027D01*
X-72951Y2926094D01*
X-73551Y2925294D01*
X-74251Y2924760D01*
X-75051Y2924627D01*
G01X-67051Y2932627D02*
Y2924627D01*
G01X-69351Y2932627D02*
X-64751D01*
G01X-57051Y2924627D02*
X-61051D01*
Y2932627D01*
X-57051D01*
G01X-58651Y2928760D02*
X-61051D01*
G01X-53151Y2925693D02*
X-52351Y2925027D01*
X-51451Y2924627D01*
X-50651D01*
X-49851Y2925027D01*
X-49251Y2925693D01*
X-48951Y2926627D01*
X-49151Y2927560D01*
X-49651Y2928360D01*
X-50551Y2928894D01*
X-51751Y2929160D01*
X-52451Y2929694D01*
X-52751Y2930627D01*
X-52551Y2931560D01*
X-52051Y2932227D01*
X-51351Y2932627D01*
X-50651D01*
X-49951Y2932360D01*
X-49351Y2931694D01*
G01X-43051Y2924360D02*
X-43251Y2924494D01*
Y2924760D01*
X-43051Y2924894D01*
X-42851Y2924760D01*
Y2924494D01*
X-43051Y2924360D01*
G01Y2927960D02*
X-43251Y2928094D01*
Y2928360D01*
X-43051Y2928494D01*
X-42851Y2928360D01*
Y2928094D01*
X-43051Y2927960D01*
G01X-35551Y2921960D02*
X-36551Y2923294D01*
X-37051Y2924627D01*
Y2929960D01*
X-36551Y2931294D01*
X-35551Y2932627D01*
G01X-29251D02*
Y2926894D01*
X-28851Y2925693D01*
X-28051Y2924894D01*
X-27051Y2924627D01*
X-26051Y2924894D01*
X-25251Y2925693D01*
X-24851Y2926894D01*
Y2932627D01*
G01X-21351Y2924627D02*
Y2932627D01*
X-16751Y2924627D01*
Y2932627D01*
G01X-13051D02*
Y2924627D01*
X-9051D01*
G01X-1051D02*
X-5051D01*
Y2932627D01*
X-1051D01*
G01X-2651Y2928760D02*
X-5051D01*
G01X2849Y2925693D02*
X3649Y2925027D01*
X4549Y2924627D01*
X5349D01*
X6149Y2925027D01*
X6749Y2925693D01*
X7049Y2926627D01*
X6849Y2927560D01*
X6349Y2928360D01*
X5449Y2928894D01*
X4249Y2929160D01*
X3549Y2929694D01*
X3249Y2930627D01*
X3449Y2931560D01*
X3949Y2932227D01*
X4649Y2932627D01*
X5349D01*
X6049Y2932360D01*
X6649Y2931694D01*
G01X10849Y2925693D02*
X11649Y2925027D01*
X12549Y2924627D01*
X13349D01*
X14149Y2925027D01*
X14749Y2925693D01*
X15049Y2926627D01*
X14849Y2927560D01*
X14349Y2928360D01*
X13449Y2928894D01*
X12249Y2929160D01*
X11549Y2929694D01*
X11249Y2930627D01*
X11449Y2931560D01*
X11949Y2932227D01*
X12649Y2932627D01*
X13349D01*
X14049Y2932360D01*
X14649Y2931694D01*
G01X28949Y2924627D02*
X28149Y2924760D01*
X27449Y2925294D01*
X26849Y2926094D01*
X26449Y2927027D01*
X26249Y2928094D01*
Y2929160D01*
X26449Y2930227D01*
X26849Y2931160D01*
X27449Y2931960D01*
X28149Y2932494D01*
X28949Y2932627D01*
X29749Y2932494D01*
X30449Y2931960D01*
X31049Y2931160D01*
X31449Y2930227D01*
X31649Y2929160D01*
Y2928094D01*
X31449Y2927027D01*
X31049Y2926094D01*
X30449Y2925294D01*
X29749Y2924760D01*
X28949Y2924627D01*
G01X36949Y2932627D02*
Y2924627D01*
G01X34649Y2932627D02*
X39249D01*
G01X42849Y2924627D02*
Y2932627D01*
G01X47049D02*
Y2924627D01*
G01Y2928627D02*
X42849D01*
G01X54949Y2924627D02*
X50949D01*
Y2932627D01*
X54949D01*
G01X53349Y2928760D02*
X50949D01*
G01X58949Y2924627D02*
Y2932627D01*
X61449D01*
X62249Y2932227D01*
X62749Y2931694D01*
X62949Y2930627D01*
X62749Y2929560D01*
X62149Y2928894D01*
X61449Y2928494D01*
X58949D01*
G01X61449D02*
X62949Y2924627D01*
G01X65949Y2932627D02*
X67349Y2924627D01*
X68949Y2932627D01*
X70549Y2924627D01*
X71949Y2932627D01*
G01X75749D02*
X78149D01*
G01X76949D02*
Y2924627D01*
G01X75749D02*
X78149D01*
G01X82849Y2925693D02*
X83649Y2925027D01*
X84549Y2924627D01*
X85349D01*
X86149Y2925027D01*
X86749Y2925693D01*
X87049Y2926627D01*
X86849Y2927560D01*
X86349Y2928360D01*
X85449Y2928894D01*
X84249Y2929160D01*
X83549Y2929694D01*
X83249Y2930627D01*
X83449Y2931560D01*
X83949Y2932227D01*
X84649Y2932627D01*
X85349D01*
X86049Y2932360D01*
X86649Y2931694D01*
G01X94949Y2924627D02*
X90949D01*
Y2932627D01*
X94949D01*
G01X93349Y2928760D02*
X90949D01*
G01X106849Y2925693D02*
X107649Y2925027D01*
X108549Y2924627D01*
X109349D01*
X110149Y2925027D01*
X110749Y2925693D01*
X111049Y2926627D01*
X110849Y2927560D01*
X110349Y2928360D01*
X109449Y2928894D01*
X108249Y2929160D01*
X107549Y2929694D01*
X107249Y2930627D01*
X107449Y2931560D01*
X107949Y2932227D01*
X108649Y2932627D01*
X109349D01*
X110049Y2932360D01*
X110649Y2931694D01*
G01X114949Y2924627D02*
Y2932627D01*
X117349D01*
X118149Y2932227D01*
X118749Y2931294D01*
X118949Y2930227D01*
X118749Y2929160D01*
X118249Y2928360D01*
X117349Y2927960D01*
X114949D01*
G01X126949Y2924627D02*
X122949D01*
Y2932627D01*
X126949D01*
G01X125349Y2928760D02*
X122949D01*
G01X135149Y2931960D02*
X134549Y2932360D01*
X133849Y2932627D01*
X133049D01*
X132149Y2932227D01*
X131449Y2931560D01*
X130949Y2930760D01*
X130549Y2929427D01*
X130449Y2928227D01*
X130649Y2927027D01*
X130949Y2926227D01*
X131549Y2925427D01*
X132249Y2924894D01*
X132949Y2924627D01*
X133649D01*
X134349Y2924894D01*
X134949Y2925294D01*
X135449Y2925827D01*
G01X139749Y2932627D02*
X142149D01*
G01X140949D02*
Y2924627D01*
G01X139749D02*
X142149D01*
G01X147049D02*
Y2932627D01*
X150849D01*
G01X149449Y2928760D02*
X147049D01*
G01X155749Y2932627D02*
X158149D01*
G01X156949D02*
Y2924627D01*
G01X155749D02*
X158149D01*
G01X166949D02*
X162949D01*
Y2932627D01*
X166949D01*
G01X165349Y2928760D02*
X162949D01*
G01X170749Y2924627D02*
Y2932627D01*
X172749D01*
X173549Y2932227D01*
X174149Y2931694D01*
X174649Y2930894D01*
X175049Y2929960D01*
X175149Y2928627D01*
X175049Y2927294D01*
X174649Y2926360D01*
X174149Y2925560D01*
X173549Y2925027D01*
X172749Y2924627D01*
X170749D01*
G01X187749Y2932627D02*
X190149D01*
G01X188949D02*
Y2924627D01*
G01X187749D02*
X190149D01*
G01X194649D02*
Y2932627D01*
X199249Y2924627D01*
Y2932627D01*
G01X212949D02*
Y2924627D01*
G01X210649Y2932627D02*
X215249D01*
G01X219049Y2927960D02*
X219749Y2928894D01*
X220349Y2929427D01*
X221149Y2929694D01*
X221849Y2929427D01*
X222349Y2928894D01*
X222749Y2928094D01*
X222849Y2927160D01*
X222749Y2926360D01*
X222349Y2925560D01*
X221749Y2924894D01*
X221049Y2924627D01*
X220249Y2924894D01*
X219549Y2925693D01*
X219149Y2926894D01*
X219049Y2928227D01*
X219249Y2929960D01*
X219549Y2930894D01*
X220049Y2931827D01*
X220749Y2932494D01*
X221449Y2932627D01*
X222149Y2932360D01*
X222649Y2931694D01*
G01X226349Y2924627D02*
Y2932627D01*
X228949Y2925960D01*
X231549Y2932627D01*
Y2924627D01*
G01X237549Y2928627D02*
X239549D01*
Y2926227D01*
X238949Y2925427D01*
X238249Y2924894D01*
X237249Y2924627D01*
X236249Y2924894D01*
X235549Y2925427D01*
X234949Y2926227D01*
X234549Y2927160D01*
X234349Y2928227D01*
Y2929160D01*
X234549Y2929960D01*
X234949Y2930894D01*
X235549Y2931694D01*
X236149Y2932227D01*
X236949Y2932627D01*
X237649D01*
X238449Y2932360D01*
X239049Y2931827D01*
G01X241949Y2921960D02*
X247949D01*
G01X250949Y2924627D02*
Y2932627D01*
X253349D01*
X254149Y2932227D01*
X254749Y2931294D01*
X254949Y2930227D01*
X254749Y2929160D01*
X254249Y2928360D01*
X253349Y2927960D01*
X250949D01*
G01X258749Y2924627D02*
Y2932627D01*
X260749D01*
X261549Y2932227D01*
X262149Y2931694D01*
X262649Y2930894D01*
X263049Y2929960D01*
X263149Y2928627D01*
X263049Y2927294D01*
X262649Y2926360D01*
X262149Y2925560D01*
X261549Y2925027D01*
X260749Y2924627D01*
X258749D01*
G01X269749Y2928894D02*
X270149Y2929294D01*
X270449Y2929960D01*
X270649Y2930894D01*
X270449Y2931694D01*
X270049Y2932227D01*
X269349Y2932627D01*
X266649D01*
Y2924627D01*
X269949D01*
X270649Y2925160D01*
X271049Y2925960D01*
X271249Y2926894D01*
X271049Y2927827D01*
X270449Y2928627D01*
X269749Y2928894D01*
X266649D01*
G01X273949Y2921960D02*
X279949D01*
G01X282449Y2924627D02*
X284949Y2932627D01*
X287449Y2924627D01*
G01X286549Y2927427D02*
X283349D01*
G01X292949Y2924360D02*
X292749Y2924494D01*
Y2924760D01*
X292949Y2924894D01*
X293149Y2924760D01*
Y2924494D01*
X292949Y2924360D01*
G01X298749Y2924627D02*
Y2932627D01*
X300749D01*
X301549Y2932227D01*
X302149Y2931694D01*
X302649Y2930894D01*
X303049Y2929960D01*
X303149Y2928627D01*
X303049Y2927294D01*
X302649Y2926360D01*
X302149Y2925560D01*
X301549Y2925027D01*
X300749Y2924627D01*
X298749D01*
G01X308949D02*
X308149Y2924760D01*
X307449Y2925294D01*
X306849Y2926094D01*
X306449Y2927027D01*
X306249Y2928094D01*
Y2929160D01*
X306449Y2930227D01*
X306849Y2931160D01*
X307449Y2931960D01*
X308149Y2932494D01*
X308949Y2932627D01*
X309749Y2932494D01*
X310449Y2931960D01*
X311049Y2931160D01*
X311449Y2930227D01*
X311649Y2929160D01*
Y2928094D01*
X311449Y2927027D01*
X311049Y2926094D01*
X310449Y2925294D01*
X309749Y2924760D01*
X308949Y2924627D01*
G01X319149Y2931960D02*
X318549Y2932360D01*
X317849Y2932627D01*
X317049D01*
X316149Y2932227D01*
X315449Y2931560D01*
X314949Y2930760D01*
X314549Y2929427D01*
X314449Y2928227D01*
X314649Y2927027D01*
X314949Y2926227D01*
X315549Y2925427D01*
X316249Y2924894D01*
X316949Y2924627D01*
X317649D01*
X318349Y2924894D01*
X318949Y2925294D01*
X319449Y2925827D01*
G01X325449Y2921960D02*
X326449Y2923294D01*
X326949Y2924627D01*
Y2929960D01*
X326449Y2931294D01*
X325449Y2932627D01*
G01X-83051Y2909627D02*
Y2917627D01*
X-84251Y2916027D01*
G01Y2909627D02*
X-81851D01*
G01X-75051Y2909360D02*
X-75251Y2909494D01*
Y2909760D01*
X-75051Y2909894D01*
X-74851Y2909760D01*
Y2909494D01*
X-75051Y2909360D01*
G01X-69051Y2909627D02*
Y2917627D01*
X-66651D01*
X-65851Y2917227D01*
X-65251Y2916294D01*
X-65051Y2915227D01*
X-65251Y2914160D01*
X-65751Y2913360D01*
X-66651Y2912960D01*
X-69051D01*
G01X-56851Y2916960D02*
X-57451Y2917360D01*
X-58151Y2917627D01*
X-58951D01*
X-59851Y2917227D01*
X-60551Y2916560D01*
X-61051Y2915760D01*
X-61451Y2914427D01*
X-61551Y2913227D01*
X-61351Y2912027D01*
X-61051Y2911227D01*
X-60451Y2910427D01*
X-59751Y2909894D01*
X-59051Y2909627D01*
X-58351D01*
X-57651Y2909894D01*
X-57051Y2910294D01*
X-56551Y2910827D01*
G01X-50251Y2913894D02*
X-49851Y2914294D01*
X-49551Y2914960D01*
X-49351Y2915894D01*
X-49551Y2916694D01*
X-49951Y2917227D01*
X-50651Y2917627D01*
X-53351D01*
Y2909627D01*
X-50051D01*
X-49351Y2910160D01*
X-48951Y2910960D01*
X-48751Y2911894D01*
X-48951Y2912827D01*
X-49551Y2913627D01*
X-50251Y2913894D01*
X-53351D01*
G01X-37151Y2910693D02*
X-36351Y2910027D01*
X-35451Y2909627D01*
X-34651D01*
X-33851Y2910027D01*
X-33251Y2910693D01*
X-32951Y2911627D01*
X-33151Y2912560D01*
X-33651Y2913360D01*
X-34551Y2913894D01*
X-35751Y2914160D01*
X-36451Y2914694D01*
X-36751Y2915627D01*
X-36551Y2916560D01*
X-36051Y2917227D01*
X-35351Y2917627D01*
X-34651D01*
X-33951Y2917360D01*
X-33351Y2916694D01*
G01X-28251Y2917627D02*
X-25851D01*
G01X-27051D02*
Y2909627D01*
G01X-28251D02*
X-25851D01*
G01X-20951Y2917627D02*
X-17151D01*
X-20951Y2909627D01*
X-17151D01*
G01X-9051D02*
X-13051D01*
Y2917627D01*
X-9051D01*
G01X-10651Y2913760D02*
X-13051D01*
G01X20949Y2909360D02*
X20749Y2909494D01*
Y2909760D01*
X20949Y2909894D01*
X21149Y2909760D01*
Y2909494D01*
X20949Y2909360D01*
G01Y2912960D02*
X20749Y2913094D01*
Y2913360D01*
X20949Y2913494D01*
X21149Y2913360D01*
Y2913094D01*
X20949Y2912960D01*
G01X35049Y2909627D02*
Y2917627D01*
X38849D01*
G01X37449Y2913760D02*
X35049D01*
G01X44949Y2909627D02*
X44149Y2909760D01*
X43449Y2910294D01*
X42849Y2911094D01*
X42449Y2912027D01*
X42249Y2913094D01*
Y2914160D01*
X42449Y2915227D01*
X42849Y2916160D01*
X43449Y2916960D01*
X44149Y2917494D01*
X44949Y2917627D01*
X45749Y2917494D01*
X46449Y2916960D01*
X47049Y2916160D01*
X47449Y2915227D01*
X47649Y2914160D01*
Y2913094D01*
X47449Y2912027D01*
X47049Y2911094D01*
X46449Y2910294D01*
X45749Y2909760D01*
X44949Y2909627D01*
G01X50949Y2917627D02*
Y2909627D01*
X54949D01*
G01X58949Y2917627D02*
Y2909627D01*
X62949D01*
G01X68949D02*
X68149Y2909760D01*
X67449Y2910294D01*
X66849Y2911094D01*
X66449Y2912027D01*
X66249Y2913094D01*
Y2914160D01*
X66449Y2915227D01*
X66849Y2916160D01*
X67449Y2916960D01*
X68149Y2917494D01*
X68949Y2917627D01*
X69749Y2917494D01*
X70449Y2916960D01*
X71049Y2916160D01*
X71449Y2915227D01*
X71649Y2914160D01*
Y2913094D01*
X71449Y2912027D01*
X71049Y2911094D01*
X70449Y2910294D01*
X69749Y2909760D01*
X68949Y2909627D01*
G01X73949Y2917627D02*
X75349Y2909627D01*
X76949Y2917627D01*
X78549Y2909627D01*
X79949Y2917627D01*
G01X93549Y2913627D02*
X95549D01*
Y2911227D01*
X94949Y2910427D01*
X94249Y2909894D01*
X93249Y2909627D01*
X92249Y2909894D01*
X91549Y2910427D01*
X90949Y2911227D01*
X90549Y2912160D01*
X90349Y2913227D01*
Y2914160D01*
X90549Y2914960D01*
X90949Y2915894D01*
X91549Y2916694D01*
X92149Y2917227D01*
X92949Y2917627D01*
X93649D01*
X94449Y2917360D01*
X95049Y2916827D01*
G01X102949Y2909627D02*
X98949D01*
Y2917627D01*
X102949D01*
G01X101349Y2913760D02*
X98949D01*
G01X106949Y2909627D02*
Y2917627D01*
X109449D01*
X110249Y2917227D01*
X110749Y2916694D01*
X110949Y2915627D01*
X110749Y2914560D01*
X110149Y2913894D01*
X109449Y2913494D01*
X106949D01*
G01X109449D02*
X110949Y2909627D01*
G01X117749Y2913894D02*
X118149Y2914294D01*
X118449Y2914960D01*
X118649Y2915894D01*
X118449Y2916694D01*
X118049Y2917227D01*
X117349Y2917627D01*
X114649D01*
Y2909627D01*
X117949D01*
X118649Y2910160D01*
X119049Y2910960D01*
X119249Y2911894D01*
X119049Y2912827D01*
X118449Y2913627D01*
X117749Y2913894D01*
X114649D01*
G01X126949Y2909627D02*
X122949D01*
Y2917627D01*
X126949D01*
G01X125349Y2913760D02*
X122949D01*
G01X130949Y2909627D02*
Y2917627D01*
X133449D01*
X134249Y2917227D01*
X134749Y2916694D01*
X134949Y2915627D01*
X134749Y2914560D01*
X134149Y2913894D01*
X133449Y2913494D01*
X130949D01*
G01X133449D02*
X134949Y2909627D01*
G01X147049D02*
Y2917627D01*
X150849D01*
G01X149449Y2913760D02*
X147049D01*
G01X155749Y2917627D02*
X158149D01*
G01X156949D02*
Y2909627D01*
G01X155749D02*
X158149D01*
G01X162949Y2917627D02*
Y2909627D01*
X166949D01*
G01X174949D02*
X170949D01*
Y2917627D01*
X174949D01*
G01X173349Y2913760D02*
X170949D01*
G01X180249Y2907227D02*
X181649Y2909094D01*
Y2910960D01*
X180249D01*
Y2909094D01*
X181649D01*
G01Y2912294D02*
Y2914160D01*
X180249D01*
Y2912294D01*
X181649D01*
G01X193949Y2917627D02*
X195349Y2909627D01*
X196949Y2917627D01*
X198549Y2909627D01*
X199949Y2917627D01*
G01X203749D02*
X206149D01*
G01X204949D02*
Y2909627D01*
G01X203749D02*
X206149D01*
G01X212949Y2917627D02*
Y2909627D01*
G01X210649Y2917627D02*
X215249D01*
G01X218849Y2909627D02*
Y2917627D01*
G01X223049D02*
Y2909627D01*
G01Y2913627D02*
X218849D01*
G01X236949Y2917627D02*
Y2909627D01*
G01X234649Y2917627D02*
X239249D01*
G01X244949Y2909627D02*
X244149Y2909760D01*
X243449Y2910294D01*
X242849Y2911094D01*
X242449Y2912027D01*
X242249Y2913094D01*
Y2914160D01*
X242449Y2915227D01*
X242849Y2916160D01*
X243449Y2916960D01*
X244149Y2917494D01*
X244949Y2917627D01*
X245749Y2917494D01*
X246449Y2916960D01*
X247049Y2916160D01*
X247449Y2915227D01*
X247649Y2914160D01*
Y2913094D01*
X247449Y2912027D01*
X247049Y2911094D01*
X246449Y2910294D01*
X245749Y2909760D01*
X244949Y2909627D01*
G01X250949Y2917627D02*
Y2909627D01*
X254949D01*
G01X262949D02*
X258949D01*
Y2917627D01*
X262949D01*
G01X261349Y2913760D02*
X258949D01*
G01X266949Y2909627D02*
Y2917627D01*
X269449D01*
X270249Y2917227D01*
X270749Y2916694D01*
X270949Y2915627D01*
X270749Y2914560D01*
X270149Y2913894D01*
X269449Y2913494D01*
X266949D01*
G01X269449D02*
X270949Y2909627D01*
G01X274449D02*
X276949Y2917627D01*
X279449Y2909627D01*
G01X278549Y2912427D02*
X275349D01*
G01X282649Y2909627D02*
Y2917627D01*
X287249Y2909627D01*
Y2917627D01*
G01X295149Y2916960D02*
X294549Y2917360D01*
X293849Y2917627D01*
X293049D01*
X292149Y2917227D01*
X291449Y2916560D01*
X290949Y2915760D01*
X290549Y2914427D01*
X290449Y2913227D01*
X290649Y2912027D01*
X290949Y2911227D01*
X291549Y2910427D01*
X292249Y2909894D01*
X292949Y2909627D01*
X293649D01*
X294349Y2909894D01*
X294949Y2910294D01*
X295449Y2910827D01*
G01X302949Y2909627D02*
X298949D01*
Y2917627D01*
X302949D01*
G01X301349Y2913760D02*
X298949D01*
G01X315649Y2911094D02*
X318249D01*
G01Y2913494D02*
X315649D01*
G01X323849Y2912294D02*
X326249D01*
G01X324949Y2914027D02*
Y2910560D01*
G01X331149Y2909360D02*
X334749Y2917627D01*
G01X339649Y2912294D02*
X342249D01*
G01X348949Y2917627D02*
X348149Y2917360D01*
X347549Y2916694D01*
X347149Y2915894D01*
X346849Y2914827D01*
X346749Y2913627D01*
X346849Y2912427D01*
X347149Y2911360D01*
X347549Y2910560D01*
X348149Y2909894D01*
X348949Y2909627D01*
X349749Y2909894D01*
X350349Y2910560D01*
X350749Y2911360D01*
X351049Y2912427D01*
X351149Y2913627D01*
X351049Y2914827D01*
X350749Y2915894D01*
X350349Y2916694D01*
X349749Y2917360D01*
X348949Y2917627D01*
G01X356949Y2909360D02*
X356749Y2909494D01*
Y2909760D01*
X356949Y2909894D01*
X357149Y2909760D01*
Y2909494D01*
X356949Y2909360D01*
G01X364949Y2909627D02*
Y2917627D01*
X363749Y2916027D01*
G01Y2909627D02*
X366149D01*
G01X370749Y2910827D02*
X371349Y2910160D01*
X372049Y2909760D01*
X372949Y2909627D01*
X373849Y2909894D01*
X374549Y2910427D01*
X375049Y2911360D01*
X375149Y2912427D01*
X374949Y2913494D01*
X374449Y2914160D01*
X373749Y2914694D01*
X373049Y2914827D01*
X372349Y2914694D01*
X371449Y2914160D01*
X371749Y2917627D01*
X374449D01*
G01X378349Y2909627D02*
Y2917627D01*
X380949Y2910960D01*
X383549Y2917627D01*
Y2909627D01*
G01X386349D02*
Y2917627D01*
X388949Y2910960D01*
X391549Y2917627D01*
Y2909627D01*
G01X-24429Y2456134D02*
X-67736D01*
G01X-59862D02*
Y2509284D01*
G01X-24429Y2471883D02*
X-67736D01*
G01X-68051Y2684627D02*
X-68851Y2684760D01*
X-69551Y2685294D01*
X-70151Y2686094D01*
X-70551Y2687027D01*
X-70751Y2688094D01*
Y2689160D01*
X-70551Y2690227D01*
X-70151Y2691160D01*
X-69551Y2691960D01*
X-68851Y2692494D01*
X-68051Y2692627D01*
X-67251Y2692494D01*
X-66551Y2691960D01*
X-65951Y2691160D01*
X-65551Y2690227D01*
X-65351Y2689160D01*
Y2688094D01*
X-65551Y2687027D01*
X-65951Y2686094D01*
X-66551Y2685294D01*
X-67251Y2684760D01*
X-68051Y2684627D01*
G01X-67251Y2686760D02*
X-66051Y2684627D01*
G01X-62251Y2692627D02*
Y2686894D01*
X-61851Y2685693D01*
X-61051Y2684894D01*
X-60051Y2684627D01*
X-59051Y2684894D01*
X-58251Y2685693D01*
X-57851Y2686894D01*
Y2692627D01*
G01X-54551Y2684627D02*
X-52051Y2692627D01*
X-49551Y2684627D01*
G01X-50451Y2687427D02*
X-53651D01*
G01X-46351Y2684627D02*
Y2692627D01*
X-41751Y2684627D01*
Y2692627D01*
G01X-36051D02*
Y2684627D01*
G01X-38351Y2692627D02*
X-33751D01*
G01X-30551Y2684627D02*
X-28051Y2692627D01*
X-25551Y2684627D01*
G01X-26451Y2687427D02*
X-29651D01*
G01X-14051Y2684627D02*
Y2692627D01*
X-11651D01*
X-10851Y2692227D01*
X-10251Y2691294D01*
X-10051Y2690227D01*
X-10251Y2689160D01*
X-10751Y2688360D01*
X-11651Y2687960D01*
X-14051D01*
G01X-6051Y2684627D02*
Y2692627D01*
X-3551D01*
X-2751Y2692227D01*
X-2251Y2691694D01*
X-2051Y2690627D01*
X-2251Y2689560D01*
X-2851Y2688894D01*
X-3551Y2688494D01*
X-6051D01*
G01X-3551D02*
X-2051Y2684627D01*
G01X2749Y2692627D02*
X5149D01*
G01X3949D02*
Y2684627D01*
G01X2749D02*
X5149D01*
G01X11949D02*
X11149Y2684760D01*
X10449Y2685294D01*
X9849Y2686094D01*
X9449Y2687027D01*
X9249Y2688094D01*
Y2689160D01*
X9449Y2690227D01*
X9849Y2691160D01*
X10449Y2691960D01*
X11149Y2692494D01*
X11949Y2692627D01*
X12749Y2692494D01*
X13449Y2691960D01*
X14049Y2691160D01*
X14449Y2690227D01*
X14649Y2689160D01*
Y2688094D01*
X14449Y2687027D01*
X14049Y2686094D01*
X13449Y2685294D01*
X12749Y2684760D01*
X11949Y2684627D01*
G01X17949D02*
Y2692627D01*
X20449D01*
X21249Y2692227D01*
X21749Y2691694D01*
X21949Y2690627D01*
X21749Y2689560D01*
X21149Y2688894D01*
X20449Y2688494D01*
X17949D01*
G01X20449D02*
X21949Y2684627D01*
G01X35949Y2692627D02*
Y2684627D01*
G01X33649Y2692627D02*
X38249D01*
G01X43949Y2684627D02*
X43149Y2684760D01*
X42449Y2685294D01*
X41849Y2686094D01*
X41449Y2687027D01*
X41249Y2688094D01*
Y2689160D01*
X41449Y2690227D01*
X41849Y2691160D01*
X42449Y2691960D01*
X43149Y2692494D01*
X43949Y2692627D01*
X44749Y2692494D01*
X45449Y2691960D01*
X46049Y2691160D01*
X46449Y2690227D01*
X46649Y2689160D01*
Y2688094D01*
X46449Y2687027D01*
X46049Y2686094D01*
X45449Y2685294D01*
X44749Y2684760D01*
X43949Y2684627D01*
G01X58749Y2692627D02*
X61149D01*
G01X59949D02*
Y2684627D01*
G01X58749D02*
X61149D01*
G01X67949Y2692627D02*
Y2684627D01*
G01X65649Y2692627D02*
X70249D01*
G01X73849Y2685693D02*
X74649Y2685027D01*
X75549Y2684627D01*
X76349D01*
X77149Y2685027D01*
X77749Y2685693D01*
X78049Y2686627D01*
X77849Y2687560D01*
X77349Y2688360D01*
X76449Y2688894D01*
X75249Y2689160D01*
X74549Y2689694D01*
X74249Y2690627D01*
X74449Y2691560D01*
X74949Y2692227D01*
X75649Y2692627D01*
X76349D01*
X77049Y2692360D01*
X77649Y2691694D01*
G01X90749Y2692627D02*
X93149D01*
G01X91949D02*
Y2684627D01*
G01X90749D02*
X93149D01*
G01X97349D02*
Y2692627D01*
X99949Y2685960D01*
X102549Y2692627D01*
Y2684627D01*
G01X105949D02*
Y2692627D01*
X108349D01*
X109149Y2692227D01*
X109749Y2691294D01*
X109949Y2690227D01*
X109749Y2689160D01*
X109249Y2688360D01*
X108349Y2687960D01*
X105949D01*
G01X113949Y2692627D02*
Y2684627D01*
X117949D01*
G01X125949D02*
X121949D01*
Y2692627D01*
X125949D01*
G01X124349Y2688760D02*
X121949D01*
G01X129349Y2684627D02*
Y2692627D01*
X131949Y2685960D01*
X134549Y2692627D01*
Y2684627D01*
G01X141949D02*
X137949D01*
Y2692627D01*
X141949D01*
G01X140349Y2688760D02*
X137949D01*
G01X145649Y2684627D02*
Y2692627D01*
X150249Y2684627D01*
Y2692627D01*
G01X155949D02*
Y2684627D01*
G01X153649Y2692627D02*
X158249D01*
G01X161449Y2684627D02*
X163949Y2692627D01*
X166449Y2684627D01*
G01X165549Y2687427D02*
X162349D01*
G01X171949Y2692627D02*
Y2684627D01*
G01X169649Y2692627D02*
X174249D01*
G01X178749D02*
X181149D01*
G01X179949D02*
Y2684627D01*
G01X178749D02*
X181149D01*
G01X187949D02*
X187149Y2684760D01*
X186449Y2685294D01*
X185849Y2686094D01*
X185449Y2687027D01*
X185249Y2688094D01*
Y2689160D01*
X185449Y2690227D01*
X185849Y2691160D01*
X186449Y2691960D01*
X187149Y2692494D01*
X187949Y2692627D01*
X188749Y2692494D01*
X189449Y2691960D01*
X190049Y2691160D01*
X190449Y2690227D01*
X190649Y2689160D01*
Y2688094D01*
X190449Y2687027D01*
X190049Y2686094D01*
X189449Y2685294D01*
X188749Y2684760D01*
X187949Y2684627D01*
G01X193649D02*
Y2692627D01*
X198249Y2684627D01*
Y2692627D01*
G01X203949Y2684360D02*
X203749Y2684494D01*
Y2684760D01*
X203949Y2684894D01*
X204149Y2684760D01*
Y2684494D01*
X203949Y2684360D01*
G01X-69251Y2722627D02*
X-66851D01*
G01X-68051D02*
Y2714627D01*
G01X-69251D02*
X-66851D01*
G01X-62651D02*
Y2722627D01*
X-60051Y2715960D01*
X-57451Y2722627D01*
Y2714627D01*
G01X-54051D02*
Y2722627D01*
X-51651D01*
X-50851Y2722227D01*
X-50251Y2721294D01*
X-50051Y2720227D01*
X-50251Y2719160D01*
X-50751Y2718360D01*
X-51651Y2717960D01*
X-54051D01*
G01X-42051Y2714627D02*
X-46051D01*
Y2722627D01*
X-42051D01*
G01X-43651Y2718760D02*
X-46051D01*
G01X-38251Y2714627D02*
Y2722627D01*
X-36251D01*
X-35451Y2722227D01*
X-34851Y2721694D01*
X-34351Y2720894D01*
X-33951Y2719960D01*
X-33851Y2718627D01*
X-33951Y2717294D01*
X-34351Y2716360D01*
X-34851Y2715560D01*
X-35451Y2715027D01*
X-36251Y2714627D01*
X-38251D01*
G01X-30551D02*
X-28051Y2722627D01*
X-25551Y2714627D01*
G01X-26451Y2717427D02*
X-29651D01*
G01X-22351Y2714627D02*
Y2722627D01*
X-17751Y2714627D01*
Y2722627D01*
G01X-9851Y2721960D02*
X-10451Y2722360D01*
X-11151Y2722627D01*
X-11951D01*
X-12851Y2722227D01*
X-13551Y2721560D01*
X-14051Y2720760D01*
X-14451Y2719427D01*
X-14551Y2718227D01*
X-14351Y2717027D01*
X-14051Y2716227D01*
X-13451Y2715427D01*
X-12751Y2714894D01*
X-12051Y2714627D01*
X-11351D01*
X-10651Y2714894D01*
X-10051Y2715294D01*
X-9551Y2715827D01*
G01X-2051Y2714627D02*
X-6051D01*
Y2722627D01*
X-2051D01*
G01X-3651Y2718760D02*
X-6051D01*
G01X1849Y2715693D02*
X2649Y2715027D01*
X3549Y2714627D01*
X4349D01*
X5149Y2715027D01*
X5749Y2715693D01*
X6049Y2716627D01*
X5849Y2717560D01*
X5349Y2718360D01*
X4449Y2718894D01*
X3249Y2719160D01*
X2549Y2719694D01*
X2249Y2720627D01*
X2449Y2721560D01*
X2949Y2722227D01*
X3649Y2722627D01*
X4349D01*
X5049Y2722360D01*
X5649Y2721694D01*
G01X17449Y2714627D02*
X19949Y2722627D01*
X22449Y2714627D01*
G01X21549Y2717427D02*
X18349D01*
G01X25649Y2714627D02*
Y2722627D01*
X30249Y2714627D01*
Y2722627D01*
G01X33749Y2714627D02*
Y2722627D01*
X35749D01*
X36549Y2722227D01*
X37149Y2721694D01*
X37649Y2720894D01*
X38049Y2719960D01*
X38149Y2718627D01*
X38049Y2717294D01*
X37649Y2716360D01*
X37149Y2715560D01*
X36549Y2715027D01*
X35749Y2714627D01*
X33749D01*
G01X52749Y2718894D02*
X53149Y2719294D01*
X53449Y2719960D01*
X53649Y2720894D01*
X53449Y2721694D01*
X53049Y2722227D01*
X52349Y2722627D01*
X49649D01*
Y2714627D01*
X52949D01*
X53649Y2715160D01*
X54049Y2715960D01*
X54249Y2716894D01*
X54049Y2717827D01*
X53449Y2718627D01*
X52749Y2718894D01*
X49649D01*
G01X59949Y2714627D02*
X59149Y2714760D01*
X58449Y2715294D01*
X57849Y2716094D01*
X57449Y2717027D01*
X57249Y2718094D01*
Y2719160D01*
X57449Y2720227D01*
X57849Y2721160D01*
X58449Y2721960D01*
X59149Y2722494D01*
X59949Y2722627D01*
X60749Y2722494D01*
X61449Y2721960D01*
X62049Y2721160D01*
X62449Y2720227D01*
X62649Y2719160D01*
Y2718094D01*
X62449Y2717027D01*
X62049Y2716094D01*
X61449Y2715294D01*
X60749Y2714760D01*
X59949Y2714627D01*
G01X65449D02*
X67949Y2722627D01*
X70449Y2714627D01*
G01X69549Y2717427D02*
X66349D01*
G01X73949Y2714627D02*
Y2722627D01*
X76449D01*
X77249Y2722227D01*
X77749Y2721694D01*
X77949Y2720627D01*
X77749Y2719560D01*
X77149Y2718894D01*
X76449Y2718494D01*
X73949D01*
G01X76449D02*
X77949Y2714627D01*
G01X81749D02*
Y2722627D01*
X83749D01*
X84549Y2722227D01*
X85149Y2721694D01*
X85649Y2720894D01*
X86049Y2719960D01*
X86149Y2718627D01*
X86049Y2717294D01*
X85649Y2716360D01*
X85149Y2715560D01*
X84549Y2715027D01*
X83749Y2714627D01*
X81749D01*
G01X99949Y2722627D02*
Y2714627D01*
G01X97649Y2722627D02*
X102249D01*
G01X105849Y2714627D02*
Y2722627D01*
G01X110049D02*
Y2714627D01*
G01Y2718627D02*
X105849D01*
G01X114749Y2722627D02*
X117149D01*
G01X115949D02*
Y2714627D01*
G01X114749D02*
X117149D01*
G01X126149Y2721960D02*
X125549Y2722360D01*
X124849Y2722627D01*
X124049D01*
X123149Y2722227D01*
X122449Y2721560D01*
X121949Y2720760D01*
X121549Y2719427D01*
X121449Y2718227D01*
X121649Y2717027D01*
X121949Y2716227D01*
X122549Y2715427D01*
X123249Y2714894D01*
X123949Y2714627D01*
X124649D01*
X125349Y2714894D01*
X125949Y2715294D01*
X126449Y2715827D01*
G01X129749Y2714627D02*
Y2722627D01*
G01X133549D02*
X129749Y2717693D01*
G01X134149Y2714627D02*
X131449Y2719960D01*
G01X137649Y2714627D02*
Y2722627D01*
X142249Y2714627D01*
Y2722627D01*
G01X149949Y2714627D02*
X145949D01*
Y2722627D01*
X149949D01*
G01X148349Y2718760D02*
X145949D01*
G01X153849Y2715693D02*
X154649Y2715027D01*
X155549Y2714627D01*
X156349D01*
X157149Y2715027D01*
X157749Y2715693D01*
X158049Y2716627D01*
X157849Y2717560D01*
X157349Y2718360D01*
X156449Y2718894D01*
X155249Y2719160D01*
X154549Y2719694D01*
X154249Y2720627D01*
X154449Y2721560D01*
X154949Y2722227D01*
X155649Y2722627D01*
X156349D01*
X157049Y2722360D01*
X157649Y2721694D01*
G01X161849Y2715693D02*
X162649Y2715027D01*
X163549Y2714627D01*
X164349D01*
X165149Y2715027D01*
X165749Y2715693D01*
X166049Y2716627D01*
X165849Y2717560D01*
X165349Y2718360D01*
X164449Y2718894D01*
X163249Y2719160D01*
X162549Y2719694D01*
X162249Y2720627D01*
X162449Y2721560D01*
X162949Y2722227D01*
X163649Y2722627D01*
X164349D01*
X165049Y2722360D01*
X165649Y2721694D01*
G01X171949Y2714360D02*
X171749Y2714494D01*
Y2714760D01*
X171949Y2714894D01*
X172149Y2714760D01*
Y2714494D01*
X171949Y2714360D01*
G01X194749Y2722627D02*
X197149D01*
G01X195949D02*
Y2714627D01*
G01X194749D02*
X197149D01*
G01X201649D02*
Y2722627D01*
X206249Y2714627D01*
Y2722627D01*
G01X210749D02*
X213149D01*
G01X211949D02*
Y2714627D01*
G01X210749D02*
X213149D01*
G01X219949Y2722627D02*
Y2714627D01*
G01X217649Y2722627D02*
X222249D01*
G01X226749D02*
X229149D01*
G01X227949D02*
Y2714627D01*
G01X226749D02*
X229149D01*
G01X233449D02*
X235949Y2722627D01*
X238449Y2714627D01*
G01X237549Y2717427D02*
X234349D01*
G01X241949Y2722627D02*
Y2714627D01*
X245949D01*
G01X257749D02*
Y2722627D01*
X259749D01*
X260549Y2722227D01*
X261149Y2721694D01*
X261649Y2720894D01*
X262049Y2719960D01*
X262149Y2718627D01*
X262049Y2717294D01*
X261649Y2716360D01*
X261149Y2715560D01*
X260549Y2715027D01*
X259749Y2714627D01*
X257749D01*
G01X269949D02*
X265949D01*
Y2722627D01*
X269949D01*
G01X268349Y2718760D02*
X265949D01*
G01X275949Y2722627D02*
Y2714627D01*
G01X273649Y2722627D02*
X278249D01*
G01X281449Y2714627D02*
X283949Y2722627D01*
X286449Y2714627D01*
G01X285549Y2717427D02*
X282349D01*
G01X290749Y2722627D02*
X293149D01*
G01X291949D02*
Y2714627D01*
G01X290749D02*
X293149D01*
G01X297949Y2722627D02*
Y2714627D01*
X301949D01*
G01X313949Y2722627D02*
Y2714627D01*
X317949D01*
G01X321449D02*
X323949Y2722627D01*
X326449Y2714627D01*
G01X325549Y2717427D02*
X322349D01*
G01X331949Y2714627D02*
Y2718227D01*
X329949Y2722627D01*
G01X333949D02*
X331949Y2718227D01*
G01X341949Y2714627D02*
X337949D01*
Y2722627D01*
X341949D01*
G01X340349Y2718760D02*
X337949D01*
G01X345949Y2714627D02*
Y2722627D01*
X348449D01*
X349249Y2722227D01*
X349749Y2721694D01*
X349949Y2720627D01*
X349749Y2719560D01*
X349149Y2718894D01*
X348449Y2718494D01*
X345949D01*
G01X348449D02*
X349949Y2714627D01*
G01X-70151Y2700693D02*
X-69351Y2700027D01*
X-68451Y2699627D01*
X-67651D01*
X-66851Y2700027D01*
X-66251Y2700693D01*
X-65951Y2701627D01*
X-66151Y2702560D01*
X-66651Y2703360D01*
X-67551Y2703894D01*
X-68751Y2704160D01*
X-69451Y2704694D01*
X-69751Y2705627D01*
X-69551Y2706560D01*
X-69051Y2707227D01*
X-68351Y2707627D01*
X-67651D01*
X-66951Y2707360D01*
X-66351Y2706694D01*
G01X-60051Y2707627D02*
Y2699627D01*
G01X-62351Y2707627D02*
X-57751D01*
G01X-54551Y2699627D02*
X-52051Y2707627D01*
X-49551Y2699627D01*
G01X-50451Y2702427D02*
X-53651D01*
G01X-41851Y2706960D02*
X-42451Y2707360D01*
X-43151Y2707627D01*
X-43951D01*
X-44851Y2707227D01*
X-45551Y2706560D01*
X-46051Y2705760D01*
X-46451Y2704427D01*
X-46551Y2703227D01*
X-46351Y2702027D01*
X-46051Y2701227D01*
X-45451Y2700427D01*
X-44751Y2699894D01*
X-44051Y2699627D01*
X-43351D01*
X-42651Y2699894D01*
X-42051Y2700294D01*
X-41551Y2700827D01*
G01X-38251Y2699627D02*
Y2707627D01*
G01X-34451D02*
X-38251Y2702693D01*
G01X-33851Y2699627D02*
X-36551Y2704960D01*
G01X-29251Y2707627D02*
X-26851D01*
G01X-28051D02*
Y2699627D01*
G01X-29251D02*
X-26851D01*
G01X-22351D02*
Y2707627D01*
X-17751Y2699627D01*
Y2707627D01*
G01X-11451Y2703627D02*
X-9451D01*
Y2701227D01*
X-10051Y2700427D01*
X-10751Y2699894D01*
X-11751Y2699627D01*
X-12751Y2699894D01*
X-13451Y2700427D01*
X-14051Y2701227D01*
X-14451Y2702160D01*
X-14651Y2703227D01*
Y2704160D01*
X-14451Y2704960D01*
X-14051Y2705894D01*
X-13451Y2706694D01*
X-12851Y2707227D01*
X-12051Y2707627D01*
X-11351D01*
X-10551Y2707360D01*
X-9951Y2706827D01*
G01X1449Y2699627D02*
X3949Y2707627D01*
X6449Y2699627D01*
G01X5549Y2702427D02*
X2349D01*
G01X9649Y2699627D02*
Y2707627D01*
X14249Y2699627D01*
Y2707627D01*
G01X17749Y2699627D02*
Y2707627D01*
X19749D01*
X20549Y2707227D01*
X21149Y2706694D01*
X21649Y2705894D01*
X22049Y2704960D01*
X22149Y2703627D01*
X22049Y2702294D01*
X21649Y2701360D01*
X21149Y2700560D01*
X20549Y2700027D01*
X19749Y2699627D01*
X17749D01*
G01X35949D02*
X35149Y2699760D01*
X34449Y2700294D01*
X33849Y2701094D01*
X33449Y2702027D01*
X33249Y2703094D01*
Y2704160D01*
X33449Y2705227D01*
X33849Y2706160D01*
X34449Y2706960D01*
X35149Y2707494D01*
X35949Y2707627D01*
X36749Y2707494D01*
X37449Y2706960D01*
X38049Y2706160D01*
X38449Y2705227D01*
X38649Y2704160D01*
Y2703094D01*
X38449Y2702027D01*
X38049Y2701094D01*
X37449Y2700294D01*
X36749Y2699760D01*
X35949Y2699627D01*
G01X43949Y2707627D02*
Y2699627D01*
G01X41649Y2707627D02*
X46249D01*
G01X49849Y2699627D02*
Y2707627D01*
G01X54049D02*
Y2699627D01*
G01Y2703627D02*
X49849D01*
G01X61949Y2699627D02*
X57949D01*
Y2707627D01*
X61949D01*
G01X60349Y2703760D02*
X57949D01*
G01X65949Y2699627D02*
Y2707627D01*
X68449D01*
X69249Y2707227D01*
X69749Y2706694D01*
X69949Y2705627D01*
X69749Y2704560D01*
X69149Y2703894D01*
X68449Y2703494D01*
X65949D01*
G01X68449D02*
X69949Y2699627D01*
G01X81849Y2700693D02*
X82649Y2700027D01*
X83549Y2699627D01*
X84349D01*
X85149Y2700027D01*
X85749Y2700693D01*
X86049Y2701627D01*
X85849Y2702560D01*
X85349Y2703360D01*
X84449Y2703894D01*
X83249Y2704160D01*
X82549Y2704694D01*
X82249Y2705627D01*
X82449Y2706560D01*
X82949Y2707227D01*
X83649Y2707627D01*
X84349D01*
X85049Y2707360D01*
X85649Y2706694D01*
G01X89749Y2707627D02*
Y2701894D01*
X90149Y2700693D01*
X90949Y2699894D01*
X91949Y2699627D01*
X92949Y2699894D01*
X93749Y2700693D01*
X94149Y2701894D01*
Y2707627D01*
G01X100749Y2703894D02*
X101149Y2704294D01*
X101449Y2704960D01*
X101649Y2705894D01*
X101449Y2706694D01*
X101049Y2707227D01*
X100349Y2707627D01*
X97649D01*
Y2699627D01*
X100949D01*
X101649Y2700160D01*
X102049Y2700960D01*
X102249Y2701894D01*
X102049Y2702827D01*
X101449Y2703627D01*
X100749Y2703894D01*
X97649D01*
G01X105849Y2700693D02*
X106649Y2700027D01*
X107549Y2699627D01*
X108349D01*
X109149Y2700027D01*
X109749Y2700693D01*
X110049Y2701627D01*
X109849Y2702560D01*
X109349Y2703360D01*
X108449Y2703894D01*
X107249Y2704160D01*
X106549Y2704694D01*
X106249Y2705627D01*
X106449Y2706560D01*
X106949Y2707227D01*
X107649Y2707627D01*
X108349D01*
X109049Y2707360D01*
X109649Y2706694D01*
G01X117949Y2699627D02*
X113949D01*
Y2707627D01*
X117949D01*
G01X116349Y2703760D02*
X113949D01*
G01X123949Y2699627D02*
X123149Y2699760D01*
X122449Y2700294D01*
X121849Y2701094D01*
X121449Y2702027D01*
X121249Y2703094D01*
Y2704160D01*
X121449Y2705227D01*
X121849Y2706160D01*
X122449Y2706960D01*
X123149Y2707494D01*
X123949Y2707627D01*
X124749Y2707494D01*
X125449Y2706960D01*
X126049Y2706160D01*
X126449Y2705227D01*
X126649Y2704160D01*
Y2703094D01*
X126449Y2702027D01*
X126049Y2701094D01*
X125449Y2700294D01*
X124749Y2699760D01*
X123949Y2699627D01*
G01X124749Y2701760D02*
X125949Y2699627D01*
G01X129749Y2707627D02*
Y2701894D01*
X130149Y2700693D01*
X130949Y2699894D01*
X131949Y2699627D01*
X132949Y2699894D01*
X133749Y2700693D01*
X134149Y2701894D01*
Y2707627D01*
G01X141949Y2699627D02*
X137949D01*
Y2707627D01*
X141949D01*
G01X140349Y2703760D02*
X137949D01*
G01X145649Y2699627D02*
Y2707627D01*
X150249Y2699627D01*
Y2707627D01*
G01X155949D02*
Y2699627D01*
G01X153649Y2707627D02*
X158249D01*
G01X174149Y2706960D02*
X173549Y2707360D01*
X172849Y2707627D01*
X172049D01*
X171149Y2707227D01*
X170449Y2706560D01*
X169949Y2705760D01*
X169549Y2704427D01*
X169449Y2703227D01*
X169649Y2702027D01*
X169949Y2701227D01*
X170549Y2700427D01*
X171249Y2699894D01*
X171949Y2699627D01*
X172649D01*
X173349Y2699894D01*
X173949Y2700294D01*
X174449Y2700827D01*
G01X177849Y2699627D02*
Y2707627D01*
G01X182049D02*
Y2699627D01*
G01Y2703627D02*
X177849D01*
G01X185449Y2699627D02*
X187949Y2707627D01*
X190449Y2699627D01*
G01X189549Y2702427D02*
X186349D01*
G01X193649Y2699627D02*
Y2707627D01*
X198249Y2699627D01*
Y2707627D01*
G01X204549Y2703627D02*
X206549D01*
Y2701227D01*
X205949Y2700427D01*
X205249Y2699894D01*
X204249Y2699627D01*
X203249Y2699894D01*
X202549Y2700427D01*
X201949Y2701227D01*
X201549Y2702160D01*
X201349Y2703227D01*
Y2704160D01*
X201549Y2704960D01*
X201949Y2705894D01*
X202549Y2706694D01*
X203149Y2707227D01*
X203949Y2707627D01*
X204649D01*
X205449Y2707360D01*
X206049Y2706827D01*
G01X213949Y2699627D02*
X209949D01*
Y2707627D01*
X213949D01*
G01X212349Y2703760D02*
X209949D01*
G01X217849Y2700693D02*
X218649Y2700027D01*
X219549Y2699627D01*
X220349D01*
X221149Y2700027D01*
X221749Y2700693D01*
X222049Y2701627D01*
X221849Y2702560D01*
X221349Y2703360D01*
X220449Y2703894D01*
X219249Y2704160D01*
X218549Y2704694D01*
X218249Y2705627D01*
X218449Y2706560D01*
X218949Y2707227D01*
X219649Y2707627D01*
X220349D01*
X221049Y2707360D01*
X221649Y2706694D01*
G01X233349Y2699627D02*
Y2707627D01*
X235949Y2700960D01*
X238549Y2707627D01*
Y2699627D01*
G01X241749Y2707627D02*
Y2701894D01*
X242149Y2700693D01*
X242949Y2699894D01*
X243949Y2699627D01*
X244949Y2699894D01*
X245749Y2700693D01*
X246149Y2701894D01*
Y2707627D01*
G01X249849Y2700693D02*
X250649Y2700027D01*
X251549Y2699627D01*
X252349D01*
X253149Y2700027D01*
X253749Y2700693D01*
X254049Y2701627D01*
X253849Y2702560D01*
X253349Y2703360D01*
X252449Y2703894D01*
X251249Y2704160D01*
X250549Y2704694D01*
X250249Y2705627D01*
X250449Y2706560D01*
X250949Y2707227D01*
X251649Y2707627D01*
X252349D01*
X253049Y2707360D01*
X253649Y2706694D01*
G01X259949Y2707627D02*
Y2699627D01*
G01X257649Y2707627D02*
X262249D01*
G01X276749Y2703894D02*
X277149Y2704294D01*
X277449Y2704960D01*
X277649Y2705894D01*
X277449Y2706694D01*
X277049Y2707227D01*
X276349Y2707627D01*
X273649D01*
Y2699627D01*
X276949D01*
X277649Y2700160D01*
X278049Y2700960D01*
X278249Y2701894D01*
X278049Y2702827D01*
X277449Y2703627D01*
X276749Y2703894D01*
X273649D01*
G01X285949Y2699627D02*
X281949D01*
Y2707627D01*
X285949D01*
G01X284349Y2703760D02*
X281949D01*
G01X297449Y2699627D02*
X299949Y2707627D01*
X302449Y2699627D01*
G01X301549Y2702427D02*
X298349D01*
G01X305949Y2699627D02*
Y2707627D01*
X308349D01*
X309149Y2707227D01*
X309749Y2706294D01*
X309949Y2705227D01*
X309749Y2704160D01*
X309249Y2703360D01*
X308349Y2702960D01*
X305949D01*
G01X313949Y2699627D02*
Y2707627D01*
X316349D01*
X317149Y2707227D01*
X317749Y2706294D01*
X317949Y2705227D01*
X317749Y2704160D01*
X317249Y2703360D01*
X316349Y2702960D01*
X313949D01*
G01X321949Y2699627D02*
Y2707627D01*
X324449D01*
X325249Y2707227D01*
X325749Y2706694D01*
X325949Y2705627D01*
X325749Y2704560D01*
X325149Y2703894D01*
X324449Y2703494D01*
X321949D01*
G01X324449D02*
X325949Y2699627D01*
G01X331949D02*
X331149Y2699760D01*
X330449Y2700294D01*
X329849Y2701094D01*
X329449Y2702027D01*
X329249Y2703094D01*
Y2704160D01*
X329449Y2705227D01*
X329849Y2706160D01*
X330449Y2706960D01*
X331149Y2707494D01*
X331949Y2707627D01*
X332749Y2707494D01*
X333449Y2706960D01*
X334049Y2706160D01*
X334449Y2705227D01*
X334649Y2704160D01*
Y2703094D01*
X334449Y2702027D01*
X334049Y2701094D01*
X333449Y2700294D01*
X332749Y2699760D01*
X331949Y2699627D01*
G01X337449Y2707627D02*
X339949Y2699627D01*
X342449Y2707627D01*
G01X349949Y2699627D02*
X345949D01*
Y2707627D01*
X349949D01*
G01X348349Y2703760D02*
X345949D01*
G01X353749Y2699627D02*
Y2707627D01*
X355749D01*
X356549Y2707227D01*
X357149Y2706694D01*
X357649Y2705894D01*
X358049Y2704960D01*
X358149Y2703627D01*
X358049Y2702294D01*
X357649Y2701360D01*
X357149Y2700560D01*
X356549Y2700027D01*
X355749Y2699627D01*
X353749D01*
G01X372749Y2703894D02*
X373149Y2704294D01*
X373449Y2704960D01*
X373649Y2705894D01*
X373449Y2706694D01*
X373049Y2707227D01*
X372349Y2707627D01*
X369649D01*
Y2699627D01*
X372949D01*
X373649Y2700160D01*
X374049Y2700960D01*
X374249Y2701894D01*
X374049Y2702827D01*
X373449Y2703627D01*
X372749Y2703894D01*
X369649D01*
G01X379949Y2699627D02*
Y2703227D01*
X377949Y2707627D01*
G01X381949D02*
X379949Y2703227D01*
G01X-70151Y2730693D02*
X-69351Y2730027D01*
X-68451Y2729627D01*
X-67651D01*
X-66851Y2730027D01*
X-66251Y2730693D01*
X-65951Y2731627D01*
X-66151Y2732560D01*
X-66651Y2733360D01*
X-67551Y2733894D01*
X-68751Y2734160D01*
X-69451Y2734694D01*
X-69751Y2735627D01*
X-69551Y2736560D01*
X-69051Y2737227D01*
X-68351Y2737627D01*
X-67651D01*
X-66951Y2737360D01*
X-66351Y2736694D01*
G01X-62051Y2729627D02*
Y2737627D01*
X-59651D01*
X-58851Y2737227D01*
X-58251Y2736294D01*
X-58051Y2735227D01*
X-58251Y2734160D01*
X-58751Y2733360D01*
X-59651Y2732960D01*
X-62051D01*
G01X-54551Y2729627D02*
X-52051Y2737627D01*
X-49551Y2729627D01*
G01X-50451Y2732427D02*
X-53651D01*
G01X-41851Y2736960D02*
X-42451Y2737360D01*
X-43151Y2737627D01*
X-43951D01*
X-44851Y2737227D01*
X-45551Y2736560D01*
X-46051Y2735760D01*
X-46451Y2734427D01*
X-46551Y2733227D01*
X-46351Y2732027D01*
X-46051Y2731227D01*
X-45451Y2730427D01*
X-44751Y2729894D01*
X-44051Y2729627D01*
X-43351D01*
X-42651Y2729894D01*
X-42051Y2730294D01*
X-41551Y2730827D01*
G01X-37251Y2737627D02*
X-34851D01*
G01X-36051D02*
Y2729627D01*
G01X-37251D02*
X-34851D01*
G01X-30351D02*
Y2737627D01*
X-25751Y2729627D01*
Y2737627D01*
G01X-19451Y2733627D02*
X-17451D01*
Y2731227D01*
X-18051Y2730427D01*
X-18751Y2729894D01*
X-19751Y2729627D01*
X-20751Y2729894D01*
X-21451Y2730427D01*
X-22051Y2731227D01*
X-22451Y2732160D01*
X-22651Y2733227D01*
Y2734160D01*
X-22451Y2734960D01*
X-22051Y2735894D01*
X-21451Y2736694D01*
X-20851Y2737227D01*
X-20051Y2737627D01*
X-19351D01*
X-18551Y2737360D01*
X-17951Y2736827D01*
G01X-6551Y2729627D02*
X-4051Y2737627D01*
X-1551Y2729627D01*
G01X-2451Y2732427D02*
X-5651D01*
G01X1649Y2729627D02*
Y2737627D01*
X6249Y2729627D01*
Y2737627D01*
G01X9749Y2729627D02*
Y2737627D01*
X11749D01*
X12549Y2737227D01*
X13149Y2736694D01*
X13649Y2735894D01*
X14049Y2734960D01*
X14149Y2733627D01*
X14049Y2732294D01*
X13649Y2731360D01*
X13149Y2730560D01*
X12549Y2730027D01*
X11749Y2729627D01*
X9749D01*
G01X25349D02*
Y2737627D01*
X27949Y2730960D01*
X30549Y2737627D01*
Y2729627D01*
G01X33449D02*
X35949Y2737627D01*
X38449Y2729627D01*
G01X37549Y2732427D02*
X34349D01*
G01X43949Y2737627D02*
Y2729627D01*
G01X41649Y2737627D02*
X46249D01*
G01X53949Y2729627D02*
X49949D01*
Y2737627D01*
X53949D01*
G01X52349Y2733760D02*
X49949D01*
G01X57949Y2729627D02*
Y2737627D01*
X60449D01*
X61249Y2737227D01*
X61749Y2736694D01*
X61949Y2735627D01*
X61749Y2734560D01*
X61149Y2733894D01*
X60449Y2733494D01*
X57949D01*
G01X60449D02*
X61949Y2729627D01*
G01X66749Y2737627D02*
X69149D01*
G01X67949D02*
Y2729627D01*
G01X66749D02*
X69149D01*
G01X73449D02*
X75949Y2737627D01*
X78449Y2729627D01*
G01X77549Y2732427D02*
X74349D01*
G01X81949Y2737627D02*
Y2729627D01*
X85949D01*
G01X97749D02*
Y2737627D01*
X99749D01*
X100549Y2737227D01*
X101149Y2736694D01*
X101649Y2735894D01*
X102049Y2734960D01*
X102149Y2733627D01*
X102049Y2732294D01*
X101649Y2731360D01*
X101149Y2730560D01*
X100549Y2730027D01*
X99749Y2729627D01*
X97749D01*
G01X106749Y2737627D02*
X109149D01*
G01X107949D02*
Y2729627D01*
G01X106749D02*
X109149D01*
G01X117949D02*
X113949D01*
Y2737627D01*
X117949D01*
G01X116349Y2733760D02*
X113949D01*
G01X121949Y2737627D02*
Y2729627D01*
X125949D01*
G01X133949D02*
X129949D01*
Y2737627D01*
X133949D01*
G01X132349Y2733760D02*
X129949D01*
G01X142149Y2736960D02*
X141549Y2737360D01*
X140849Y2737627D01*
X140049D01*
X139149Y2737227D01*
X138449Y2736560D01*
X137949Y2735760D01*
X137549Y2734427D01*
X137449Y2733227D01*
X137649Y2732027D01*
X137949Y2731227D01*
X138549Y2730427D01*
X139249Y2729894D01*
X139949Y2729627D01*
X140649D01*
X141349Y2729894D01*
X141949Y2730294D01*
X142449Y2730827D01*
G01X147949Y2737627D02*
Y2729627D01*
G01X145649Y2737627D02*
X150249D01*
G01X153949Y2729627D02*
Y2737627D01*
X156449D01*
X157249Y2737227D01*
X157749Y2736694D01*
X157949Y2735627D01*
X157749Y2734560D01*
X157149Y2733894D01*
X156449Y2733494D01*
X153949D01*
G01X156449D02*
X157949Y2729627D01*
G01X162749Y2737627D02*
X165149D01*
G01X163949D02*
Y2729627D01*
G01X162749D02*
X165149D01*
G01X174149Y2736960D02*
X173549Y2737360D01*
X172849Y2737627D01*
X172049D01*
X171149Y2737227D01*
X170449Y2736560D01*
X169949Y2735760D01*
X169549Y2734427D01*
X169449Y2733227D01*
X169649Y2732027D01*
X169949Y2731227D01*
X170549Y2730427D01*
X171249Y2729894D01*
X171949Y2729627D01*
X172649D01*
X173349Y2729894D01*
X173949Y2730294D01*
X174449Y2730827D01*
G01X190149Y2736960D02*
X189549Y2737360D01*
X188849Y2737627D01*
X188049D01*
X187149Y2737227D01*
X186449Y2736560D01*
X185949Y2735760D01*
X185549Y2734427D01*
X185449Y2733227D01*
X185649Y2732027D01*
X185949Y2731227D01*
X186549Y2730427D01*
X187249Y2729894D01*
X187949Y2729627D01*
X188649D01*
X189349Y2729894D01*
X189949Y2730294D01*
X190449Y2730827D01*
G01X195949Y2729627D02*
X195149Y2729760D01*
X194449Y2730294D01*
X193849Y2731094D01*
X193449Y2732027D01*
X193249Y2733094D01*
Y2734160D01*
X193449Y2735227D01*
X193849Y2736160D01*
X194449Y2736960D01*
X195149Y2737494D01*
X195949Y2737627D01*
X196749Y2737494D01*
X197449Y2736960D01*
X198049Y2736160D01*
X198449Y2735227D01*
X198649Y2734160D01*
Y2733094D01*
X198449Y2732027D01*
X198049Y2731094D01*
X197449Y2730294D01*
X196749Y2729760D01*
X195949Y2729627D01*
G01X201649D02*
Y2737627D01*
X206249Y2729627D01*
Y2737627D01*
G01X209849Y2730693D02*
X210649Y2730027D01*
X211549Y2729627D01*
X212349D01*
X213149Y2730027D01*
X213749Y2730693D01*
X214049Y2731627D01*
X213849Y2732560D01*
X213349Y2733360D01*
X212449Y2733894D01*
X211249Y2734160D01*
X210549Y2734694D01*
X210249Y2735627D01*
X210449Y2736560D01*
X210949Y2737227D01*
X211649Y2737627D01*
X212349D01*
X213049Y2737360D01*
X213649Y2736694D01*
G01X219949Y2737627D02*
Y2729627D01*
G01X217649Y2737627D02*
X222249D01*
G01X225449Y2729627D02*
X227949Y2737627D01*
X230449Y2729627D01*
G01X229549Y2732427D02*
X226349D01*
G01X233649Y2729627D02*
Y2737627D01*
X238249Y2729627D01*
Y2737627D01*
G01X243949D02*
Y2729627D01*
G01X241649Y2737627D02*
X246249D01*
G01X259949D02*
Y2729627D01*
G01X257649Y2737627D02*
X262249D01*
G01X267949Y2729627D02*
X267149Y2729760D01*
X266449Y2730294D01*
X265849Y2731094D01*
X265449Y2732027D01*
X265249Y2733094D01*
Y2734160D01*
X265449Y2735227D01*
X265849Y2736160D01*
X266449Y2736960D01*
X267149Y2737494D01*
X267949Y2737627D01*
X268749Y2737494D01*
X269449Y2736960D01*
X270049Y2736160D01*
X270449Y2735227D01*
X270649Y2734160D01*
Y2733094D01*
X270449Y2732027D01*
X270049Y2731094D01*
X269449Y2730294D01*
X268749Y2729760D01*
X267949Y2729627D01*
G01X281449D02*
X283949Y2737627D01*
X286449Y2729627D01*
G01X285549Y2732427D02*
X282349D01*
G01X294149Y2736960D02*
X293549Y2737360D01*
X292849Y2737627D01*
X292049D01*
X291149Y2737227D01*
X290449Y2736560D01*
X289949Y2735760D01*
X289549Y2734427D01*
X289449Y2733227D01*
X289649Y2732027D01*
X289949Y2731227D01*
X290549Y2730427D01*
X291249Y2729894D01*
X291949Y2729627D01*
X292649D01*
X293349Y2729894D01*
X293949Y2730294D01*
X294449Y2730827D01*
G01X297849Y2729627D02*
Y2737627D01*
G01X302049D02*
Y2729627D01*
G01Y2733627D02*
X297849D01*
G01X306749Y2737627D02*
X309149D01*
G01X307949D02*
Y2729627D01*
G01X306749D02*
X309149D01*
G01X317949D02*
X313949D01*
Y2737627D01*
X317949D01*
G01X316349Y2733760D02*
X313949D01*
G01X321449Y2737627D02*
X323949Y2729627D01*
X326449Y2737627D01*
G01X333949Y2729627D02*
X329949D01*
Y2737627D01*
X333949D01*
G01X332349Y2733760D02*
X329949D01*
G01X345949Y2729627D02*
Y2737627D01*
X348449D01*
X349249Y2737227D01*
X349749Y2736694D01*
X349949Y2735627D01*
X349749Y2734560D01*
X349149Y2733894D01*
X348449Y2733494D01*
X345949D01*
G01X348449D02*
X349949Y2729627D01*
G01X357949D02*
X353949D01*
Y2737627D01*
X357949D01*
G01X356349Y2733760D02*
X353949D01*
G01X363949Y2729627D02*
X363149Y2729760D01*
X362449Y2730294D01*
X361849Y2731094D01*
X361449Y2732027D01*
X361249Y2733094D01*
Y2734160D01*
X361449Y2735227D01*
X361849Y2736160D01*
X362449Y2736960D01*
X363149Y2737494D01*
X363949Y2737627D01*
X364749Y2737494D01*
X365449Y2736960D01*
X366049Y2736160D01*
X366449Y2735227D01*
X366649Y2734160D01*
Y2733094D01*
X366449Y2732027D01*
X366049Y2731094D01*
X365449Y2730294D01*
X364749Y2729760D01*
X363949Y2729627D01*
G01X364749Y2731760D02*
X365949Y2729627D01*
G01X369749Y2737627D02*
Y2731894D01*
X370149Y2730693D01*
X370949Y2729894D01*
X371949Y2729627D01*
X372949Y2729894D01*
X373749Y2730693D01*
X374149Y2731894D01*
Y2737627D01*
G01X378749D02*
X381149D01*
G01X379949D02*
Y2729627D01*
G01X378749D02*
X381149D01*
G01X385949D02*
Y2737627D01*
X388449D01*
X389249Y2737227D01*
X389749Y2736694D01*
X389949Y2735627D01*
X389749Y2734560D01*
X389149Y2733894D01*
X388449Y2733494D01*
X385949D01*
G01X388449D02*
X389949Y2729627D01*
G01X397949D02*
X393949D01*
Y2737627D01*
X397949D01*
G01X396349Y2733760D02*
X393949D01*
G01X401749Y2729627D02*
Y2737627D01*
X403749D01*
X404549Y2737227D01*
X405149Y2736694D01*
X405649Y2735894D01*
X406049Y2734960D01*
X406149Y2733627D01*
X406049Y2732294D01*
X405649Y2731360D01*
X405149Y2730560D01*
X404549Y2730027D01*
X403749Y2729627D01*
X401749D01*
G01X-65851Y2751960D02*
X-66451Y2752360D01*
X-67151Y2752627D01*
X-67951D01*
X-68851Y2752227D01*
X-69551Y2751560D01*
X-70051Y2750760D01*
X-70451Y2749427D01*
X-70551Y2748227D01*
X-70351Y2747027D01*
X-70051Y2746227D01*
X-69451Y2745427D01*
X-68751Y2744894D01*
X-68051Y2744627D01*
X-67351D01*
X-66651Y2744894D01*
X-66051Y2745294D01*
X-65551Y2745827D01*
G01X-62151Y2744627D02*
Y2752627D01*
G01X-57951D02*
Y2744627D01*
G01Y2748627D02*
X-62151D01*
G01X-54551Y2744627D02*
X-52051Y2752627D01*
X-49551Y2744627D01*
G01X-50451Y2747427D02*
X-53651D01*
G01X-46051Y2744627D02*
Y2752627D01*
X-43551D01*
X-42751Y2752227D01*
X-42251Y2751694D01*
X-42051Y2750627D01*
X-42251Y2749560D01*
X-42851Y2748894D01*
X-43551Y2748494D01*
X-46051D01*
G01X-43551D02*
X-42051Y2744627D01*
G01X-36051Y2752627D02*
Y2744627D01*
G01X-38351Y2752627D02*
X-33751D01*
G01X-28051Y2744360D02*
X-28251Y2744494D01*
Y2744760D01*
X-28051Y2744894D01*
X-27851Y2744760D01*
Y2744494D01*
X-28051Y2744360D01*
G01X-14651Y2744627D02*
Y2752627D01*
X-12051Y2745960D01*
X-9451Y2752627D01*
Y2744627D01*
G01X-6551D02*
X-4051Y2752627D01*
X-1551Y2744627D01*
G01X-2451Y2747427D02*
X-5651D01*
G01X1649Y2744627D02*
Y2752627D01*
X6249Y2744627D01*
Y2752627D01*
G01X9749D02*
Y2746894D01*
X10149Y2745693D01*
X10949Y2744894D01*
X11949Y2744627D01*
X12949Y2744894D01*
X13749Y2745693D01*
X14149Y2746894D01*
Y2752627D01*
G01X18049Y2744627D02*
Y2752627D01*
X21849D01*
G01X20449Y2748760D02*
X18049D01*
G01X25449Y2744627D02*
X27949Y2752627D01*
X30449Y2744627D01*
G01X29549Y2747427D02*
X26349D01*
G01X38149Y2751960D02*
X37549Y2752360D01*
X36849Y2752627D01*
X36049D01*
X35149Y2752227D01*
X34449Y2751560D01*
X33949Y2750760D01*
X33549Y2749427D01*
X33449Y2748227D01*
X33649Y2747027D01*
X33949Y2746227D01*
X34549Y2745427D01*
X35249Y2744894D01*
X35949Y2744627D01*
X36649D01*
X37349Y2744894D01*
X37949Y2745294D01*
X38449Y2745827D01*
G01X43949Y2752627D02*
Y2744627D01*
G01X41649Y2752627D02*
X46249D01*
G01X49749D02*
Y2746894D01*
X50149Y2745693D01*
X50949Y2744894D01*
X51949Y2744627D01*
X52949Y2744894D01*
X53749Y2745693D01*
X54149Y2746894D01*
Y2752627D01*
G01X57949Y2744627D02*
Y2752627D01*
X60449D01*
X61249Y2752227D01*
X61749Y2751694D01*
X61949Y2750627D01*
X61749Y2749560D01*
X61149Y2748894D01*
X60449Y2748494D01*
X57949D01*
G01X60449D02*
X61949Y2744627D01*
G01X69949D02*
X65949D01*
Y2752627D01*
X69949D01*
G01X68349Y2748760D02*
X65949D01*
G01X73949Y2744627D02*
Y2752627D01*
X76449D01*
X77249Y2752227D01*
X77749Y2751694D01*
X77949Y2750627D01*
X77749Y2749560D01*
X77149Y2748894D01*
X76449Y2748494D01*
X73949D01*
G01X76449D02*
X77949Y2744627D01*
G01X90749Y2752627D02*
X93149D01*
G01X91949D02*
Y2744627D01*
G01X90749D02*
X93149D01*
G01X97849Y2745693D02*
X98649Y2745027D01*
X99549Y2744627D01*
X100349D01*
X101149Y2745027D01*
X101749Y2745693D01*
X102049Y2746627D01*
X101849Y2747560D01*
X101349Y2748360D01*
X100449Y2748894D01*
X99249Y2749160D01*
X98549Y2749694D01*
X98249Y2750627D01*
X98449Y2751560D01*
X98949Y2752227D01*
X99649Y2752627D01*
X100349D01*
X101049Y2752360D01*
X101649Y2751694D01*
G01X114049Y2744627D02*
Y2752627D01*
X117849D01*
G01X116449Y2748760D02*
X114049D01*
G01X121949Y2744627D02*
Y2752627D01*
X124449D01*
X125249Y2752227D01*
X125749Y2751694D01*
X125949Y2750627D01*
X125749Y2749560D01*
X125149Y2748894D01*
X124449Y2748494D01*
X121949D01*
G01X124449D02*
X125949Y2744627D01*
G01X133949D02*
X129949D01*
Y2752627D01*
X133949D01*
G01X132349Y2748760D02*
X129949D01*
G01X141949Y2744627D02*
X137949D01*
Y2752627D01*
X141949D01*
G01X140349Y2748760D02*
X137949D01*
G01X155949Y2752627D02*
Y2744627D01*
G01X153649Y2752627D02*
X158249D01*
G01X163949Y2744627D02*
X163149Y2744760D01*
X162449Y2745294D01*
X161849Y2746094D01*
X161449Y2747027D01*
X161249Y2748094D01*
Y2749160D01*
X161449Y2750227D01*
X161849Y2751160D01*
X162449Y2751960D01*
X163149Y2752494D01*
X163949Y2752627D01*
X164749Y2752494D01*
X165449Y2751960D01*
X166049Y2751160D01*
X166449Y2750227D01*
X166649Y2749160D01*
Y2748094D01*
X166449Y2747027D01*
X166049Y2746094D01*
X165449Y2745294D01*
X164749Y2744760D01*
X163949Y2744627D01*
G01X177449D02*
X179949Y2752627D01*
X182449Y2744627D01*
G01X181549Y2747427D02*
X178349D01*
G01X185749Y2744627D02*
Y2752627D01*
X187749D01*
X188549Y2752227D01*
X189149Y2751694D01*
X189649Y2750894D01*
X190049Y2749960D01*
X190149Y2748627D01*
X190049Y2747294D01*
X189649Y2746360D01*
X189149Y2745560D01*
X188549Y2745027D01*
X187749Y2744627D01*
X185749D01*
G01X193949Y2746227D02*
X194449Y2745427D01*
X195049Y2744894D01*
X195749Y2744627D01*
X196549Y2744894D01*
X197149Y2745427D01*
X197749Y2746227D01*
X197949Y2747294D01*
Y2752627D01*
G01X201749D02*
Y2746894D01*
X202149Y2745693D01*
X202949Y2744894D01*
X203949Y2744627D01*
X204949Y2744894D01*
X205749Y2745693D01*
X206149Y2746894D01*
Y2752627D01*
G01X209849Y2745693D02*
X210649Y2745027D01*
X211549Y2744627D01*
X212349D01*
X213149Y2745027D01*
X213749Y2745693D01*
X214049Y2746627D01*
X213849Y2747560D01*
X213349Y2748360D01*
X212449Y2748894D01*
X211249Y2749160D01*
X210549Y2749694D01*
X210249Y2750627D01*
X210449Y2751560D01*
X210949Y2752227D01*
X211649Y2752627D01*
X212349D01*
X213049Y2752360D01*
X213649Y2751694D01*
G01X219949Y2752627D02*
Y2744627D01*
G01X217649Y2752627D02*
X222249D01*
G01X235949D02*
Y2744627D01*
G01X233649Y2752627D02*
X238249D01*
G01X241949Y2744627D02*
Y2752627D01*
X244449D01*
X245249Y2752227D01*
X245749Y2751694D01*
X245949Y2750627D01*
X245749Y2749560D01*
X245149Y2748894D01*
X244449Y2748494D01*
X241949D01*
G01X244449D02*
X245949Y2744627D01*
G01X249449D02*
X251949Y2752627D01*
X254449Y2744627D01*
G01X253549Y2747427D02*
X250349D01*
G01X262149Y2751960D02*
X261549Y2752360D01*
X260849Y2752627D01*
X260049D01*
X259149Y2752227D01*
X258449Y2751560D01*
X257949Y2750760D01*
X257549Y2749427D01*
X257449Y2748227D01*
X257649Y2747027D01*
X257949Y2746227D01*
X258549Y2745427D01*
X259249Y2744894D01*
X259949Y2744627D01*
X260649D01*
X261349Y2744894D01*
X261949Y2745294D01*
X262449Y2745827D01*
G01X269949Y2744627D02*
X265949D01*
Y2752627D01*
X269949D01*
G01X268349Y2748760D02*
X265949D01*
G01X280949Y2752627D02*
X282349Y2744627D01*
X283949Y2752627D01*
X285549Y2744627D01*
X286949Y2752627D01*
G01X290749D02*
X293149D01*
G01X291949D02*
Y2744627D01*
G01X290749D02*
X293149D01*
G01X297749D02*
Y2752627D01*
X299749D01*
X300549Y2752227D01*
X301149Y2751694D01*
X301649Y2750894D01*
X302049Y2749960D01*
X302149Y2748627D01*
X302049Y2747294D01*
X301649Y2746360D01*
X301149Y2745560D01*
X300549Y2745027D01*
X299749Y2744627D01*
X297749D01*
G01X307949Y2752627D02*
Y2744627D01*
G01X305649Y2752627D02*
X310249D01*
G01X313849Y2744627D02*
Y2752627D01*
G01X318049D02*
Y2744627D01*
G01Y2748627D02*
X313849D01*
G01X321849Y2745693D02*
X322649Y2745027D01*
X323549Y2744627D01*
X324349D01*
X325149Y2745027D01*
X325749Y2745693D01*
X326049Y2746627D01*
X325849Y2747560D01*
X325349Y2748360D01*
X324449Y2748894D01*
X323249Y2749160D01*
X322549Y2749694D01*
X322249Y2750627D01*
X322449Y2751560D01*
X322949Y2752227D01*
X323649Y2752627D01*
X324349D01*
X325049Y2752360D01*
X325649Y2751694D01*
G01X331749Y2743160D02*
X332149Y2744894D01*
G01X353749Y2744627D02*
Y2752627D01*
X355749D01*
X356549Y2752227D01*
X357149Y2751694D01*
X357649Y2750894D01*
X358049Y2749960D01*
X358149Y2748627D01*
X358049Y2747294D01*
X357649Y2746360D01*
X357149Y2745560D01*
X356549Y2745027D01*
X355749Y2744627D01*
X353749D01*
G01X362749Y2752627D02*
X365149D01*
G01X363949D02*
Y2744627D01*
G01X362749D02*
X365149D01*
G01X373949D02*
X369949D01*
Y2752627D01*
X373949D01*
G01X372349Y2748760D02*
X369949D01*
G01X377949Y2752627D02*
Y2744627D01*
X381949D01*
G01X389949D02*
X385949D01*
Y2752627D01*
X389949D01*
G01X388349Y2748760D02*
X385949D01*
G01X398149Y2751960D02*
X397549Y2752360D01*
X396849Y2752627D01*
X396049D01*
X395149Y2752227D01*
X394449Y2751560D01*
X393949Y2750760D01*
X393549Y2749427D01*
X393449Y2748227D01*
X393649Y2747027D01*
X393949Y2746227D01*
X394549Y2745427D01*
X395249Y2744894D01*
X395949Y2744627D01*
X396649D01*
X397349Y2744894D01*
X397949Y2745294D01*
X398449Y2745827D01*
G01X403949Y2752627D02*
Y2744627D01*
G01X401649Y2752627D02*
X406249D01*
G01X409949Y2744627D02*
Y2752627D01*
X412449D01*
X413249Y2752227D01*
X413749Y2751694D01*
X413949Y2750627D01*
X413749Y2749560D01*
X413149Y2748894D01*
X412449Y2748494D01*
X409949D01*
G01X412449D02*
X413949Y2744627D01*
G01X418749Y2752627D02*
X421149D01*
G01X419949D02*
Y2744627D01*
G01X418749D02*
X421149D01*
G01X430149Y2751960D02*
X429549Y2752360D01*
X428849Y2752627D01*
X428049D01*
X427149Y2752227D01*
X426449Y2751560D01*
X425949Y2750760D01*
X425549Y2749427D01*
X425449Y2748227D01*
X425649Y2747027D01*
X425949Y2746227D01*
X426549Y2745427D01*
X427249Y2744894D01*
X427949Y2744627D01*
X428649D01*
X429349Y2744894D01*
X429949Y2745294D01*
X430449Y2745827D01*
G01X-3000Y0D02*
X-36584D01*
G01X51979Y70500D02*
X-35667D01*
G01X62354Y114960D02*
X-35948D01*
G01X51979Y206500D02*
X-27048D01*
G01X19480Y340460D02*
X-34943D01*
G01X62354Y464960D02*
X-44032D01*
G01X52254Y554500D02*
X-28866D01*
G01X62354Y814960D02*
X-28537D01*
G01X17472Y1054606D02*
X-37868D01*
G01X17472Y1342598D02*
X-39084D01*
G01X19756Y1960629D02*
X-24505D01*
G01X-4000Y-62500D02*
Y-137500D01*
X496000D01*
Y-62500D01*
X-4000D01*
G01X0Y-3000D02*
Y-26333D01*
G01X397638Y0D02*
G03X405512Y7874I0J7874D01*
G01Y2078740D01*
G03X397638Y2086614I-7874J0D01*
G01X104331D01*
G03X98425Y2080709I-1J-5905D01*
G01Y2076772D01*
G02X92520Y2070866I-5906J0D01*
G01X5906D01*
G03X0Y2064961I-1J-5905D01*
G01Y21654D01*
G03X5906Y15748I5906J0D01*
G01X92520D01*
G02X98425Y9843I0J-5905D01*
G01Y5906D01*
G03X104331Y0I5906J0D01*
G01X397638D01*
G01X19756Y125629D02*
X-20060D01*
G01X51979Y279500D02*
X-22491D01*
G01X51979Y415500D02*
X-22187D01*
G01X62354Y1164960D02*
X-20335D01*
G01X62354Y1514960D02*
X-20687D01*
G01X52254Y1612504D02*
X-19036D01*
G01X42056Y1817693D02*
X-9922D01*
G01X62354Y1864961D02*
X-21346D01*
G01X19756Y1878630D02*
X-23290D01*
G01X19756Y2035629D02*
X-20860D01*
G01X0Y2087001D02*
Y2215647D01*
G01X160307Y2212647D02*
X0D01*
G01X5000Y2213647D02*
X0Y2212647D01*
X5000Y2211647D01*
Y2213647D01*
G01X24783Y2304560D02*
X-6713D01*
G01D02*
X34626D01*
G01X5098Y2374442D02*
G03I-2953J0D01*
G01X-14587D02*
G03I-2953J0D01*
G01X5098Y2394127D02*
G03I-2953J0D01*
G01X-14587D02*
G03I-2953J0D01*
G01X-20492Y2436449D02*
X554311D01*
G01X-20492Y2452197D02*
Y2436449D01*
G01Y2456134D02*
X554311D01*
G01Y2452197D02*
X-20492D01*
G01Y2471883D02*
Y2456134D01*
G01X554311Y2471883D02*
X-20492D01*
G01Y2475820D02*
Y2546686D01*
G01Y2538812D02*
X274783D01*
G01X8000Y-127500D02*
Y-132500D01*
G01X6543Y-127500D02*
X9457D01*
G01X14367Y-132500D02*
X11833D01*
Y-127500D01*
X14367D01*
G01X13353Y-129917D02*
X11833D01*
G01X16933Y-127500D02*
Y-132500D01*
X19467D01*
G01X23300Y-132667D02*
X23173Y-132583D01*
Y-132417D01*
X23300Y-132333D01*
X23427Y-132417D01*
Y-132583D01*
X23300Y-132667D01*
G01Y-130417D02*
X23173Y-130333D01*
Y-130167D01*
X23300Y-130083D01*
X23427Y-130167D01*
Y-130333D01*
X23300Y-130417D01*
G01X28083Y-134167D02*
X27450Y-133333D01*
X27133Y-132500D01*
Y-129167D01*
X27450Y-128333D01*
X28083Y-127500D01*
G01X33500D02*
X32993Y-127667D01*
X32613Y-128083D01*
X32360Y-128583D01*
X32170Y-129250D01*
X32107Y-130000D01*
X32170Y-130750D01*
X32360Y-131417D01*
X32613Y-131917D01*
X32993Y-132333D01*
X33500Y-132500D01*
X34007Y-132333D01*
X34387Y-131917D01*
X34640Y-131417D01*
X34830Y-130750D01*
X34893Y-130000D01*
X34830Y-129250D01*
X34640Y-128583D01*
X34387Y-128083D01*
X34007Y-127667D01*
X33500Y-127500D01*
G01X37207Y-131500D02*
X37587Y-132083D01*
X38093Y-132417D01*
X38663Y-132500D01*
X39170Y-132417D01*
X39677Y-132000D01*
X39993Y-131500D01*
X40057Y-131000D01*
X39930Y-130417D01*
X39487Y-130000D01*
X39043Y-129833D01*
X38473D01*
G01X39043D02*
X39423Y-129583D01*
X39740Y-129167D01*
X39867Y-128667D01*
X39740Y-128167D01*
X39423Y-127750D01*
X38853Y-127500D01*
X38283Y-127583D01*
X37713Y-127917D01*
G01X44017Y-134167D02*
X44650Y-133333D01*
X44967Y-132500D01*
Y-129167D01*
X44650Y-128333D01*
X44017Y-127500D01*
G01X47407Y-131500D02*
X47787Y-132083D01*
X48293Y-132417D01*
X48863Y-132500D01*
X49370Y-132417D01*
X49877Y-132000D01*
X50193Y-131500D01*
X50257Y-131000D01*
X50130Y-130417D01*
X49687Y-130000D01*
X49243Y-129833D01*
X48673D01*
G01X49243D02*
X49623Y-129583D01*
X49940Y-129167D01*
X50067Y-128667D01*
X49940Y-128167D01*
X49623Y-127750D01*
X49053Y-127500D01*
X48483Y-127583D01*
X47913Y-127917D01*
G01X52697Y-128333D02*
X53077Y-127833D01*
X53520Y-127583D01*
X54027Y-127500D01*
X54660Y-127667D01*
X55103Y-128083D01*
X55230Y-128583D01*
X55167Y-129083D01*
X54913Y-129500D01*
X53647Y-130333D01*
X53077Y-130917D01*
X52697Y-131750D01*
X52570Y-132500D01*
X55230D01*
G01X58873D02*
X59000Y-131417D01*
X59190Y-130500D01*
X59443Y-129667D01*
X59760Y-128750D01*
X60267Y-127500D01*
X57733D01*
G01X63277Y-130833D02*
X64923D01*
G01X67997Y-128333D02*
X68377Y-127833D01*
X68820Y-127583D01*
X69327Y-127500D01*
X69960Y-127667D01*
X70403Y-128083D01*
X70530Y-128583D01*
X70467Y-129083D01*
X70213Y-129500D01*
X68947Y-130333D01*
X68377Y-130917D01*
X67997Y-131750D01*
X67870Y-132500D01*
X70530D01*
G01X72907Y-131500D02*
X73287Y-132083D01*
X73793Y-132417D01*
X74363Y-132500D01*
X74870Y-132417D01*
X75377Y-132000D01*
X75693Y-131500D01*
X75757Y-131000D01*
X75630Y-130417D01*
X75187Y-130000D01*
X74743Y-129833D01*
X74173D01*
G01X74743D02*
X75123Y-129583D01*
X75440Y-129167D01*
X75567Y-128667D01*
X75440Y-128167D01*
X75123Y-127750D01*
X74553Y-127500D01*
X73983Y-127583D01*
X73413Y-127917D01*
G01X80160Y-132500D02*
Y-127500D01*
X77817Y-131083D01*
X80983D01*
G01X83107Y-131750D02*
X83487Y-132167D01*
X83930Y-132417D01*
X84500Y-132500D01*
X85070Y-132333D01*
X85513Y-132000D01*
X85830Y-131417D01*
X85893Y-130750D01*
X85767Y-130083D01*
X85450Y-129667D01*
X85007Y-129333D01*
X84563Y-129250D01*
X84120Y-129333D01*
X83550Y-129667D01*
X83740Y-127500D01*
X85450D01*
G01X93497Y-132500D02*
Y-127500D01*
X95903D01*
G01X95017Y-129917D02*
X93497D01*
G01X98217Y-132500D02*
X99800Y-127500D01*
X101383Y-132500D01*
G01X100813Y-130750D02*
X98787D01*
G01X103570Y-132500D02*
X106230Y-127500D01*
G01X103570D02*
X106230Y-132500D01*
G01X110000Y-132667D02*
X109873Y-132583D01*
Y-132417D01*
X110000Y-132333D01*
X110127Y-132417D01*
Y-132583D01*
X110000Y-132667D01*
G01Y-130417D02*
X109873Y-130333D01*
Y-130167D01*
X110000Y-130083D01*
X110127Y-130167D01*
Y-130333D01*
X110000Y-130417D01*
G01X114783Y-134167D02*
X114150Y-133333D01*
X113833Y-132500D01*
Y-129167D01*
X114150Y-128333D01*
X114783Y-127500D01*
G01X120200D02*
X119693Y-127667D01*
X119313Y-128083D01*
X119060Y-128583D01*
X118870Y-129250D01*
X118807Y-130000D01*
X118870Y-130750D01*
X119060Y-131417D01*
X119313Y-131917D01*
X119693Y-132333D01*
X120200Y-132500D01*
X120707Y-132333D01*
X121087Y-131917D01*
X121340Y-131417D01*
X121530Y-130750D01*
X121593Y-130000D01*
X121530Y-129250D01*
X121340Y-128583D01*
X121087Y-128083D01*
X120707Y-127667D01*
X120200Y-127500D01*
G01X123907Y-131500D02*
X124287Y-132083D01*
X124793Y-132417D01*
X125363Y-132500D01*
X125870Y-132417D01*
X126377Y-132000D01*
X126693Y-131500D01*
X126757Y-131000D01*
X126630Y-130417D01*
X126187Y-130000D01*
X125743Y-129833D01*
X125173D01*
G01X125743D02*
X126123Y-129583D01*
X126440Y-129167D01*
X126567Y-128667D01*
X126440Y-128167D01*
X126123Y-127750D01*
X125553Y-127500D01*
X124983Y-127583D01*
X124413Y-127917D01*
G01X130717Y-134167D02*
X131350Y-133333D01*
X131667Y-132500D01*
Y-129167D01*
X131350Y-128333D01*
X130717Y-127500D01*
G01X134107Y-131500D02*
X134487Y-132083D01*
X134993Y-132417D01*
X135563Y-132500D01*
X136070Y-132417D01*
X136577Y-132000D01*
X136893Y-131500D01*
X136957Y-131000D01*
X136830Y-130417D01*
X136387Y-130000D01*
X135943Y-129833D01*
X135373D01*
G01X135943D02*
X136323Y-129583D01*
X136640Y-129167D01*
X136767Y-128667D01*
X136640Y-128167D01*
X136323Y-127750D01*
X135753Y-127500D01*
X135183Y-127583D01*
X134613Y-127917D01*
G01X139523Y-131917D02*
X139967Y-132333D01*
X140473Y-132500D01*
X140980Y-132333D01*
X141423Y-131833D01*
X141740Y-131083D01*
X141867Y-130333D01*
Y-129417D01*
X141740Y-128667D01*
X141423Y-128000D01*
X141043Y-127667D01*
X140600Y-127500D01*
X140093Y-127667D01*
X139713Y-128000D01*
X139460Y-128500D01*
X139333Y-129167D01*
X139460Y-129750D01*
X139777Y-130333D01*
X140157Y-130667D01*
X140600Y-130750D01*
X141107Y-130583D01*
X141487Y-130167D01*
X141867Y-129417D01*
G01X145573Y-132500D02*
X145700Y-131417D01*
X145890Y-130500D01*
X146143Y-129667D01*
X146460Y-128750D01*
X146967Y-127500D01*
X144433D01*
G01X149977Y-130833D02*
X151623D01*
G01X154507Y-131500D02*
X154887Y-132083D01*
X155393Y-132417D01*
X155963Y-132500D01*
X156470Y-132417D01*
X156977Y-132000D01*
X157293Y-131500D01*
X157357Y-131000D01*
X157230Y-130417D01*
X156787Y-130000D01*
X156343Y-129833D01*
X155773D01*
G01X156343D02*
X156723Y-129583D01*
X157040Y-129167D01*
X157167Y-128667D01*
X157040Y-128167D01*
X156723Y-127750D01*
X156153Y-127500D01*
X155583Y-127583D01*
X155013Y-127917D01*
G01X159797Y-130417D02*
X160240Y-129833D01*
X160620Y-129500D01*
X161127Y-129333D01*
X161570Y-129500D01*
X161887Y-129833D01*
X162140Y-130333D01*
X162203Y-130917D01*
X162140Y-131417D01*
X161887Y-131917D01*
X161507Y-132333D01*
X161063Y-132500D01*
X160557Y-132333D01*
X160113Y-131833D01*
X159860Y-131083D01*
X159797Y-130250D01*
X159923Y-129167D01*
X160113Y-128583D01*
X160430Y-128000D01*
X160873Y-127583D01*
X161317Y-127500D01*
X161760Y-127667D01*
X162077Y-128083D01*
G01X166100Y-132500D02*
Y-127500D01*
X165340Y-128500D01*
G01Y-132500D02*
X166860D01*
G01X171960D02*
Y-127500D01*
X169617Y-131083D01*
X172783D01*
G01X22756Y2032629D02*
Y9190D01*
X30106Y-159D01*
G01X20472Y1339598D02*
Y-4178D01*
G01X17139Y2285802D02*
X18069Y2284760D01*
X19154Y2284135D01*
X20549Y2283927D01*
X21944Y2284344D01*
X23029Y2285177D01*
X23804Y2286635D01*
X23959Y2288302D01*
X23649Y2289969D01*
X22874Y2291010D01*
X21789Y2291844D01*
X20704Y2292052D01*
X19619Y2291844D01*
X18224Y2291010D01*
X18689Y2296427D01*
X22874D01*
G01X28919Y2283927D02*
Y2296427D01*
X32949Y2286010D01*
X36979Y2296427D01*
Y2283927D01*
G01X41319D02*
Y2296427D01*
X45349Y2286010D01*
X49379Y2296427D01*
Y2283927D01*
G01X24783Y2374442D02*
G03I-2953J0D01*
G01Y2394127D02*
G03I-2953J0D01*
G01X45056Y1820693D02*
Y2094525D01*
G01X75964Y2277001D02*
X44468D01*
G01D02*
X85807D01*
G01X24783Y2366940D02*
Y2296686D01*
G01X44468Y2367290D02*
Y2296686D01*
G01Y2304560D02*
X75964D01*
G01D02*
X34626D01*
G01X50374Y2371489D02*
X44468D01*
G01D02*
Y2377394D01*
G01Y2397079D02*
X50374D01*
G01Y2391174D02*
X44468D01*
G01Y2377394D02*
X50374D01*
G01X44468Y2391174D02*
Y2397079D01*
G01X54979Y412500D02*
Y-63690D01*
G01X65354Y1861961D02*
Y-13715D01*
G01X54979Y412500D02*
Y4972D01*
G01X55254Y557500D02*
Y2122478D01*
G01X70139Y2254402D02*
X71069Y2253360D01*
X72154Y2252735D01*
X73549Y2252527D01*
X74944Y2252944D01*
X76029Y2253777D01*
X76804Y2255235D01*
X76959Y2256902D01*
X76649Y2258569D01*
X75874Y2259610D01*
X74789Y2260444D01*
X73704Y2260652D01*
X72619Y2260444D01*
X71224Y2259610D01*
X71689Y2265027D01*
X75874D01*
G01X81919Y2252527D02*
Y2265027D01*
X85949Y2254610D01*
X89979Y2265027D01*
Y2252527D01*
G01X94319D02*
Y2265027D01*
X98349Y2254610D01*
X102379Y2265027D01*
Y2252527D01*
G01X95649Y2328702D02*
X64153D01*
G01D02*
X98602D01*
G01X75964Y2371489D02*
X70059D01*
G01D02*
Y2377394D01*
G01X50374D02*
Y2371489D01*
G01X70059Y2397079D02*
X75964D01*
G01Y2391174D02*
X70059D01*
G01Y2377394D02*
X75964D01*
G01X70059Y2391174D02*
Y2397079D01*
G01X50374D02*
Y2391174D01*
G01X95649Y2367552D02*
Y2269127D01*
G01Y2277001D02*
X127145D01*
G01D02*
X85807D01*
G01X75964Y2367552D02*
Y2269127D01*
G01X95649Y2363368D02*
Y2320828D01*
G01X101555Y2371489D02*
X95649D01*
G01D02*
Y2377394D01*
G01X75964D02*
Y2371489D01*
G01X95649Y2397079D02*
X101555D01*
G01Y2391174D02*
X95649D01*
G01Y2377394D02*
X101555D01*
G01X95649Y2391174D02*
Y2397079D01*
G01X75964D02*
Y2391174D01*
G01X98425Y2083709D02*
Y2101797D01*
G01X101555Y2366867D02*
Y2320828D01*
G01X125564Y2331655D02*
Y2344155D01*
X123704Y2341655D01*
G01Y2331655D02*
X127424D01*
G01X137964Y2331238D02*
X137654Y2331447D01*
Y2331863D01*
X137964Y2332072D01*
X138274Y2331863D01*
Y2331447D01*
X137964Y2331238D01*
G01X146954Y2333530D02*
X147884Y2332488D01*
X148969Y2331863D01*
X150364Y2331655D01*
X151759Y2332072D01*
X152844Y2332905D01*
X153619Y2334363D01*
X153774Y2336030D01*
X153464Y2337697D01*
X152689Y2338738D01*
X151604Y2339572D01*
X150519Y2339780D01*
X149434Y2339572D01*
X148039Y2338738D01*
X148504Y2344155D01*
X152689D01*
G01X158734Y2331655D02*
Y2344155D01*
X162764Y2333738D01*
X166794Y2344155D01*
Y2331655D01*
G01X171134D02*
Y2344155D01*
X175164Y2333738D01*
X179194Y2344155D01*
Y2331655D01*
G01X101555Y2328702D02*
X168081D01*
G01D02*
X98602D01*
G01X101555Y2377394D02*
Y2371489D01*
G01Y2397079D02*
Y2391174D01*
G01X105492D02*
X225222D01*
G01X105492Y2397079D02*
X225222D01*
G01X163385Y1949205D02*
Y-7534D01*
G01X166385Y27205D02*
X413331D01*
G01X166385Y202205D02*
X415082D01*
G01X166385Y377205D02*
X406998D01*
G01X166386Y552205D02*
X421650D01*
G01X166386Y727205D02*
X423150D01*
G01X166385Y902205D02*
X432935D01*
G01X166385Y1077205D02*
X417658D01*
G01X166385Y1252205D02*
X456059D01*
G01X166385Y1427205D02*
X443932D01*
G01X166385Y1602205D02*
X417978D01*
G01X166385Y1777205D02*
X445280D01*
G01X166385Y1952205D02*
X430122D01*
G01X169849Y2850693D02*
X170649Y2850027D01*
X171549Y2849627D01*
X172349D01*
X173149Y2850027D01*
X173749Y2850693D01*
X174049Y2851627D01*
X173849Y2852560D01*
X173349Y2853360D01*
X172449Y2853894D01*
X171249Y2854160D01*
X170549Y2854694D01*
X170249Y2855627D01*
X170449Y2856560D01*
X170949Y2857227D01*
X171649Y2857627D01*
X172349D01*
X173049Y2857360D01*
X173649Y2856694D01*
G01X179949Y2849627D02*
X179149Y2849760D01*
X178449Y2850294D01*
X177849Y2851094D01*
X177449Y2852027D01*
X177249Y2853094D01*
Y2854160D01*
X177449Y2855227D01*
X177849Y2856160D01*
X178449Y2856960D01*
X179149Y2857494D01*
X179949Y2857627D01*
X180749Y2857494D01*
X181449Y2856960D01*
X182049Y2856160D01*
X182449Y2855227D01*
X182649Y2854160D01*
Y2853094D01*
X182449Y2852027D01*
X182049Y2851094D01*
X181449Y2850294D01*
X180749Y2849760D01*
X179949Y2849627D01*
G01X185949Y2857627D02*
Y2849627D01*
X189949D01*
G01X193749D02*
Y2857627D01*
X195749D01*
X196549Y2857227D01*
X197149Y2856694D01*
X197649Y2855894D01*
X198049Y2854960D01*
X198149Y2853627D01*
X198049Y2852294D01*
X197649Y2851360D01*
X197149Y2850560D01*
X196549Y2850027D01*
X195749Y2849627D01*
X193749D01*
G01X205949D02*
X201949D01*
Y2857627D01*
X205949D01*
G01X204349Y2853760D02*
X201949D01*
G01X209949Y2849627D02*
Y2857627D01*
X212449D01*
X213249Y2857227D01*
X213749Y2856694D01*
X213949Y2855627D01*
X213749Y2854560D01*
X213149Y2853894D01*
X212449Y2853494D01*
X209949D01*
G01X212449D02*
X213949Y2849627D01*
G01X217349D02*
Y2857627D01*
X219949Y2850960D01*
X222549Y2857627D01*
Y2849627D01*
G01X225449D02*
X227949Y2857627D01*
X230449Y2849627D01*
G01X229549Y2852427D02*
X226349D01*
G01X233849Y2850693D02*
X234649Y2850027D01*
X235549Y2849627D01*
X236349D01*
X237149Y2850027D01*
X237749Y2850693D01*
X238049Y2851627D01*
X237849Y2852560D01*
X237349Y2853360D01*
X236449Y2853894D01*
X235249Y2854160D01*
X234549Y2854694D01*
X234249Y2855627D01*
X234449Y2856560D01*
X234949Y2857227D01*
X235649Y2857627D01*
X236349D01*
X237049Y2857360D01*
X237649Y2856694D01*
G01X241749Y2849627D02*
Y2857627D01*
G01X245549D02*
X241749Y2852693D01*
G01X246149Y2849627D02*
X243449Y2854960D01*
G01X259949Y2849627D02*
X259149Y2849760D01*
X258449Y2850294D01*
X257849Y2851094D01*
X257449Y2852027D01*
X257249Y2853094D01*
Y2854160D01*
X257449Y2855227D01*
X257849Y2856160D01*
X258449Y2856960D01*
X259149Y2857494D01*
X259949Y2857627D01*
X260749Y2857494D01*
X261449Y2856960D01*
X262049Y2856160D01*
X262449Y2855227D01*
X262649Y2854160D01*
Y2853094D01*
X262449Y2852027D01*
X262049Y2851094D01*
X261449Y2850294D01*
X260749Y2849760D01*
X259949Y2849627D01*
G01X265949D02*
Y2857627D01*
X268349D01*
X269149Y2857227D01*
X269749Y2856294D01*
X269949Y2855227D01*
X269749Y2854160D01*
X269249Y2853360D01*
X268349Y2852960D01*
X265949D01*
G01X277949Y2849627D02*
X273949D01*
Y2857627D01*
X277949D01*
G01X276349Y2853760D02*
X273949D01*
G01X281649Y2849627D02*
Y2857627D01*
X286249Y2849627D01*
Y2857627D01*
G01X299949Y2849627D02*
X299149Y2849760D01*
X298449Y2850294D01*
X297849Y2851094D01*
X297449Y2852027D01*
X297249Y2853094D01*
Y2854160D01*
X297449Y2855227D01*
X297849Y2856160D01*
X298449Y2856960D01*
X299149Y2857494D01*
X299949Y2857627D01*
X300749Y2857494D01*
X301449Y2856960D01*
X302049Y2856160D01*
X302449Y2855227D01*
X302649Y2854160D01*
Y2853094D01*
X302449Y2852027D01*
X302049Y2851094D01*
X301449Y2850294D01*
X300749Y2849760D01*
X299949Y2849627D01*
G01X305649D02*
Y2857627D01*
X310249Y2849627D01*
Y2857627D01*
G01X324749Y2853894D02*
X325149Y2854294D01*
X325449Y2854960D01*
X325649Y2855894D01*
X325449Y2856694D01*
X325049Y2857227D01*
X324349Y2857627D01*
X321649D01*
Y2849627D01*
X324949D01*
X325649Y2850160D01*
X326049Y2850960D01*
X326249Y2851894D01*
X326049Y2852827D01*
X325449Y2853627D01*
X324749Y2853894D01*
X321649D01*
G01X331949Y2849627D02*
X331149Y2849760D01*
X330449Y2850294D01*
X329849Y2851094D01*
X329449Y2852027D01*
X329249Y2853094D01*
Y2854160D01*
X329449Y2855227D01*
X329849Y2856160D01*
X330449Y2856960D01*
X331149Y2857494D01*
X331949Y2857627D01*
X332749Y2857494D01*
X333449Y2856960D01*
X334049Y2856160D01*
X334449Y2855227D01*
X334649Y2854160D01*
Y2853094D01*
X334449Y2852027D01*
X334049Y2851094D01*
X333449Y2850294D01*
X332749Y2849760D01*
X331949Y2849627D01*
G01X339949Y2857627D02*
Y2849627D01*
G01X337649Y2857627D02*
X342249D01*
G01X345849Y2849627D02*
Y2857627D01*
G01X350049D02*
Y2849627D01*
G01Y2853627D02*
X345849D01*
G01X361849Y2850693D02*
X362649Y2850027D01*
X363549Y2849627D01*
X364349D01*
X365149Y2850027D01*
X365749Y2850693D01*
X366049Y2851627D01*
X365849Y2852560D01*
X365349Y2853360D01*
X364449Y2853894D01*
X363249Y2854160D01*
X362549Y2854694D01*
X362249Y2855627D01*
X362449Y2856560D01*
X362949Y2857227D01*
X363649Y2857627D01*
X364349D01*
X365049Y2857360D01*
X365649Y2856694D01*
G01X370749Y2857627D02*
X373149D01*
G01X371949D02*
Y2849627D01*
G01X370749D02*
X373149D01*
G01X377749D02*
Y2857627D01*
X379749D01*
X380549Y2857227D01*
X381149Y2856694D01*
X381649Y2855894D01*
X382049Y2854960D01*
X382149Y2853627D01*
X382049Y2852294D01*
X381649Y2851360D01*
X381149Y2850560D01*
X380549Y2850027D01*
X379749Y2849627D01*
X377749D01*
G01X389949D02*
X385949D01*
Y2857627D01*
X389949D01*
G01X388349Y2853760D02*
X385949D01*
G01X395949Y2849360D02*
X395749Y2849494D01*
Y2849760D01*
X395949Y2849894D01*
X396149Y2849760D01*
Y2849494D01*
X395949Y2849360D01*
G01X191000Y-62500D02*
Y-137500D01*
G01Y-112500D02*
X294000D01*
Y-87500D01*
G01X191000D02*
X294000D01*
G01X212857Y2212647D02*
X405512D01*
G01X208490Y2282366D02*
X195990D01*
X198490Y2280506D01*
G01X208490D02*
Y2284226D01*
G01X208907Y2294766D02*
X208698Y2294456D01*
X208282D01*
X208073Y2294766D01*
X208282Y2295076D01*
X208698D01*
X208907Y2294766D01*
G01X206615Y2303756D02*
X207657Y2304686D01*
X208282Y2305771D01*
X208490Y2307166D01*
X208073Y2308561D01*
X207240Y2309646D01*
X205782Y2310421D01*
X204115Y2310576D01*
X202448Y2310266D01*
X201407Y2309491D01*
X200573Y2308406D01*
X200365Y2307321D01*
X200573Y2306236D01*
X201407Y2304841D01*
X195990Y2305306D01*
Y2309491D01*
G01X208490Y2315536D02*
X195990D01*
X206407Y2319566D01*
X195990Y2323596D01*
X208490D01*
G01Y2327936D02*
X195990D01*
X206407Y2331966D01*
X195990Y2335996D01*
X208490D01*
G01X217348Y2391174D02*
Y2295355D01*
G01D02*
Y2394127D01*
G01Y2397079D02*
Y2428575D01*
G01D02*
Y2394127D01*
G01X225183Y2541764D02*
Y2554264D01*
X223323Y2551764D01*
G01Y2541764D02*
X227043D01*
G01X237583Y2554264D02*
X236343Y2553847D01*
X235413Y2552806D01*
X234793Y2551556D01*
X234328Y2549889D01*
X234173Y2548014D01*
X234328Y2546139D01*
X234793Y2544472D01*
X235413Y2543222D01*
X236343Y2542181D01*
X237583Y2541764D01*
X238823Y2542181D01*
X239753Y2543222D01*
X240373Y2544472D01*
X240838Y2546139D01*
X240993Y2548014D01*
X240838Y2549889D01*
X240373Y2551556D01*
X239753Y2552806D01*
X238823Y2553847D01*
X237583Y2554264D01*
G01X249983D02*
X248743Y2553847D01*
X247813Y2552806D01*
X247193Y2551556D01*
X246728Y2549889D01*
X246573Y2548014D01*
X246728Y2546139D01*
X247193Y2544472D01*
X247813Y2543222D01*
X248743Y2542181D01*
X249983Y2541764D01*
X251223Y2542181D01*
X252153Y2543222D01*
X252773Y2544472D01*
X253238Y2546139D01*
X253393Y2548014D01*
X253238Y2549889D01*
X252773Y2551556D01*
X252153Y2552806D01*
X251223Y2553847D01*
X249983Y2554264D01*
G01X260368Y2545931D02*
X264398D01*
G01X274783Y2541764D02*
Y2554264D01*
X272923Y2551764D01*
G01Y2541764D02*
X276643D01*
G01X283773Y2543639D02*
X284703Y2542597D01*
X285788Y2541972D01*
X287183Y2541764D01*
X288578Y2542181D01*
X289663Y2543014D01*
X290438Y2544472D01*
X290593Y2546139D01*
X290283Y2547806D01*
X289508Y2548847D01*
X288423Y2549681D01*
X287338Y2549889D01*
X286253Y2549681D01*
X284858Y2548847D01*
X285323Y2554264D01*
X289508D01*
G01X299583D02*
X298343Y2553847D01*
X297413Y2552806D01*
X296793Y2551556D01*
X296328Y2549889D01*
X296173Y2548014D01*
X296328Y2546139D01*
X296793Y2544472D01*
X297413Y2543222D01*
X298343Y2542181D01*
X299583Y2541764D01*
X300823Y2542181D01*
X301753Y2543222D01*
X302373Y2544472D01*
X302838Y2546139D01*
X302993Y2548014D01*
X302838Y2549889D01*
X302373Y2551556D01*
X301753Y2552806D01*
X300823Y2553847D01*
X299583Y2554264D01*
G01X307953Y2541764D02*
Y2554264D01*
X311983Y2543847D01*
X316013Y2554264D01*
Y2541764D01*
G01X320353D02*
Y2554264D01*
X324383Y2543847D01*
X328413Y2554264D01*
Y2541764D01*
G01X277949Y2384427D02*
X279949D01*
Y2382027D01*
X279349Y2381227D01*
X278649Y2380694D01*
X277649Y2380427D01*
X276649Y2380694D01*
X275949Y2381227D01*
X275349Y2382027D01*
X274949Y2382960D01*
X274749Y2384027D01*
Y2384960D01*
X274949Y2385760D01*
X275349Y2386694D01*
X275949Y2387494D01*
X276549Y2388027D01*
X277349Y2388427D01*
X278049D01*
X278849Y2388160D01*
X279449Y2387627D01*
G01X283349Y2380427D02*
Y2388427D01*
X285849D01*
X286649Y2388027D01*
X287149Y2387494D01*
X287349Y2386427D01*
X287149Y2385360D01*
X286549Y2384694D01*
X285849Y2384294D01*
X283349D01*
G01X285849D02*
X287349Y2380427D01*
G01X293349D02*
X292549Y2380560D01*
X291849Y2381094D01*
X291249Y2381894D01*
X290849Y2382827D01*
X290649Y2383894D01*
Y2384960D01*
X290849Y2386027D01*
X291249Y2386960D01*
X291849Y2387760D01*
X292549Y2388294D01*
X293349Y2388427D01*
X294149Y2388294D01*
X294849Y2387760D01*
X295449Y2386960D01*
X295849Y2386027D01*
X296049Y2384960D01*
Y2383894D01*
X295849Y2382827D01*
X295449Y2381894D01*
X294849Y2381094D01*
X294149Y2380560D01*
X293349Y2380427D01*
G01X299149Y2388427D02*
Y2382694D01*
X299549Y2381493D01*
X300349Y2380694D01*
X301349Y2380427D01*
X302349Y2380694D01*
X303149Y2381493D01*
X303549Y2382694D01*
Y2388427D01*
G01X307349Y2380427D02*
Y2388427D01*
X309749D01*
X310549Y2388027D01*
X311149Y2387094D01*
X311349Y2386027D01*
X311149Y2384960D01*
X310649Y2384160D01*
X309749Y2383760D01*
X307349D01*
G01X315249Y2381493D02*
X316049Y2380827D01*
X316949Y2380427D01*
X317749D01*
X318549Y2380827D01*
X319149Y2381493D01*
X319449Y2382427D01*
X319249Y2383360D01*
X318749Y2384160D01*
X317849Y2384694D01*
X316649Y2384960D01*
X315949Y2385494D01*
X315649Y2386427D01*
X315849Y2387360D01*
X316349Y2388027D01*
X317049Y2388427D01*
X317749D01*
X318449Y2388160D01*
X319049Y2387494D01*
G01X334149Y2384694D02*
X334549Y2385094D01*
X334849Y2385760D01*
X335049Y2386694D01*
X334849Y2387494D01*
X334449Y2388027D01*
X333749Y2388427D01*
X331049D01*
Y2380427D01*
X334349D01*
X335049Y2380960D01*
X335449Y2381760D01*
X335649Y2382694D01*
X335449Y2383627D01*
X334849Y2384427D01*
X334149Y2384694D01*
X331049D01*
G01X570059Y2538812D02*
X274783D01*
G01X301507Y-122500D02*
Y-117500D01*
X302773D01*
X303280Y-117750D01*
X303660Y-118083D01*
X303977Y-118583D01*
X304230Y-119167D01*
X304293Y-120000D01*
X304230Y-120833D01*
X303977Y-121417D01*
X303660Y-121917D01*
X303280Y-122250D01*
X302773Y-122500D01*
X301507D01*
G01X306417D02*
X308000Y-117500D01*
X309583Y-122500D01*
G01X309013Y-120750D02*
X306987D01*
G01X313100Y-117500D02*
Y-122500D01*
G01X311643Y-117500D02*
X314557D01*
G01X319467Y-122500D02*
X316933D01*
Y-117500D01*
X319467D01*
G01X318453Y-119917D02*
X316933D01*
G01X323300Y-122667D02*
X323173Y-122583D01*
Y-122417D01*
X323300Y-122333D01*
X323427Y-122417D01*
Y-122583D01*
X323300Y-122667D01*
G01Y-120417D02*
X323173Y-120333D01*
Y-120167D01*
X323300Y-120083D01*
X323427Y-120167D01*
Y-120333D01*
X323300Y-120417D01*
G01X296000Y-62500D02*
Y-137500D01*
G01X294000Y-62500D02*
Y-137500D01*
G01X301633Y-97500D02*
Y-92500D01*
X303153D01*
X303660Y-92750D01*
X304040Y-93333D01*
X304167Y-94000D01*
X304040Y-94667D01*
X303723Y-95167D01*
X303153Y-95417D01*
X301633D01*
G01X306860Y-97667D02*
X309140Y-92500D01*
G01X311643Y-97500D02*
Y-92500D01*
X314557Y-97500D01*
Y-92500D01*
G01X318200Y-97667D02*
X318073Y-97583D01*
Y-97417D01*
X318200Y-97333D01*
X318327Y-97417D01*
Y-97583D01*
X318200Y-97667D01*
G01Y-95417D02*
X318073Y-95333D01*
Y-95167D01*
X318200Y-95083D01*
X318327Y-95167D01*
Y-95333D01*
X318200Y-95417D01*
G01X296000Y-112500D02*
X496000D01*
G01X301633Y-72500D02*
Y-67500D01*
X303153D01*
X303660Y-67750D01*
X304040Y-68333D01*
X304167Y-69000D01*
X304040Y-69667D01*
X303723Y-70167D01*
X303153Y-70417D01*
X301633D01*
G01X306733Y-72500D02*
Y-67500D01*
X308317D01*
X308823Y-67750D01*
X309140Y-68083D01*
X309267Y-68750D01*
X309140Y-69417D01*
X308760Y-69833D01*
X308317Y-70083D01*
X306733D01*
G01X308317D02*
X309267Y-72500D01*
G01X313100D02*
X312593Y-72417D01*
X312150Y-72083D01*
X311770Y-71583D01*
X311517Y-71000D01*
X311390Y-70333D01*
Y-69667D01*
X311517Y-69000D01*
X311770Y-68417D01*
X312150Y-67917D01*
X312593Y-67583D01*
X313100Y-67500D01*
X313607Y-67583D01*
X314050Y-67917D01*
X314430Y-68417D01*
X314683Y-69000D01*
X314810Y-69667D01*
Y-70333D01*
X314683Y-71000D01*
X314430Y-71583D01*
X314050Y-72083D01*
X313607Y-72417D01*
X313100Y-72500D01*
G01X316933Y-71500D02*
X317250Y-72000D01*
X317630Y-72333D01*
X318073Y-72500D01*
X318580Y-72333D01*
X318960Y-72000D01*
X319340Y-71500D01*
X319467Y-70833D01*
Y-67500D01*
G01X324567Y-72500D02*
X322033D01*
Y-67500D01*
X324567D01*
G01X323553Y-69917D02*
X322033D01*
G01X329793Y-67917D02*
X329413Y-67667D01*
X328970Y-67500D01*
X328463D01*
X327893Y-67750D01*
X327450Y-68167D01*
X327133Y-68667D01*
X326880Y-69500D01*
X326817Y-70250D01*
X326943Y-71000D01*
X327133Y-71500D01*
X327513Y-72000D01*
X327957Y-72333D01*
X328400Y-72500D01*
X328843D01*
X329287Y-72333D01*
X329667Y-72083D01*
X329983Y-71750D01*
G01X333500Y-67500D02*
Y-72500D01*
G01X332043Y-67500D02*
X334957D01*
G01X338600Y-72667D02*
X338473Y-72583D01*
Y-72417D01*
X338600Y-72333D01*
X338727Y-72417D01*
Y-72583D01*
X338600Y-72667D01*
G01Y-70417D02*
X338473Y-70333D01*
Y-70167D01*
X338600Y-70083D01*
X338727Y-70167D01*
Y-70333D01*
X338600Y-70417D01*
G01X296000Y-87500D02*
X496000D01*
G01X307087Y2040503D02*
Y-3491D01*
G01X310086Y127165D02*
X425869D01*
G01X310086Y477165D02*
X412724D01*
G01X310086Y827165D02*
X425524D01*
G01X310086Y1343504D02*
X486045D01*
G01X310086Y1693504D02*
X498845D01*
G01X302445Y1899199D02*
G03I6273J-15498D01*
G01X317323Y1881102D02*
G02X296850I-10237J0D01*
G01Y1885039D01*
G02X317323I10236J0D01*
G01Y1881102D01*
G01Y1885039D02*
Y1881102D01*
G02X296850I-10237J0D01*
G01Y1885039D01*
G02X317323I10236J0D01*
G01X310086Y1883071D02*
X480318D01*
G01X318087Y1892913D02*
X313267Y1891248D01*
X318356Y1890931D01*
X318087Y1892913D01*
G01X313267Y1891248D02*
X412397Y1904731D01*
G01X310087Y2043503D02*
X453371D01*
G01X359842Y2000780D02*
Y-7197D01*
G01X362842Y78780D02*
X435756D01*
G01X362842Y253780D02*
X437995D01*
G01X362842Y428779D02*
X425195D01*
G01X362842Y603779D02*
X553196D01*
G01X362842Y778780D02*
X555890D01*
G01X362842Y953780D02*
X527596D01*
G01X362842Y1128779D02*
X492109D01*
G01X362842Y1303780D02*
X491435D01*
G01X362842Y1478780D02*
X494130D01*
G01X362842Y1653780D02*
X497498D01*
G01X362842Y1828779D02*
X478971D01*
G01X362842Y2003780D02*
X465834D01*
G01X373385Y1954520D02*
Y-17303D01*
X379969Y-25417D01*
G01X376385Y32520D02*
X414898D01*
X416776Y33300D01*
G01X376385Y207520D02*
X411379D01*
X412219Y207729D01*
G01X373078Y308268D02*
X433280D01*
G01X376385Y382520D02*
X406662D01*
X408115Y383111D01*
G01X376386Y557520D02*
X421651D01*
X422750Y558103D01*
G01X376386Y732520D02*
X420456D01*
X425840Y734939D01*
G01X376385Y907520D02*
X422157D01*
X447757Y920803D01*
G01X376385Y1082520D02*
X426199D01*
X429222Y1084080D01*
G01X376385Y1257520D02*
X434957D01*
X461568Y1272466D01*
X462122D01*
G01X376385Y1432520D02*
X438326D01*
X442224Y1434060D01*
G01X376385Y1607520D02*
X420793D01*
X429663Y1611569D01*
G01X376385Y1782520D02*
X428557D01*
X439721Y1787745D01*
G01X376385Y1957520D02*
X433946D01*
X441576Y1961893D01*
G01X411000Y-112500D02*
Y-137500D01*
G01X405512Y2081740D02*
Y2116592D01*
G01Y2087001D02*
Y2215647D01*
G01X400512Y2211647D02*
X405512Y2212647D01*
X400512Y2213647D01*
Y2211647D01*
G01X416633Y-122500D02*
Y-117500D01*
X418217D01*
X418723Y-117750D01*
X419040Y-118083D01*
X419167Y-118750D01*
X419040Y-119417D01*
X418660Y-119833D01*
X418217Y-120083D01*
X416633D01*
G01X418217D02*
X419167Y-122500D01*
G01X424267D02*
X421733D01*
Y-117500D01*
X424267D01*
G01X423253Y-119917D02*
X421733D01*
G01X426517Y-117500D02*
X428100Y-122500D01*
X429683Y-117500D01*
G01X433200Y-122667D02*
X433073Y-122583D01*
Y-122417D01*
X433200Y-122333D01*
X433327Y-122417D01*
Y-122583D01*
X433200Y-122667D01*
G01Y-120417D02*
X433073Y-120333D01*
Y-120167D01*
X433200Y-120083D01*
X433327Y-120167D01*
Y-120333D01*
X433200Y-120417D01*
G01X413881Y1899910D02*
Y1909910D01*
X416381D01*
X417381Y1909410D01*
X418131Y1908743D01*
X418756Y1907743D01*
X419256Y1906576D01*
X419381Y1904910D01*
X419256Y1903243D01*
X418756Y1902077D01*
X418131Y1901076D01*
X417381Y1900410D01*
X416381Y1899910D01*
X413881D01*
G01X429131D02*
X424131D01*
Y1909910D01*
X429131D01*
G01X427131Y1905077D02*
X424131D01*
G01X436631Y1909910D02*
Y1899910D01*
G01X433756Y1909910D02*
X439506D01*
G01X443506Y1899910D02*
X446631Y1909910D01*
X449756Y1899910D01*
G01X448631Y1903410D02*
X444631D01*
G01X455131Y1909910D02*
X458131D01*
G01X456631D02*
Y1899910D01*
G01X455131D02*
X458131D01*
G01X464131Y1909910D02*
Y1899910D01*
X469131D01*
G01X483506D02*
X486631Y1909910D01*
X489756Y1899910D01*
G01X488631Y1903410D02*
X484631D01*
G01X453636Y54717D02*
Y64717D01*
X456136D01*
X457136Y64217D01*
X457886Y63550D01*
X458511Y62550D01*
X459011Y61383D01*
X459136Y59717D01*
X459011Y58050D01*
X458511Y56884D01*
X457886Y55883D01*
X457136Y55217D01*
X456136Y54717D01*
X453636D01*
G01X468886D02*
X463886D01*
Y64717D01*
X468886D01*
G01X466886Y59884D02*
X463886D01*
G01X476386Y64717D02*
Y54717D01*
G01X473511Y64717D02*
X479261D01*
G01X483261Y54717D02*
X486386Y64717D01*
X489511Y54717D01*
G01X488386Y58217D02*
X484386D01*
G01X494886Y64717D02*
X497886D01*
G01X496386D02*
Y54717D01*
G01X494886D02*
X497886D01*
G01X503886Y64717D02*
Y54717D01*
X508886D01*
G01X523261D02*
X526386Y64717D01*
X529511Y54717D01*
G01X528386Y58217D02*
X524386D01*
G01X460000Y-112500D02*
Y-137500D01*
G01X517409Y2517627D02*
Y2530127D01*
X511674Y2521169D01*
X519424D01*
G01X523919Y2517627D02*
Y2530127D01*
X527949Y2519710D01*
X531979Y2530127D01*
Y2517627D01*
G01X536319D02*
Y2530127D01*
X540349Y2519710D01*
X544379Y2530127D01*
Y2517627D01*
G01X554311Y2511253D02*
X522815D01*
G01D02*
X562185D01*
G01X735703Y-119199D02*
G03I-95259J0D01*
G01X535266Y39171D02*
Y1031771D01*
X812066D01*
Y39171D01*
X535266D01*
G01Y86421D02*
X812066D01*
G01X535266Y133671D02*
X812066D01*
G01X535266Y180921D02*
X812066D01*
G01X535266Y228171D02*
X812066D01*
G01X535266Y275421D02*
X812066D01*
G01X535266Y322671D02*
X812066D01*
G01X535266Y369921D02*
X812066D01*
G01X535266Y417171D02*
X812066D01*
G01X535266Y464421D02*
X812066D01*
G01X535266Y511671D02*
X812066D01*
G01X535266Y558921D02*
X812066D01*
G01X535266Y606171D02*
X812066D01*
G01X535266Y653421D02*
X812066D01*
G01X535266Y700671D02*
X812066D01*
G01X535266Y747921D02*
X812066D01*
G01X535266Y795171D02*
X812066D01*
G01X535266Y842421D02*
X812066D01*
G01X535266Y889671D02*
X812066D01*
G01X535266Y936921D02*
X812066D01*
G01X535266Y995471D02*
X812066D01*
G01X535266Y984171D02*
X812066D01*
G01X535266Y1006771D02*
X812066D01*
G01X554311Y2436449D02*
X570059Y2444323D01*
G01Y2464009D02*
X554311Y2471883D01*
G01X570059Y2444323D02*
X554311Y2452197D01*
G01Y2456134D02*
X570059Y2464009D01*
G01X554311Y2475820D02*
Y2519127D01*
G01X571806Y-103799D02*
X572276Y-103169D01*
X572824Y-102854D01*
X573451Y-102749D01*
X574234Y-102959D01*
X574782Y-103484D01*
X574939Y-104114D01*
X574861Y-104744D01*
X574547Y-105269D01*
X572981Y-106319D01*
X572276Y-107054D01*
X571806Y-108104D01*
X571649Y-109049D01*
X574939D01*
G01X579594Y-102749D02*
X578967Y-102959D01*
X578497Y-103484D01*
X578184Y-104114D01*
X577949Y-104954D01*
X577871Y-105899D01*
X577949Y-106844D01*
X578184Y-107684D01*
X578497Y-108314D01*
X578967Y-108839D01*
X579594Y-109049D01*
X580221Y-108839D01*
X580691Y-108314D01*
X581004Y-107684D01*
X581239Y-106844D01*
X581317Y-105899D01*
X581239Y-104954D01*
X581004Y-104114D01*
X580691Y-103484D01*
X580221Y-102959D01*
X579594Y-102749D01*
G01X584171Y-108104D02*
X584641Y-108629D01*
X585189Y-108944D01*
X585894Y-109049D01*
X586599Y-108839D01*
X587147Y-108419D01*
X587539Y-107684D01*
X587617Y-106844D01*
X587461Y-106004D01*
X587069Y-105479D01*
X586521Y-105059D01*
X585972Y-104954D01*
X585424Y-105059D01*
X584719Y-105479D01*
X584954Y-102749D01*
X587069D01*
G01X592194Y-109259D02*
X592037Y-109154D01*
Y-108944D01*
X592194Y-108839D01*
X592351Y-108944D01*
Y-109154D01*
X592194Y-109259D01*
G01X598494Y-102749D02*
X597867Y-102959D01*
X597397Y-103484D01*
X597084Y-104114D01*
X596849Y-104954D01*
X596771Y-105899D01*
X596849Y-106844D01*
X597084Y-107684D01*
X597397Y-108314D01*
X597867Y-108839D01*
X598494Y-109049D01*
X599121Y-108839D01*
X599591Y-108314D01*
X599904Y-107684D01*
X600139Y-106844D01*
X600217Y-105899D01*
X600139Y-104954D01*
X599904Y-104114D01*
X599591Y-103484D01*
X599121Y-102959D01*
X598494Y-102749D01*
G01X604794D02*
X604167Y-102959D01*
X603697Y-103484D01*
X603384Y-104114D01*
X603149Y-104954D01*
X603071Y-105899D01*
X603149Y-106844D01*
X603384Y-107684D01*
X603697Y-108314D01*
X604167Y-108839D01*
X604794Y-109049D01*
X605421Y-108839D01*
X605891Y-108314D01*
X606204Y-107684D01*
X606439Y-106844D01*
X606517Y-105899D01*
X606439Y-104954D01*
X606204Y-104114D01*
X605891Y-103484D01*
X605421Y-102959D01*
X604794Y-102749D01*
G01X572266Y995471D02*
Y39171D01*
G01X605492Y2456134D02*
X562185D01*
G01X605492Y2452197D02*
X562185D01*
G01X570059Y2467945D02*
Y2519127D01*
G01Y2467945D02*
Y2546686D01*
G01Y2511253D02*
X601555D01*
G01D02*
X562185D01*
G01X600777Y-188099D02*
X599844Y-186849D01*
X599377Y-185599D01*
Y-180599D01*
X599844Y-179349D01*
X600777Y-178099D01*
G01X606597Y-185599D02*
Y-178099D01*
X610891Y-185599D01*
Y-178099D01*
G01X616244Y-185599D02*
X615497Y-185474D01*
X614844Y-184974D01*
X614284Y-184224D01*
X613911Y-183349D01*
X613724Y-182349D01*
Y-181349D01*
X613911Y-180349D01*
X614284Y-179474D01*
X614844Y-178724D01*
X615497Y-178224D01*
X616244Y-178099D01*
X616991Y-178224D01*
X617644Y-178724D01*
X618204Y-179474D01*
X618577Y-180349D01*
X618764Y-181349D01*
Y-182349D01*
X618577Y-183349D01*
X618204Y-184224D01*
X617644Y-184974D01*
X616991Y-185474D01*
X616244Y-185599D01*
G01X621597D02*
Y-178099D01*
X625891Y-185599D01*
Y-178099D01*
G01X630031Y-183099D02*
X632457D01*
G01X636877Y-185599D02*
Y-178099D01*
X639117D01*
X639864Y-178474D01*
X640424Y-179349D01*
X640611Y-180349D01*
X640424Y-181349D01*
X639957Y-182099D01*
X639117Y-182474D01*
X636877D01*
G01X644377Y-178099D02*
Y-185599D01*
X648111D01*
G01X651411D02*
X653744Y-178099D01*
X656077Y-185599D01*
G01X655237Y-182974D02*
X652251D01*
G01X661244Y-178099D02*
Y-185599D01*
G01X659097Y-178099D02*
X663391D01*
G01X670611Y-185599D02*
X666877D01*
Y-178099D01*
X670611D01*
G01X669117Y-181724D02*
X666877D01*
G01X674191Y-185599D02*
Y-178099D01*
X676057D01*
X676804Y-178474D01*
X677364Y-178974D01*
X677831Y-179724D01*
X678204Y-180599D01*
X678297Y-181849D01*
X678204Y-183099D01*
X677831Y-183974D01*
X677364Y-184724D01*
X676804Y-185224D01*
X676057Y-185599D01*
X674191D01*
G01X684211Y-188099D02*
X685144Y-186849D01*
X685611Y-185599D01*
Y-180599D01*
X685144Y-179349D01*
X684211Y-178099D01*
G01X603544Y-51699D02*
Y-41699D01*
X606044D01*
X607044Y-42199D01*
X607794Y-42866D01*
X608419Y-43866D01*
X608919Y-45033D01*
X609044Y-46699D01*
X608919Y-48366D01*
X608419Y-49532D01*
X607794Y-50533D01*
X607044Y-51199D01*
X606044Y-51699D01*
X603544D01*
G01X618794D02*
X613794D01*
Y-41699D01*
X618794D01*
G01X616794Y-46532D02*
X613794D01*
G01X626294Y-41699D02*
Y-51699D01*
G01X623419Y-41699D02*
X629169D01*
G01X633169Y-51699D02*
X636294Y-41699D01*
X639419Y-51699D01*
G01X638294Y-48199D02*
X634294D01*
G01X644794Y-41699D02*
X647794D01*
G01X646294D02*
Y-51699D01*
G01X644794D02*
X647794D01*
G01X653794Y-41699D02*
Y-51699D01*
X658794D01*
G01X673169D02*
X676294Y-41699D01*
X679419Y-51699D01*
G01X678294Y-48199D02*
X674294D01*
G01X602544Y-54199D02*
X682544D01*
G01X610049Y2418427D02*
X597549D01*
X600049Y2416567D01*
G01X610049D02*
Y2420287D01*
G01Y2426797D02*
X597549D01*
X607966Y2430827D01*
X597549Y2434857D01*
X610049D01*
G01Y2439197D02*
X597549D01*
X607966Y2443227D01*
X597549Y2447257D01*
X610049D01*
G01X586111Y2413020D02*
Y2456327D01*
G01X628427Y-204899D02*
X627494Y-203649D01*
X627027Y-202399D01*
Y-197399D01*
X627494Y-196149D01*
X628427Y-194899D01*
G01X636394Y-202399D02*
Y-194899D01*
X635274Y-196399D01*
G01Y-202399D02*
X637514D01*
G01X641934D02*
X645854Y-194899D01*
G01X641934D02*
X645854Y-202399D01*
G01X651861Y-204899D02*
X652794Y-203649D01*
X653261Y-202399D01*
Y-197399D01*
X652794Y-196149D01*
X651861Y-194899D01*
G01X611869Y-105899D02*
X632644D01*
G01X610697Y-64199D02*
Y-56699D01*
X614991Y-64199D01*
Y-56699D01*
G01X620344Y-64199D02*
X619597Y-64074D01*
X618944Y-63574D01*
X618384Y-62824D01*
X618011Y-61949D01*
X617824Y-60949D01*
Y-59949D01*
X618011Y-58949D01*
X618384Y-58074D01*
X618944Y-57324D01*
X619597Y-56824D01*
X620344Y-56699D01*
X621091Y-56824D01*
X621744Y-57324D01*
X622304Y-58074D01*
X622677Y-58949D01*
X622864Y-59949D01*
Y-60949D01*
X622677Y-61949D01*
X622304Y-62824D01*
X621744Y-63574D01*
X621091Y-64074D01*
X620344Y-64199D01*
G01X633384Y-63199D02*
X634131Y-63824D01*
X634971Y-64199D01*
X635717D01*
X636464Y-63824D01*
X637024Y-63199D01*
X637304Y-62324D01*
X637117Y-61449D01*
X636651Y-60699D01*
X635811Y-60199D01*
X634691Y-59949D01*
X634037Y-59449D01*
X633757Y-58574D01*
X633944Y-57699D01*
X634411Y-57074D01*
X635064Y-56699D01*
X635717D01*
X636371Y-56949D01*
X636931Y-57574D01*
G01X644897Y-57324D02*
X644337Y-56949D01*
X643684Y-56699D01*
X642937D01*
X642097Y-57074D01*
X641444Y-57699D01*
X640977Y-58449D01*
X640604Y-59699D01*
X640511Y-60824D01*
X640697Y-61949D01*
X640977Y-62699D01*
X641537Y-63449D01*
X642191Y-63949D01*
X642844Y-64199D01*
X643497D01*
X644151Y-63949D01*
X644711Y-63574D01*
X645177Y-63074D01*
G01X648011Y-64199D02*
X650344Y-56699D01*
X652677Y-64199D01*
G01X651837Y-61574D02*
X648851D01*
G01X655977Y-56699D02*
Y-64199D01*
X659711D01*
G01X667211D02*
X663477D01*
Y-56699D01*
X667211D01*
G01X665717Y-60324D02*
X663477D01*
G01X630049Y2454227D02*
X632049D01*
Y2451827D01*
X631449Y2451027D01*
X630749Y2450494D01*
X629749Y2450227D01*
X628749Y2450494D01*
X628049Y2451027D01*
X627449Y2451827D01*
X627049Y2452760D01*
X626849Y2453827D01*
Y2454760D01*
X627049Y2455560D01*
X627449Y2456494D01*
X628049Y2457294D01*
X628649Y2457827D01*
X629449Y2458227D01*
X630149D01*
X630949Y2457960D01*
X631549Y2457427D01*
G01X635449Y2450227D02*
Y2458227D01*
X637949D01*
X638749Y2457827D01*
X639249Y2457294D01*
X639449Y2456227D01*
X639249Y2455160D01*
X638649Y2454494D01*
X637949Y2454094D01*
X635449D01*
G01X637949D02*
X639449Y2450227D01*
G01X645449D02*
X644649Y2450360D01*
X643949Y2450894D01*
X643349Y2451694D01*
X642949Y2452627D01*
X642749Y2453694D01*
Y2454760D01*
X642949Y2455827D01*
X643349Y2456760D01*
X643949Y2457560D01*
X644649Y2458094D01*
X645449Y2458227D01*
X646249Y2458094D01*
X646949Y2457560D01*
X647549Y2456760D01*
X647949Y2455827D01*
X648149Y2454760D01*
Y2453694D01*
X647949Y2452627D01*
X647549Y2451694D01*
X646949Y2450894D01*
X646249Y2450360D01*
X645449Y2450227D01*
G01X651249Y2458227D02*
Y2452494D01*
X651649Y2451293D01*
X652449Y2450494D01*
X653449Y2450227D01*
X654449Y2450494D01*
X655249Y2451293D01*
X655649Y2452494D01*
Y2458227D01*
G01X659449Y2450227D02*
Y2458227D01*
X661849D01*
X662649Y2457827D01*
X663249Y2456894D01*
X663449Y2455827D01*
X663249Y2454760D01*
X662749Y2453960D01*
X661849Y2453560D01*
X659449D01*
G01X667349Y2451293D02*
X668149Y2450627D01*
X669049Y2450227D01*
X669849D01*
X670649Y2450627D01*
X671249Y2451293D01*
X671549Y2452227D01*
X671349Y2453160D01*
X670849Y2453960D01*
X669949Y2454494D01*
X668749Y2454760D01*
X668049Y2455294D01*
X667749Y2456227D01*
X667949Y2457160D01*
X668449Y2457827D01*
X669149Y2458227D01*
X669849D01*
X670549Y2457960D01*
X671149Y2457294D01*
G01X682949Y2450227D02*
X685449Y2458227D01*
X687949Y2450227D01*
G01X687049Y2453027D02*
X683849D01*
G01X645444Y-161399D02*
X691444D01*
G01X632644Y-153599D02*
Y-134399D01*
G01X648244D02*
Y-153599D01*
G01X632644D02*
G03X648244I7800J0D01*
G01X645444Y-126599D02*
X691444D01*
G01X648244Y-129199D02*
Y-101899D01*
G01X632644Y-129199D02*
Y-101899D01*
G01X648244Y-134399D02*
G03X632644I-7800J0D01*
G01X643244Y-106899D02*
X648244Y-105899D01*
X643244Y-104899D01*
Y-106899D01*
G01X632644Y-105899D02*
X648244D01*
G01X637644Y-104899D02*
X632644Y-105899D01*
X637644Y-106899D01*
Y-104899D01*
G01X650066Y995471D02*
Y39171D01*
G01X686444Y-156399D02*
X687444Y-161399D01*
X688444Y-156399D01*
X686444D01*
G01X687444Y-126599D02*
Y-161399D01*
G01X688444Y-131599D02*
X687444Y-126599D01*
X686444Y-131599D01*
X688444D01*
G01X687444Y-112524D02*
Y-126599D01*
G01X685344Y-106937D02*
X684714Y-106467D01*
X684399Y-105919D01*
X684294Y-105292D01*
X684504Y-104509D01*
X685029Y-103961D01*
X685659Y-103804D01*
X686289Y-103882D01*
X686814Y-104196D01*
X687864Y-105762D01*
X688599Y-106467D01*
X689649Y-106937D01*
X690594Y-107094D01*
Y-103804D01*
G01Y-98209D02*
X684294D01*
X688809Y-101107D01*
Y-97191D01*
G01X690594Y-91909D02*
X684294D01*
X688809Y-94807D01*
Y-90891D01*
G01X690804Y-86549D02*
X690699Y-86706D01*
X690489D01*
X690384Y-86549D01*
X690489Y-86392D01*
X690699D01*
X690804Y-86549D01*
G01X684294Y-80249D02*
X684504Y-80876D01*
X685029Y-81346D01*
X685659Y-81659D01*
X686499Y-81894D01*
X687444Y-81972D01*
X688389Y-81894D01*
X689229Y-81659D01*
X689859Y-81346D01*
X690384Y-80876D01*
X690594Y-80249D01*
X690384Y-79622D01*
X689859Y-79152D01*
X689229Y-78839D01*
X688389Y-78604D01*
X687444Y-78526D01*
X686499Y-78604D01*
X685659Y-78839D01*
X685029Y-79152D01*
X684504Y-79622D01*
X684294Y-80249D01*
G01Y-73949D02*
X684504Y-74576D01*
X685029Y-75046D01*
X685659Y-75359D01*
X686499Y-75594D01*
X687444Y-75672D01*
X688389Y-75594D01*
X689229Y-75359D01*
X689859Y-75046D01*
X690384Y-74576D01*
X690594Y-73949D01*
X690384Y-73322D01*
X689859Y-72852D01*
X689229Y-72539D01*
X688389Y-72304D01*
X687444Y-72226D01*
X686499Y-72304D01*
X685659Y-72539D01*
X685029Y-72852D01*
X684504Y-73322D01*
X684294Y-73949D01*
G01X727866Y995471D02*
Y39171D01*
G01X780166Y995471D02*
Y39171D01*
G01X-723776Y2987387D02*
Y-376795D01*
Y-489221D01*
X1782976D01*
Y-376795D01*
Y2987387D01*
X-723776D01*
G01X-225825Y1070699D02*
X-226455Y1071169D01*
X-226770Y1071717D01*
X-226875Y1072344D01*
X-226665Y1073127D01*
X-226140Y1073675D01*
X-225510Y1073832D01*
X-224880Y1073754D01*
X-224355Y1073440D01*
X-223305Y1071874D01*
X-222570Y1071169D01*
X-221520Y1070699D01*
X-220575Y1070542D01*
Y1073832D01*
G01X-226875Y1078487D02*
X-226665Y1077860D01*
X-226140Y1077390D01*
X-225510Y1077077D01*
X-224670Y1076842D01*
X-223725Y1076764D01*
X-222780Y1076842D01*
X-221940Y1077077D01*
X-221310Y1077390D01*
X-220785Y1077860D01*
X-220575Y1078487D01*
X-220785Y1079114D01*
X-221310Y1079584D01*
X-221940Y1079897D01*
X-222780Y1080132D01*
X-223725Y1080210D01*
X-224670Y1080132D01*
X-225510Y1079897D01*
X-226140Y1079584D01*
X-226665Y1079114D01*
X-226875Y1078487D01*
G01X-220575Y1084787D02*
X-220680Y1085335D01*
X-220995Y1085962D01*
X-221520Y1086354D01*
X-222255Y1086510D01*
X-222990Y1086354D01*
X-223620Y1085884D01*
X-223935Y1085179D01*
Y1084395D01*
X-224145Y1083925D01*
X-224670Y1083534D01*
X-225405Y1083377D01*
X-226140Y1083612D01*
X-226665Y1084160D01*
X-226875Y1084787D01*
X-226665Y1085414D01*
X-226140Y1085962D01*
X-225405Y1086197D01*
X-224670Y1086040D01*
X-224145Y1085649D01*
X-223935Y1085179D01*
Y1084395D01*
X-223620Y1083690D01*
X-222990Y1083220D01*
X-222255Y1083064D01*
X-221520Y1083220D01*
X-220995Y1083612D01*
X-220680Y1084239D01*
X-220575Y1084787D01*
G01X-223200Y1089599D02*
X-223935Y1090147D01*
X-224355Y1090617D01*
X-224565Y1091244D01*
X-224355Y1091792D01*
X-223935Y1092184D01*
X-223305Y1092497D01*
X-222570Y1092575D01*
X-221940Y1092497D01*
X-221310Y1092184D01*
X-220785Y1091714D01*
X-220575Y1091165D01*
X-220785Y1090539D01*
X-221415Y1089990D01*
X-222360Y1089677D01*
X-223410Y1089599D01*
X-224775Y1089755D01*
X-225510Y1089990D01*
X-226245Y1090382D01*
X-226770Y1090930D01*
X-226875Y1091479D01*
X-226665Y1092027D01*
X-226140Y1092419D01*
G01X-223200Y1095899D02*
X-223935Y1096447D01*
X-224355Y1096917D01*
X-224565Y1097544D01*
X-224355Y1098092D01*
X-223935Y1098484D01*
X-223305Y1098797D01*
X-222570Y1098875D01*
X-221940Y1098797D01*
X-221310Y1098484D01*
X-220785Y1098014D01*
X-220575Y1097465D01*
X-220785Y1096839D01*
X-221415Y1096290D01*
X-222360Y1095977D01*
X-223410Y1095899D01*
X-224775Y1096055D01*
X-225510Y1096290D01*
X-226245Y1096682D01*
X-226770Y1097230D01*
X-226875Y1097779D01*
X-226665Y1098327D01*
X-226140Y1098719D01*
G01X-220365Y1103687D02*
X-220470Y1103530D01*
X-220680D01*
X-220785Y1103687D01*
X-220680Y1103844D01*
X-220470D01*
X-220365Y1103687D01*
G01X-220575Y1109987D02*
X-226875D01*
X-225615Y1109047D01*
G01X-220575D02*
Y1110927D01*
G01Y1117227D02*
X-226875D01*
X-222360Y1114329D01*
Y1118245D01*
G01X-89232Y9796D02*
X-89859Y9586D01*
X-90329Y9061D01*
X-90642Y8431D01*
X-90877Y7591D01*
X-90955Y6646D01*
X-90877Y5701D01*
X-90642Y4861D01*
X-90329Y4231D01*
X-89859Y3706D01*
X-89232Y3496D01*
X-88605Y3706D01*
X-88135Y4231D01*
X-87822Y4861D01*
X-87587Y5701D01*
X-87509Y6646D01*
X-87587Y7591D01*
X-87822Y8431D01*
X-88135Y9061D01*
X-88605Y9586D01*
X-89232Y9796D01*
G01X-93016Y3150D02*
X-93643Y2940D01*
X-94113Y2415D01*
X-94426Y1785D01*
X-94661Y945D01*
X-94739Y0D01*
X-94661Y-945D01*
X-94426Y-1785D01*
X-94113Y-2415D01*
X-93643Y-2940D01*
X-93016Y-3150D01*
X-92389Y-2940D01*
X-91919Y-2415D01*
X-91606Y-1785D01*
X-91371Y-945D01*
X-91293Y0D01*
X-91371Y945D01*
X-91606Y1785D01*
X-91919Y2415D01*
X-92389Y2940D01*
X-93016Y3150D01*
G01X-74699Y67350D02*
X-74542Y68715D01*
X-74307Y69870D01*
X-73994Y70920D01*
X-73602Y72075D01*
X-72975Y73650D01*
X-76109D01*
G01X-68242D02*
X-68869Y73440D01*
X-69339Y72915D01*
X-69652Y72285D01*
X-69887Y71445D01*
X-69965Y70500D01*
X-69887Y69555D01*
X-69652Y68715D01*
X-69339Y68085D01*
X-68869Y67560D01*
X-68242Y67350D01*
X-67615Y67560D01*
X-67145Y68085D01*
X-66832Y68715D01*
X-66597Y69555D01*
X-66519Y70500D01*
X-66597Y71445D01*
X-66832Y72285D01*
X-67145Y72915D01*
X-67615Y73440D01*
X-68242Y73650D01*
G01X-63665Y68295D02*
X-63195Y67770D01*
X-62647Y67455D01*
X-61942Y67350D01*
X-61237Y67560D01*
X-60689Y67980D01*
X-60297Y68715D01*
X-60219Y69555D01*
X-60375Y70395D01*
X-60767Y70920D01*
X-61315Y71340D01*
X-61864Y71445D01*
X-62412Y71340D01*
X-63117Y70920D01*
X-62882Y73650D01*
X-60767D01*
G01X-55642Y67140D02*
X-55799Y67245D01*
Y67455D01*
X-55642Y67560D01*
X-55485Y67455D01*
Y67245D01*
X-55642Y67140D01*
G01X-49342Y73650D02*
X-49969Y73440D01*
X-50439Y72915D01*
X-50752Y72285D01*
X-50987Y71445D01*
X-51065Y70500D01*
X-50987Y69555D01*
X-50752Y68715D01*
X-50439Y68085D01*
X-49969Y67560D01*
X-49342Y67350D01*
X-48715Y67560D01*
X-48245Y68085D01*
X-47932Y68715D01*
X-47697Y69555D01*
X-47619Y70500D01*
X-47697Y71445D01*
X-47932Y72285D01*
X-48245Y72915D01*
X-48715Y73440D01*
X-49342Y73650D01*
G01X-43042D02*
X-43669Y73440D01*
X-44139Y72915D01*
X-44452Y72285D01*
X-44687Y71445D01*
X-44765Y70500D01*
X-44687Y69555D01*
X-44452Y68715D01*
X-44139Y68085D01*
X-43669Y67560D01*
X-43042Y67350D01*
X-42415Y67560D01*
X-41945Y68085D01*
X-41632Y68715D01*
X-41397Y69555D01*
X-41319Y70500D01*
X-41397Y71445D01*
X-41632Y72285D01*
X-41945Y72915D01*
X-42415Y73440D01*
X-43042Y73650D01*
G01X-81123Y111810D02*
Y118110D01*
X-82063Y116850D01*
G01Y111810D02*
X-80183D01*
G01X-74823D02*
Y118110D01*
X-75763Y116850D01*
G01Y111810D02*
X-73883D01*
G01X-67583D02*
Y118110D01*
X-70481Y113595D01*
X-66565D01*
G01X-63555Y112545D02*
X-63006Y112020D01*
X-62380Y111810D01*
X-61753Y112020D01*
X-61205Y112650D01*
X-60813Y113595D01*
X-60656Y114540D01*
Y115695D01*
X-60813Y116640D01*
X-61205Y117480D01*
X-61675Y117900D01*
X-62223Y118110D01*
X-62850Y117900D01*
X-63320Y117480D01*
X-63633Y116850D01*
X-63790Y116010D01*
X-63633Y115275D01*
X-63241Y114540D01*
X-62771Y114120D01*
X-62223Y114015D01*
X-61596Y114225D01*
X-61126Y114750D01*
X-60656Y115695D01*
G01X-55923Y111600D02*
X-56080Y111705D01*
Y111915D01*
X-55923Y112020D01*
X-55766Y111915D01*
Y111705D01*
X-55923Y111600D01*
G01X-51111Y114435D02*
X-50563Y115170D01*
X-50093Y115590D01*
X-49466Y115800D01*
X-48918Y115590D01*
X-48526Y115170D01*
X-48213Y114540D01*
X-48135Y113805D01*
X-48213Y113175D01*
X-48526Y112545D01*
X-48996Y112020D01*
X-49545Y111810D01*
X-50171Y112020D01*
X-50720Y112650D01*
X-51033Y113595D01*
X-51111Y114645D01*
X-50955Y116010D01*
X-50720Y116745D01*
X-50328Y117480D01*
X-49780Y118005D01*
X-49231Y118110D01*
X-48683Y117900D01*
X-48291Y117375D01*
G01X-43323Y118110D02*
X-43950Y117900D01*
X-44420Y117375D01*
X-44733Y116745D01*
X-44968Y115905D01*
X-45046Y114960D01*
X-44968Y114015D01*
X-44733Y113175D01*
X-44420Y112545D01*
X-43950Y112020D01*
X-43323Y111810D01*
X-42696Y112020D01*
X-42226Y112545D01*
X-41913Y113175D01*
X-41678Y114015D01*
X-41600Y114960D01*
X-41678Y115905D01*
X-41913Y116745D01*
X-42226Y117375D01*
X-42696Y117900D01*
X-43323Y118110D01*
G01X-73711Y208600D02*
X-73241Y209230D01*
X-72693Y209545D01*
X-72066Y209650D01*
X-71283Y209440D01*
X-70735Y208915D01*
X-70578Y208285D01*
X-70656Y207655D01*
X-70970Y207130D01*
X-72536Y206080D01*
X-73241Y205345D01*
X-73711Y204295D01*
X-73868Y203350D01*
X-70578D01*
G01X-65923Y209650D02*
X-66550Y209440D01*
X-67020Y208915D01*
X-67333Y208285D01*
X-67568Y207445D01*
X-67646Y206500D01*
X-67568Y205555D01*
X-67333Y204715D01*
X-67020Y204085D01*
X-66550Y203560D01*
X-65923Y203350D01*
X-65296Y203560D01*
X-64826Y204085D01*
X-64513Y204715D01*
X-64278Y205555D01*
X-64200Y206500D01*
X-64278Y207445D01*
X-64513Y208285D01*
X-64826Y208915D01*
X-65296Y209440D01*
X-65923Y209650D01*
G01X-61111Y205975D02*
X-60563Y206710D01*
X-60093Y207130D01*
X-59466Y207340D01*
X-58918Y207130D01*
X-58526Y206710D01*
X-58213Y206080D01*
X-58135Y205345D01*
X-58213Y204715D01*
X-58526Y204085D01*
X-58996Y203560D01*
X-59545Y203350D01*
X-60171Y203560D01*
X-60720Y204190D01*
X-61033Y205135D01*
X-61111Y206185D01*
X-60955Y207550D01*
X-60720Y208285D01*
X-60328Y209020D01*
X-59780Y209545D01*
X-59231Y209650D01*
X-58683Y209440D01*
X-58291Y208915D01*
G01X-55046Y204295D02*
X-54576Y203770D01*
X-54028Y203455D01*
X-53323Y203350D01*
X-52618Y203560D01*
X-52070Y203980D01*
X-51678Y204715D01*
X-51600Y205555D01*
X-51756Y206395D01*
X-52148Y206920D01*
X-52696Y207340D01*
X-53245Y207445D01*
X-53793Y207340D01*
X-54498Y206920D01*
X-54263Y209650D01*
X-52148D01*
G01X-47023Y203140D02*
X-47180Y203245D01*
Y203455D01*
X-47023Y203560D01*
X-46866Y203455D01*
Y203245D01*
X-47023Y203140D01*
G01X-40723Y209650D02*
X-41350Y209440D01*
X-41820Y208915D01*
X-42133Y208285D01*
X-42368Y207445D01*
X-42446Y206500D01*
X-42368Y205555D01*
X-42133Y204715D01*
X-41820Y204085D01*
X-41350Y203560D01*
X-40723Y203350D01*
X-40096Y203560D01*
X-39626Y204085D01*
X-39313Y204715D01*
X-39078Y205555D01*
X-39000Y206500D01*
X-39078Y207445D01*
X-39313Y208285D01*
X-39626Y208915D01*
X-40096Y209440D01*
X-40723Y209650D01*
G01X-34423D02*
X-35050Y209440D01*
X-35520Y208915D01*
X-35833Y208285D01*
X-36068Y207445D01*
X-36146Y206500D01*
X-36068Y205555D01*
X-35833Y204715D01*
X-35520Y204085D01*
X-35050Y203560D01*
X-34423Y203350D01*
X-33796Y203560D01*
X-33326Y204085D01*
X-33013Y204715D01*
X-32778Y205555D01*
X-32700Y206500D01*
X-32778Y207445D01*
X-33013Y208285D01*
X-33326Y208915D01*
X-33796Y209440D01*
X-34423Y209650D01*
G01X-81841Y338570D02*
X-81371Y337835D01*
X-80745Y337415D01*
X-80040Y337310D01*
X-79413Y337415D01*
X-78786Y337940D01*
X-78395Y338570D01*
X-78316Y339200D01*
X-78473Y339935D01*
X-79021Y340460D01*
X-79570Y340670D01*
X-80275D01*
G01X-79570D02*
X-79100Y340985D01*
X-78708Y341510D01*
X-78551Y342140D01*
X-78708Y342770D01*
X-79100Y343295D01*
X-79805Y343610D01*
X-80510Y343505D01*
X-81215Y343085D01*
G01X-72878Y337310D02*
Y343610D01*
X-75776Y339095D01*
X-71860D01*
G01X-67518Y343610D02*
X-68145Y343400D01*
X-68615Y342875D01*
X-68928Y342245D01*
X-69163Y341405D01*
X-69241Y340460D01*
X-69163Y339515D01*
X-68928Y338675D01*
X-68615Y338045D01*
X-68145Y337520D01*
X-67518Y337310D01*
X-66891Y337520D01*
X-66421Y338045D01*
X-66108Y338675D01*
X-65873Y339515D01*
X-65795Y340460D01*
X-65873Y341405D01*
X-66108Y342245D01*
X-66421Y342875D01*
X-66891Y343400D01*
X-67518Y343610D01*
G01X-60278Y337310D02*
Y343610D01*
X-63176Y339095D01*
X-59260D01*
G01X-54918Y337100D02*
X-55075Y337205D01*
Y337415D01*
X-54918Y337520D01*
X-54761Y337415D01*
Y337205D01*
X-54918Y337100D01*
G01X-50106Y339935D02*
X-49558Y340670D01*
X-49088Y341090D01*
X-48461Y341300D01*
X-47913Y341090D01*
X-47521Y340670D01*
X-47208Y340040D01*
X-47130Y339305D01*
X-47208Y338675D01*
X-47521Y338045D01*
X-47991Y337520D01*
X-48540Y337310D01*
X-49166Y337520D01*
X-49715Y338150D01*
X-50028Y339095D01*
X-50106Y340145D01*
X-49950Y341510D01*
X-49715Y342245D01*
X-49323Y342980D01*
X-48775Y343505D01*
X-48226Y343610D01*
X-47678Y343400D01*
X-47286Y342875D01*
G01X-42318Y343610D02*
X-42945Y343400D01*
X-43415Y342875D01*
X-43728Y342245D01*
X-43963Y341405D01*
X-44041Y340460D01*
X-43963Y339515D01*
X-43728Y338675D01*
X-43415Y338045D01*
X-42945Y337520D01*
X-42318Y337310D01*
X-41691Y337520D01*
X-41221Y338045D01*
X-40908Y338675D01*
X-40673Y339515D01*
X-40595Y340460D01*
X-40673Y341405D01*
X-40908Y342245D01*
X-41221Y342875D01*
X-41691Y343400D01*
X-42318Y343610D01*
G01X-88267Y461810D02*
Y468110D01*
X-91165Y463595D01*
X-87249D01*
G01X-84395Y464435D02*
X-83847Y465170D01*
X-83377Y465590D01*
X-82750Y465800D01*
X-82202Y465590D01*
X-81810Y465170D01*
X-81497Y464540D01*
X-81419Y463805D01*
X-81497Y463175D01*
X-81810Y462545D01*
X-82280Y462020D01*
X-82829Y461810D01*
X-83455Y462020D01*
X-84004Y462650D01*
X-84317Y463595D01*
X-84395Y464645D01*
X-84239Y466010D01*
X-84004Y466745D01*
X-83612Y467480D01*
X-83064Y468005D01*
X-82515Y468110D01*
X-81967Y467900D01*
X-81575Y467375D01*
G01X-75667Y461810D02*
Y468110D01*
X-78565Y463595D01*
X-74649D01*
G01X-71639Y462545D02*
X-71090Y462020D01*
X-70464Y461810D01*
X-69837Y462020D01*
X-69289Y462650D01*
X-68897Y463595D01*
X-68740Y464540D01*
Y465695D01*
X-68897Y466640D01*
X-69289Y467480D01*
X-69759Y467900D01*
X-70307Y468110D01*
X-70934Y467900D01*
X-71404Y467480D01*
X-71717Y466850D01*
X-71874Y466010D01*
X-71717Y465275D01*
X-71325Y464540D01*
X-70855Y464120D01*
X-70307Y464015D01*
X-69680Y464225D01*
X-69210Y464750D01*
X-68740Y465695D01*
G01X-64007Y461600D02*
X-64164Y461705D01*
Y461915D01*
X-64007Y462020D01*
X-63850Y461915D01*
Y461705D01*
X-64007Y461600D01*
G01X-59195Y464435D02*
X-58647Y465170D01*
X-58177Y465590D01*
X-57550Y465800D01*
X-57002Y465590D01*
X-56610Y465170D01*
X-56297Y464540D01*
X-56219Y463805D01*
X-56297Y463175D01*
X-56610Y462545D01*
X-57080Y462020D01*
X-57629Y461810D01*
X-58255Y462020D01*
X-58804Y462650D01*
X-59117Y463595D01*
X-59195Y464645D01*
X-59039Y466010D01*
X-58804Y466745D01*
X-58412Y467480D01*
X-57864Y468005D01*
X-57315Y468110D01*
X-56767Y467900D01*
X-56375Y467375D01*
G01X-51407Y468110D02*
X-52034Y467900D01*
X-52504Y467375D01*
X-52817Y466745D01*
X-53052Y465905D01*
X-53130Y464960D01*
X-53052Y464015D01*
X-52817Y463175D01*
X-52504Y462545D01*
X-52034Y462020D01*
X-51407Y461810D01*
X-50780Y462020D01*
X-50310Y462545D01*
X-49997Y463175D01*
X-49762Y464015D01*
X-49684Y464960D01*
X-49762Y465905D01*
X-49997Y466745D01*
X-50310Y467375D01*
X-50780Y467900D01*
X-51407Y468110D01*
G01X-75764Y552295D02*
X-75294Y551770D01*
X-74746Y551455D01*
X-74041Y551350D01*
X-73336Y551560D01*
X-72788Y551980D01*
X-72396Y552715D01*
X-72318Y553555D01*
X-72474Y554395D01*
X-72866Y554920D01*
X-73414Y555340D01*
X-73963Y555445D01*
X-74511Y555340D01*
X-75216Y554920D01*
X-74981Y557650D01*
X-72866D01*
G01X-69464Y552295D02*
X-68994Y551770D01*
X-68446Y551455D01*
X-67741Y551350D01*
X-67036Y551560D01*
X-66488Y551980D01*
X-66096Y552715D01*
X-66018Y553555D01*
X-66174Y554395D01*
X-66566Y554920D01*
X-67114Y555340D01*
X-67663Y555445D01*
X-68211Y555340D01*
X-68916Y554920D01*
X-68681Y557650D01*
X-66566D01*
G01X-60501Y551350D02*
Y557650D01*
X-63399Y553135D01*
X-59483D01*
G01X-56864Y552295D02*
X-56394Y551770D01*
X-55846Y551455D01*
X-55141Y551350D01*
X-54436Y551560D01*
X-53888Y551980D01*
X-53496Y552715D01*
X-53418Y553555D01*
X-53574Y554395D01*
X-53966Y554920D01*
X-54514Y555340D01*
X-55063Y555445D01*
X-55611Y555340D01*
X-56316Y554920D01*
X-56081Y557650D01*
X-53966D01*
G01X-48841Y551140D02*
X-48998Y551245D01*
Y551455D01*
X-48841Y551560D01*
X-48684Y551455D01*
Y551245D01*
X-48841Y551140D01*
G01X-42541Y557650D02*
X-43168Y557440D01*
X-43638Y556915D01*
X-43951Y556285D01*
X-44186Y555445D01*
X-44264Y554500D01*
X-44186Y553555D01*
X-43951Y552715D01*
X-43638Y552085D01*
X-43168Y551560D01*
X-42541Y551350D01*
X-41914Y551560D01*
X-41444Y552085D01*
X-41131Y552715D01*
X-40896Y553555D01*
X-40818Y554500D01*
X-40896Y555445D01*
X-41131Y556285D01*
X-41444Y556915D01*
X-41914Y557440D01*
X-42541Y557650D01*
G01X-36241D02*
X-36868Y557440D01*
X-37338Y556915D01*
X-37651Y556285D01*
X-37886Y555445D01*
X-37964Y554500D01*
X-37886Y553555D01*
X-37651Y552715D01*
X-37338Y552085D01*
X-36868Y551560D01*
X-36241Y551350D01*
X-35614Y551560D01*
X-35144Y552085D01*
X-34831Y552715D01*
X-34596Y553555D01*
X-34518Y554500D01*
X-34596Y555445D01*
X-34831Y556285D01*
X-35144Y556915D01*
X-35614Y557440D01*
X-36241Y557650D01*
G01X-73712Y811810D02*
X-73164Y811915D01*
X-72537Y812230D01*
X-72145Y812755D01*
X-71989Y813490D01*
X-72145Y814225D01*
X-72615Y814855D01*
X-73320Y815170D01*
X-74104D01*
X-74574Y815380D01*
X-74965Y815905D01*
X-75122Y816640D01*
X-74887Y817375D01*
X-74339Y817900D01*
X-73712Y818110D01*
X-73085Y817900D01*
X-72537Y817375D01*
X-72302Y816640D01*
X-72459Y815905D01*
X-72850Y815380D01*
X-73320Y815170D01*
X-74104D01*
X-74809Y814855D01*
X-75279Y814225D01*
X-75435Y813490D01*
X-75279Y812755D01*
X-74887Y812230D01*
X-74260Y811915D01*
X-73712Y811810D01*
G01X-67412D02*
Y818110D01*
X-68352Y816850D01*
G01Y811810D02*
X-66472D01*
G01X-60172D02*
Y818110D01*
X-63070Y813595D01*
X-59154D01*
G01X-56144Y812545D02*
X-55595Y812020D01*
X-54969Y811810D01*
X-54342Y812020D01*
X-53794Y812650D01*
X-53402Y813595D01*
X-53245Y814540D01*
Y815695D01*
X-53402Y816640D01*
X-53794Y817480D01*
X-54264Y817900D01*
X-54812Y818110D01*
X-55439Y817900D01*
X-55909Y817480D01*
X-56222Y816850D01*
X-56379Y816010D01*
X-56222Y815275D01*
X-55830Y814540D01*
X-55360Y814120D01*
X-54812Y814015D01*
X-54185Y814225D01*
X-53715Y814750D01*
X-53245Y815695D01*
G01X-48512Y811600D02*
X-48669Y811705D01*
Y811915D01*
X-48512Y812020D01*
X-48355Y811915D01*
Y811705D01*
X-48512Y811600D01*
G01X-43700Y814435D02*
X-43152Y815170D01*
X-42682Y815590D01*
X-42055Y815800D01*
X-41507Y815590D01*
X-41115Y815170D01*
X-40802Y814540D01*
X-40724Y813805D01*
X-40802Y813175D01*
X-41115Y812545D01*
X-41585Y812020D01*
X-42134Y811810D01*
X-42760Y812020D01*
X-43309Y812650D01*
X-43622Y813595D01*
X-43700Y814645D01*
X-43544Y816010D01*
X-43309Y816745D01*
X-42917Y817480D01*
X-42369Y818005D01*
X-41820Y818110D01*
X-41272Y817900D01*
X-40880Y817375D01*
G01X-35912Y818110D02*
X-36539Y817900D01*
X-37009Y817375D01*
X-37322Y816745D01*
X-37557Y815905D01*
X-37635Y814960D01*
X-37557Y814015D01*
X-37322Y813175D01*
X-37009Y812545D01*
X-36539Y812020D01*
X-35912Y811810D01*
X-35285Y812020D01*
X-34815Y812545D01*
X-34502Y813175D01*
X-34267Y814015D01*
X-34189Y814960D01*
X-34267Y815905D01*
X-34502Y816745D01*
X-34815Y817375D01*
X-35285Y817900D01*
X-35912Y818110D01*
G01X-89343Y1051456D02*
Y1057756D01*
X-90283Y1056496D01*
G01Y1051456D02*
X-88403D01*
G01X-83043Y1057756D02*
X-83670Y1057546D01*
X-84140Y1057021D01*
X-84453Y1056391D01*
X-84688Y1055551D01*
X-84766Y1054606D01*
X-84688Y1053661D01*
X-84453Y1052821D01*
X-84140Y1052191D01*
X-83670Y1051666D01*
X-83043Y1051456D01*
X-82416Y1051666D01*
X-81946Y1052191D01*
X-81633Y1052821D01*
X-81398Y1053661D01*
X-81320Y1054606D01*
X-81398Y1055551D01*
X-81633Y1056391D01*
X-81946Y1057021D01*
X-82416Y1057546D01*
X-83043Y1057756D01*
G01X-78466Y1052401D02*
X-77996Y1051876D01*
X-77448Y1051561D01*
X-76743Y1051456D01*
X-76038Y1051666D01*
X-75490Y1052086D01*
X-75098Y1052821D01*
X-75020Y1053661D01*
X-75176Y1054501D01*
X-75568Y1055026D01*
X-76116Y1055446D01*
X-76665Y1055551D01*
X-77213Y1055446D01*
X-77918Y1055026D01*
X-77683Y1057756D01*
X-75568D01*
G01X-69503Y1051456D02*
Y1057756D01*
X-72401Y1053241D01*
X-68485D01*
G01X-65631Y1054081D02*
X-65083Y1054816D01*
X-64613Y1055236D01*
X-63986Y1055446D01*
X-63438Y1055236D01*
X-63046Y1054816D01*
X-62733Y1054186D01*
X-62655Y1053451D01*
X-62733Y1052821D01*
X-63046Y1052191D01*
X-63516Y1051666D01*
X-64065Y1051456D01*
X-64691Y1051666D01*
X-65240Y1052296D01*
X-65553Y1053241D01*
X-65631Y1054291D01*
X-65475Y1055656D01*
X-65240Y1056391D01*
X-64848Y1057126D01*
X-64300Y1057651D01*
X-63751Y1057756D01*
X-63203Y1057546D01*
X-62811Y1057021D01*
G01X-57843Y1051246D02*
X-58000Y1051351D01*
Y1051561D01*
X-57843Y1051666D01*
X-57686Y1051561D01*
Y1051351D01*
X-57843Y1051246D01*
G01X-51543Y1057756D02*
X-52170Y1057546D01*
X-52640Y1057021D01*
X-52953Y1056391D01*
X-53188Y1055551D01*
X-53266Y1054606D01*
X-53188Y1053661D01*
X-52953Y1052821D01*
X-52640Y1052191D01*
X-52170Y1051666D01*
X-51543Y1051456D01*
X-50916Y1051666D01*
X-50446Y1052191D01*
X-50133Y1052821D01*
X-49898Y1053661D01*
X-49820Y1054606D01*
X-49898Y1055551D01*
X-50133Y1056391D01*
X-50446Y1057021D01*
X-50916Y1057546D01*
X-51543Y1057756D01*
G01X-46731Y1054081D02*
X-46183Y1054816D01*
X-45713Y1055236D01*
X-45086Y1055446D01*
X-44538Y1055236D01*
X-44146Y1054816D01*
X-43833Y1054186D01*
X-43755Y1053451D01*
X-43833Y1052821D01*
X-44146Y1052191D01*
X-44616Y1051666D01*
X-45165Y1051456D01*
X-45791Y1051666D01*
X-46340Y1052296D01*
X-46653Y1053241D01*
X-46731Y1054291D01*
X-46575Y1055656D01*
X-46340Y1056391D01*
X-45948Y1057126D01*
X-45400Y1057651D01*
X-44851Y1057756D01*
X-44303Y1057546D01*
X-43911Y1057021D01*
G01X-71810Y1161810D02*
Y1168110D01*
X-72750Y1166850D01*
G01Y1161810D02*
X-70870D01*
G01X-65510D02*
Y1168110D01*
X-66450Y1166850D01*
G01Y1161810D02*
X-64570D01*
G01X-60698Y1164435D02*
X-60150Y1165170D01*
X-59680Y1165590D01*
X-59053Y1165800D01*
X-58505Y1165590D01*
X-58113Y1165170D01*
X-57800Y1164540D01*
X-57722Y1163805D01*
X-57800Y1163175D01*
X-58113Y1162545D01*
X-58583Y1162020D01*
X-59132Y1161810D01*
X-59758Y1162020D01*
X-60307Y1162650D01*
X-60620Y1163595D01*
X-60698Y1164645D01*
X-60542Y1166010D01*
X-60307Y1166745D01*
X-59915Y1167480D01*
X-59367Y1168005D01*
X-58818Y1168110D01*
X-58270Y1167900D01*
X-57878Y1167375D01*
G01X-51970Y1161810D02*
Y1168110D01*
X-54868Y1163595D01*
X-50952D01*
G01X-47942Y1162545D02*
X-47393Y1162020D01*
X-46767Y1161810D01*
X-46140Y1162020D01*
X-45592Y1162650D01*
X-45200Y1163595D01*
X-45043Y1164540D01*
Y1165695D01*
X-45200Y1166640D01*
X-45592Y1167480D01*
X-46062Y1167900D01*
X-46610Y1168110D01*
X-47237Y1167900D01*
X-47707Y1167480D01*
X-48020Y1166850D01*
X-48177Y1166010D01*
X-48020Y1165275D01*
X-47628Y1164540D01*
X-47158Y1164120D01*
X-46610Y1164015D01*
X-45983Y1164225D01*
X-45513Y1164750D01*
X-45043Y1165695D01*
G01X-40310Y1161600D02*
X-40467Y1161705D01*
Y1161915D01*
X-40310Y1162020D01*
X-40153Y1161915D01*
Y1161705D01*
X-40310Y1161600D01*
G01X-35498Y1164435D02*
X-34950Y1165170D01*
X-34480Y1165590D01*
X-33853Y1165800D01*
X-33305Y1165590D01*
X-32913Y1165170D01*
X-32600Y1164540D01*
X-32522Y1163805D01*
X-32600Y1163175D01*
X-32913Y1162545D01*
X-33383Y1162020D01*
X-33932Y1161810D01*
X-34558Y1162020D01*
X-35107Y1162650D01*
X-35420Y1163595D01*
X-35498Y1164645D01*
X-35342Y1166010D01*
X-35107Y1166745D01*
X-34715Y1167480D01*
X-34167Y1168005D01*
X-33618Y1168110D01*
X-33070Y1167900D01*
X-32678Y1167375D01*
G01X-27710Y1168110D02*
X-28337Y1167900D01*
X-28807Y1167375D01*
X-29120Y1166745D01*
X-29355Y1165905D01*
X-29433Y1164960D01*
X-29355Y1164015D01*
X-29120Y1163175D01*
X-28807Y1162545D01*
X-28337Y1162020D01*
X-27710Y1161810D01*
X-27083Y1162020D01*
X-26613Y1162545D01*
X-26300Y1163175D01*
X-26065Y1164015D01*
X-25987Y1164960D01*
X-26065Y1165905D01*
X-26300Y1166745D01*
X-26613Y1167375D01*
X-27083Y1167900D01*
X-27710Y1168110D01*
G01X-90559Y1339448D02*
Y1345748D01*
X-91499Y1344488D01*
G01Y1339448D02*
X-89619D01*
G01X-85982Y1340708D02*
X-85512Y1339973D01*
X-84886Y1339553D01*
X-84181Y1339448D01*
X-83554Y1339553D01*
X-82927Y1340078D01*
X-82536Y1340708D01*
X-82457Y1341338D01*
X-82614Y1342073D01*
X-83162Y1342598D01*
X-83711Y1342808D01*
X-84416D01*
G01X-83711D02*
X-83241Y1343123D01*
X-82849Y1343648D01*
X-82692Y1344278D01*
X-82849Y1344908D01*
X-83241Y1345433D01*
X-83946Y1345748D01*
X-84651Y1345643D01*
X-85356Y1345223D01*
G01X-77019Y1339448D02*
Y1345748D01*
X-79917Y1341233D01*
X-76001D01*
G01X-73147Y1344698D02*
X-72677Y1345328D01*
X-72129Y1345643D01*
X-71502Y1345748D01*
X-70719Y1345538D01*
X-70171Y1345013D01*
X-70014Y1344383D01*
X-70092Y1343753D01*
X-70406Y1343228D01*
X-71972Y1342178D01*
X-72677Y1341443D01*
X-73147Y1340393D01*
X-73304Y1339448D01*
X-70014D01*
G01X-67082Y1340393D02*
X-66612Y1339868D01*
X-66064Y1339553D01*
X-65359Y1339448D01*
X-64654Y1339658D01*
X-64106Y1340078D01*
X-63714Y1340813D01*
X-63636Y1341653D01*
X-63792Y1342493D01*
X-64184Y1343018D01*
X-64732Y1343438D01*
X-65281Y1343543D01*
X-65829Y1343438D01*
X-66534Y1343018D01*
X-66299Y1345748D01*
X-64184D01*
G01X-59059Y1339238D02*
X-59216Y1339343D01*
Y1339553D01*
X-59059Y1339658D01*
X-58902Y1339553D01*
Y1339343D01*
X-59059Y1339238D01*
G01X-54091Y1340183D02*
X-53542Y1339658D01*
X-52916Y1339448D01*
X-52289Y1339658D01*
X-51741Y1340288D01*
X-51349Y1341233D01*
X-51192Y1342178D01*
Y1343333D01*
X-51349Y1344278D01*
X-51741Y1345118D01*
X-52211Y1345538D01*
X-52759Y1345748D01*
X-53386Y1345538D01*
X-53856Y1345118D01*
X-54169Y1344488D01*
X-54326Y1343648D01*
X-54169Y1342913D01*
X-53777Y1342178D01*
X-53307Y1341758D01*
X-52759Y1341653D01*
X-52132Y1341863D01*
X-51662Y1342388D01*
X-51192Y1343333D01*
G01X-46459Y1339448D02*
X-45911Y1339553D01*
X-45284Y1339868D01*
X-44892Y1340393D01*
X-44736Y1341128D01*
X-44892Y1341863D01*
X-45362Y1342493D01*
X-46067Y1342808D01*
X-46851D01*
X-47321Y1343018D01*
X-47712Y1343543D01*
X-47869Y1344278D01*
X-47634Y1345013D01*
X-47086Y1345538D01*
X-46459Y1345748D01*
X-45832Y1345538D01*
X-45284Y1345013D01*
X-45049Y1344278D01*
X-45206Y1343543D01*
X-45597Y1343018D01*
X-46067Y1342808D01*
X-46851D01*
X-47556Y1342493D01*
X-48026Y1341863D01*
X-48182Y1341128D01*
X-48026Y1340393D01*
X-47634Y1339868D01*
X-47007Y1339553D01*
X-46459Y1339448D01*
G01X-72162Y1511810D02*
Y1518110D01*
X-73102Y1516850D01*
G01Y1511810D02*
X-71222D01*
G01X-67585Y1512755D02*
X-67115Y1512230D01*
X-66567Y1511915D01*
X-65862Y1511810D01*
X-65157Y1512020D01*
X-64609Y1512440D01*
X-64217Y1513175D01*
X-64139Y1514015D01*
X-64295Y1514855D01*
X-64687Y1515380D01*
X-65235Y1515800D01*
X-65784Y1515905D01*
X-66332Y1515800D01*
X-67037Y1515380D01*
X-66802Y1518110D01*
X-64687D01*
G01X-59562Y1511810D02*
Y1518110D01*
X-60502Y1516850D01*
G01Y1511810D02*
X-58622D01*
G01X-52322D02*
Y1518110D01*
X-55220Y1513595D01*
X-51304D01*
G01X-48294Y1512545D02*
X-47745Y1512020D01*
X-47119Y1511810D01*
X-46492Y1512020D01*
X-45944Y1512650D01*
X-45552Y1513595D01*
X-45395Y1514540D01*
Y1515695D01*
X-45552Y1516640D01*
X-45944Y1517480D01*
X-46414Y1517900D01*
X-46962Y1518110D01*
X-47589Y1517900D01*
X-48059Y1517480D01*
X-48372Y1516850D01*
X-48529Y1516010D01*
X-48372Y1515275D01*
X-47980Y1514540D01*
X-47510Y1514120D01*
X-46962Y1514015D01*
X-46335Y1514225D01*
X-45865Y1514750D01*
X-45395Y1515695D01*
G01X-40662Y1511600D02*
X-40819Y1511705D01*
Y1511915D01*
X-40662Y1512020D01*
X-40505Y1511915D01*
Y1511705D01*
X-40662Y1511600D01*
G01X-35850Y1514435D02*
X-35302Y1515170D01*
X-34832Y1515590D01*
X-34205Y1515800D01*
X-33657Y1515590D01*
X-33265Y1515170D01*
X-32952Y1514540D01*
X-32874Y1513805D01*
X-32952Y1513175D01*
X-33265Y1512545D01*
X-33735Y1512020D01*
X-34284Y1511810D01*
X-34910Y1512020D01*
X-35459Y1512650D01*
X-35772Y1513595D01*
X-35850Y1514645D01*
X-35694Y1516010D01*
X-35459Y1516745D01*
X-35067Y1517480D01*
X-34519Y1518005D01*
X-33970Y1518110D01*
X-33422Y1517900D01*
X-33030Y1517375D01*
G01X-28062Y1518110D02*
X-28689Y1517900D01*
X-29159Y1517375D01*
X-29472Y1516745D01*
X-29707Y1515905D01*
X-29785Y1514960D01*
X-29707Y1514015D01*
X-29472Y1513175D01*
X-29159Y1512545D01*
X-28689Y1512020D01*
X-28062Y1511810D01*
X-27435Y1512020D01*
X-26965Y1512545D01*
X-26652Y1513175D01*
X-26417Y1514015D01*
X-26339Y1514960D01*
X-26417Y1515905D01*
X-26652Y1516745D01*
X-26965Y1517375D01*
X-27435Y1517900D01*
X-28062Y1518110D01*
G01X-70511Y1609354D02*
Y1615654D01*
X-71451Y1614394D01*
G01Y1609354D02*
X-69571D01*
G01X-65699Y1611979D02*
X-65151Y1612714D01*
X-64681Y1613134D01*
X-64054Y1613344D01*
X-63506Y1613134D01*
X-63114Y1612714D01*
X-62801Y1612084D01*
X-62723Y1611349D01*
X-62801Y1610719D01*
X-63114Y1610089D01*
X-63584Y1609564D01*
X-64133Y1609354D01*
X-64759Y1609564D01*
X-65308Y1610194D01*
X-65621Y1611139D01*
X-65699Y1612189D01*
X-65543Y1613554D01*
X-65308Y1614289D01*
X-64916Y1615024D01*
X-64368Y1615549D01*
X-63819Y1615654D01*
X-63271Y1615444D01*
X-62879Y1614919D01*
G01X-57911Y1609354D02*
Y1615654D01*
X-58851Y1614394D01*
G01Y1609354D02*
X-56971D01*
G01X-53099Y1614604D02*
X-52629Y1615234D01*
X-52081Y1615549D01*
X-51454Y1615654D01*
X-50671Y1615444D01*
X-50123Y1614919D01*
X-49966Y1614289D01*
X-50044Y1613659D01*
X-50358Y1613134D01*
X-51924Y1612084D01*
X-52629Y1611349D01*
X-53099Y1610299D01*
X-53256Y1609354D01*
X-49966D01*
G01X-47034Y1610299D02*
X-46564Y1609774D01*
X-46016Y1609459D01*
X-45311Y1609354D01*
X-44606Y1609564D01*
X-44058Y1609984D01*
X-43666Y1610719D01*
X-43588Y1611559D01*
X-43744Y1612399D01*
X-44136Y1612924D01*
X-44684Y1613344D01*
X-45233Y1613449D01*
X-45781Y1613344D01*
X-46486Y1612924D01*
X-46251Y1615654D01*
X-44136D01*
G01X-39011Y1609144D02*
X-39168Y1609249D01*
Y1609459D01*
X-39011Y1609564D01*
X-38854Y1609459D01*
Y1609249D01*
X-39011Y1609144D01*
G01X-32711Y1615654D02*
X-33338Y1615444D01*
X-33808Y1614919D01*
X-34121Y1614289D01*
X-34356Y1613449D01*
X-34434Y1612504D01*
X-34356Y1611559D01*
X-34121Y1610719D01*
X-33808Y1610089D01*
X-33338Y1609564D01*
X-32711Y1609354D01*
X-32084Y1609564D01*
X-31614Y1610089D01*
X-31301Y1610719D01*
X-31066Y1611559D01*
X-30988Y1612504D01*
X-31066Y1613449D01*
X-31301Y1614289D01*
X-31614Y1614919D01*
X-32084Y1615444D01*
X-32711Y1615654D01*
G01X-25471Y1609354D02*
Y1615654D01*
X-28369Y1611139D01*
X-24453D01*
G01X-72821Y1861811D02*
Y1868111D01*
X-73761Y1866851D01*
G01Y1861811D02*
X-71881D01*
G01X-66521D02*
X-65973Y1861916D01*
X-65346Y1862231D01*
X-64954Y1862756D01*
X-64798Y1863491D01*
X-64954Y1864226D01*
X-65424Y1864856D01*
X-66129Y1865171D01*
X-66913D01*
X-67383Y1865381D01*
X-67774Y1865906D01*
X-67931Y1866641D01*
X-67696Y1867376D01*
X-67148Y1867901D01*
X-66521Y1868111D01*
X-65894Y1867901D01*
X-65346Y1867376D01*
X-65111Y1866641D01*
X-65268Y1865906D01*
X-65659Y1865381D01*
X-66129Y1865171D01*
X-66913D01*
X-67618Y1864856D01*
X-68088Y1864226D01*
X-68244Y1863491D01*
X-68088Y1862756D01*
X-67696Y1862231D01*
X-67069Y1861916D01*
X-66521Y1861811D01*
G01X-61709Y1864436D02*
X-61161Y1865171D01*
X-60691Y1865591D01*
X-60064Y1865801D01*
X-59516Y1865591D01*
X-59124Y1865171D01*
X-58811Y1864541D01*
X-58733Y1863806D01*
X-58811Y1863176D01*
X-59124Y1862546D01*
X-59594Y1862021D01*
X-60143Y1861811D01*
X-60769Y1862021D01*
X-61318Y1862651D01*
X-61631Y1863596D01*
X-61709Y1864646D01*
X-61553Y1866011D01*
X-61318Y1866746D01*
X-60926Y1867481D01*
X-60378Y1868006D01*
X-59829Y1868111D01*
X-59281Y1867901D01*
X-58889Y1867376D01*
G01X-52981Y1861811D02*
Y1868111D01*
X-55879Y1863596D01*
X-51963D01*
G01X-48953Y1862546D02*
X-48404Y1862021D01*
X-47778Y1861811D01*
X-47151Y1862021D01*
X-46603Y1862651D01*
X-46211Y1863596D01*
X-46054Y1864541D01*
Y1865696D01*
X-46211Y1866641D01*
X-46603Y1867481D01*
X-47073Y1867901D01*
X-47621Y1868111D01*
X-48248Y1867901D01*
X-48718Y1867481D01*
X-49031Y1866851D01*
X-49188Y1866011D01*
X-49031Y1865276D01*
X-48639Y1864541D01*
X-48169Y1864121D01*
X-47621Y1864016D01*
X-46994Y1864226D01*
X-46524Y1864751D01*
X-46054Y1865696D01*
G01X-41321Y1861601D02*
X-41478Y1861706D01*
Y1861916D01*
X-41321Y1862021D01*
X-41164Y1861916D01*
Y1861706D01*
X-41321Y1861601D01*
G01X-36509Y1864436D02*
X-35961Y1865171D01*
X-35491Y1865591D01*
X-34864Y1865801D01*
X-34316Y1865591D01*
X-33924Y1865171D01*
X-33611Y1864541D01*
X-33533Y1863806D01*
X-33611Y1863176D01*
X-33924Y1862546D01*
X-34394Y1862021D01*
X-34943Y1861811D01*
X-35569Y1862021D01*
X-36118Y1862651D01*
X-36431Y1863596D01*
X-36509Y1864646D01*
X-36353Y1866011D01*
X-36118Y1866746D01*
X-35726Y1867481D01*
X-35178Y1868006D01*
X-34629Y1868111D01*
X-34081Y1867901D01*
X-33689Y1867376D01*
G01X-28721Y1861811D02*
Y1868111D01*
X-29661Y1866851D01*
G01Y1861811D02*
X-27781D01*
G01X-74765Y1875480D02*
Y1881780D01*
X-75705Y1880520D01*
G01Y1875480D02*
X-73825D01*
G01X-68465D02*
X-67917Y1875585D01*
X-67290Y1875900D01*
X-66898Y1876425D01*
X-66742Y1877160D01*
X-66898Y1877895D01*
X-67368Y1878525D01*
X-68073Y1878840D01*
X-68857D01*
X-69327Y1879050D01*
X-69718Y1879575D01*
X-69875Y1880310D01*
X-69640Y1881045D01*
X-69092Y1881570D01*
X-68465Y1881780D01*
X-67838Y1881570D01*
X-67290Y1881045D01*
X-67055Y1880310D01*
X-67212Y1879575D01*
X-67603Y1879050D01*
X-68073Y1878840D01*
X-68857D01*
X-69562Y1878525D01*
X-70032Y1877895D01*
X-70188Y1877160D01*
X-70032Y1876425D01*
X-69640Y1875900D01*
X-69013Y1875585D01*
X-68465Y1875480D01*
G01X-62322D02*
X-62165Y1876845D01*
X-61930Y1878000D01*
X-61617Y1879050D01*
X-61225Y1880205D01*
X-60598Y1881780D01*
X-63732D01*
G01X-55865Y1875480D02*
X-55317Y1875585D01*
X-54690Y1875900D01*
X-54298Y1876425D01*
X-54142Y1877160D01*
X-54298Y1877895D01*
X-54768Y1878525D01*
X-55473Y1878840D01*
X-56257D01*
X-56727Y1879050D01*
X-57118Y1879575D01*
X-57275Y1880310D01*
X-57040Y1881045D01*
X-56492Y1881570D01*
X-55865Y1881780D01*
X-55238Y1881570D01*
X-54690Y1881045D01*
X-54455Y1880310D01*
X-54612Y1879575D01*
X-55003Y1879050D01*
X-55473Y1878840D01*
X-56257D01*
X-56962Y1878525D01*
X-57432Y1877895D01*
X-57588Y1877160D01*
X-57432Y1876425D01*
X-57040Y1875900D01*
X-56413Y1875585D01*
X-55865Y1875480D01*
G01X-51053Y1878105D02*
X-50505Y1878840D01*
X-50035Y1879260D01*
X-49408Y1879470D01*
X-48860Y1879260D01*
X-48468Y1878840D01*
X-48155Y1878210D01*
X-48077Y1877475D01*
X-48155Y1876845D01*
X-48468Y1876215D01*
X-48938Y1875690D01*
X-49487Y1875480D01*
X-50113Y1875690D01*
X-50662Y1876320D01*
X-50975Y1877265D01*
X-51053Y1878315D01*
X-50897Y1879680D01*
X-50662Y1880415D01*
X-50270Y1881150D01*
X-49722Y1881675D01*
X-49173Y1881780D01*
X-48625Y1881570D01*
X-48233Y1881045D01*
G01X-43265Y1875270D02*
X-43422Y1875375D01*
Y1875585D01*
X-43265Y1875690D01*
X-43108Y1875585D01*
Y1875375D01*
X-43265Y1875270D01*
G01X-38688Y1876740D02*
X-38218Y1876005D01*
X-37592Y1875585D01*
X-36887Y1875480D01*
X-36260Y1875585D01*
X-35633Y1876110D01*
X-35242Y1876740D01*
X-35163Y1877370D01*
X-35320Y1878105D01*
X-35868Y1878630D01*
X-36417Y1878840D01*
X-37122D01*
G01X-36417D02*
X-35947Y1879155D01*
X-35555Y1879680D01*
X-35398Y1880310D01*
X-35555Y1880940D01*
X-35947Y1881465D01*
X-36652Y1881780D01*
X-37357Y1881675D01*
X-38062Y1881255D01*
G01X-30665Y1881780D02*
X-31292Y1881570D01*
X-31762Y1881045D01*
X-32075Y1880415D01*
X-32310Y1879575D01*
X-32388Y1878630D01*
X-32310Y1877685D01*
X-32075Y1876845D01*
X-31762Y1876215D01*
X-31292Y1875690D01*
X-30665Y1875480D01*
X-30038Y1875690D01*
X-29568Y1876215D01*
X-29255Y1876845D01*
X-29020Y1877685D01*
X-28942Y1878630D01*
X-29020Y1879575D01*
X-29255Y1880415D01*
X-29568Y1881045D01*
X-30038Y1881570D01*
X-30665Y1881780D01*
G01X-75980Y1957479D02*
Y1963779D01*
X-76920Y1962519D01*
G01Y1957479D02*
X-75040D01*
G01X-71012Y1958214D02*
X-70463Y1957689D01*
X-69837Y1957479D01*
X-69210Y1957689D01*
X-68662Y1958319D01*
X-68270Y1959264D01*
X-68113Y1960209D01*
Y1961364D01*
X-68270Y1962309D01*
X-68662Y1963149D01*
X-69132Y1963569D01*
X-69680Y1963779D01*
X-70307Y1963569D01*
X-70777Y1963149D01*
X-71090Y1962519D01*
X-71247Y1961679D01*
X-71090Y1960944D01*
X-70698Y1960209D01*
X-70228Y1959789D01*
X-69680Y1959684D01*
X-69053Y1959894D01*
X-68583Y1960419D01*
X-68113Y1961364D01*
G01X-64868Y1960104D02*
X-64320Y1960839D01*
X-63850Y1961259D01*
X-63223Y1961469D01*
X-62675Y1961259D01*
X-62283Y1960839D01*
X-61970Y1960209D01*
X-61892Y1959474D01*
X-61970Y1958844D01*
X-62283Y1958214D01*
X-62753Y1957689D01*
X-63302Y1957479D01*
X-63928Y1957689D01*
X-64477Y1958319D01*
X-64790Y1959264D01*
X-64868Y1960314D01*
X-64712Y1961679D01*
X-64477Y1962414D01*
X-64085Y1963149D01*
X-63537Y1963674D01*
X-62988Y1963779D01*
X-62440Y1963569D01*
X-62048Y1963044D01*
G01X-57080Y1963779D02*
X-57707Y1963569D01*
X-58177Y1963044D01*
X-58490Y1962414D01*
X-58725Y1961574D01*
X-58803Y1960629D01*
X-58725Y1959684D01*
X-58490Y1958844D01*
X-58177Y1958214D01*
X-57707Y1957689D01*
X-57080Y1957479D01*
X-56453Y1957689D01*
X-55983Y1958214D01*
X-55670Y1958844D01*
X-55435Y1959684D01*
X-55357Y1960629D01*
X-55435Y1961574D01*
X-55670Y1962414D01*
X-55983Y1963044D01*
X-56453Y1963569D01*
X-57080Y1963779D01*
G01X-52268Y1960104D02*
X-51720Y1960839D01*
X-51250Y1961259D01*
X-50623Y1961469D01*
X-50075Y1961259D01*
X-49683Y1960839D01*
X-49370Y1960209D01*
X-49292Y1959474D01*
X-49370Y1958844D01*
X-49683Y1958214D01*
X-50153Y1957689D01*
X-50702Y1957479D01*
X-51328Y1957689D01*
X-51877Y1958319D01*
X-52190Y1959264D01*
X-52268Y1960314D01*
X-52112Y1961679D01*
X-51877Y1962414D01*
X-51485Y1963149D01*
X-50937Y1963674D01*
X-50388Y1963779D01*
X-49840Y1963569D01*
X-49448Y1963044D01*
G01X-44480Y1957269D02*
X-44637Y1957374D01*
Y1957584D01*
X-44480Y1957689D01*
X-44323Y1957584D01*
Y1957374D01*
X-44480Y1957269D01*
G01X-39668Y1962729D02*
X-39198Y1963359D01*
X-38650Y1963674D01*
X-38023Y1963779D01*
X-37240Y1963569D01*
X-36692Y1963044D01*
X-36535Y1962414D01*
X-36613Y1961784D01*
X-36927Y1961259D01*
X-38493Y1960209D01*
X-39198Y1959474D01*
X-39668Y1958424D01*
X-39825Y1957479D01*
X-36535D01*
G01X-33212Y1958214D02*
X-32663Y1957689D01*
X-32037Y1957479D01*
X-31410Y1957689D01*
X-30862Y1958319D01*
X-30470Y1959264D01*
X-30313Y1960209D01*
Y1961364D01*
X-30470Y1962309D01*
X-30862Y1963149D01*
X-31332Y1963569D01*
X-31880Y1963779D01*
X-32507Y1963569D01*
X-32977Y1963149D01*
X-33290Y1962519D01*
X-33447Y1961679D01*
X-33290Y1960944D01*
X-32898Y1960209D01*
X-32428Y1959789D01*
X-31880Y1959684D01*
X-31253Y1959894D01*
X-30783Y1960419D01*
X-30313Y1961364D01*
G01X-73823Y2037729D02*
X-73353Y2038359D01*
X-72805Y2038674D01*
X-72178Y2038779D01*
X-71395Y2038569D01*
X-70847Y2038044D01*
X-70690Y2037414D01*
X-70768Y2036784D01*
X-71082Y2036259D01*
X-72648Y2035209D01*
X-73353Y2034474D01*
X-73823Y2033424D01*
X-73980Y2032479D01*
X-70690D01*
G01X-66035Y2038779D02*
X-66662Y2038569D01*
X-67132Y2038044D01*
X-67445Y2037414D01*
X-67680Y2036574D01*
X-67758Y2035629D01*
X-67680Y2034684D01*
X-67445Y2033844D01*
X-67132Y2033214D01*
X-66662Y2032689D01*
X-66035Y2032479D01*
X-65408Y2032689D01*
X-64938Y2033214D01*
X-64625Y2033844D01*
X-64390Y2034684D01*
X-64312Y2035629D01*
X-64390Y2036574D01*
X-64625Y2037414D01*
X-64938Y2038044D01*
X-65408Y2038569D01*
X-66035Y2038779D01*
G01X-61458Y2033739D02*
X-60988Y2033004D01*
X-60362Y2032584D01*
X-59657Y2032479D01*
X-59030Y2032584D01*
X-58403Y2033109D01*
X-58012Y2033739D01*
X-57933Y2034369D01*
X-58090Y2035104D01*
X-58638Y2035629D01*
X-59187Y2035839D01*
X-59892D01*
G01X-59187D02*
X-58717Y2036154D01*
X-58325Y2036679D01*
X-58168Y2037309D01*
X-58325Y2037939D01*
X-58717Y2038464D01*
X-59422Y2038779D01*
X-60127Y2038674D01*
X-60832Y2038254D01*
G01X-55158Y2033424D02*
X-54688Y2032899D01*
X-54140Y2032584D01*
X-53435Y2032479D01*
X-52730Y2032689D01*
X-52182Y2033109D01*
X-51790Y2033844D01*
X-51712Y2034684D01*
X-51868Y2035524D01*
X-52260Y2036049D01*
X-52808Y2036469D01*
X-53357Y2036574D01*
X-53905Y2036469D01*
X-54610Y2036049D01*
X-54375Y2038779D01*
X-52260D01*
G01X-48623Y2035104D02*
X-48075Y2035839D01*
X-47605Y2036259D01*
X-46978Y2036469D01*
X-46430Y2036259D01*
X-46038Y2035839D01*
X-45725Y2035209D01*
X-45647Y2034474D01*
X-45725Y2033844D01*
X-46038Y2033214D01*
X-46508Y2032689D01*
X-47057Y2032479D01*
X-47683Y2032689D01*
X-48232Y2033319D01*
X-48545Y2034264D01*
X-48623Y2035314D01*
X-48467Y2036679D01*
X-48232Y2037414D01*
X-47840Y2038149D01*
X-47292Y2038674D01*
X-46743Y2038779D01*
X-46195Y2038569D01*
X-45803Y2038044D01*
G01X-40835Y2032269D02*
X-40992Y2032374D01*
Y2032584D01*
X-40835Y2032689D01*
X-40678Y2032584D01*
Y2032374D01*
X-40835Y2032269D01*
G01X-36023Y2037729D02*
X-35553Y2038359D01*
X-35005Y2038674D01*
X-34378Y2038779D01*
X-33595Y2038569D01*
X-33047Y2038044D01*
X-32890Y2037414D01*
X-32968Y2036784D01*
X-33282Y2036259D01*
X-34848Y2035209D01*
X-35553Y2034474D01*
X-36023Y2033424D01*
X-36180Y2032479D01*
X-32890D01*
G01X-29567Y2033214D02*
X-29018Y2032689D01*
X-28392Y2032479D01*
X-27765Y2032689D01*
X-27217Y2033319D01*
X-26825Y2034264D01*
X-26668Y2035209D01*
Y2036364D01*
X-26825Y2037309D01*
X-27217Y2038149D01*
X-27687Y2038569D01*
X-28235Y2038779D01*
X-28862Y2038569D01*
X-29332Y2038149D01*
X-29645Y2037519D01*
X-29802Y2036679D01*
X-29645Y2035944D01*
X-29253Y2035209D01*
X-28783Y2034789D01*
X-28235Y2034684D01*
X-27608Y2034894D01*
X-27138Y2035419D01*
X-26668Y2036364D01*
G01X-65235Y122479D02*
Y128779D01*
X-66175Y127519D01*
G01Y122479D02*
X-64295D01*
G01X-60423Y127729D02*
X-59953Y128359D01*
X-59405Y128674D01*
X-58778Y128779D01*
X-57995Y128569D01*
X-57447Y128044D01*
X-57290Y127414D01*
X-57368Y126784D01*
X-57682Y126259D01*
X-59248Y125209D01*
X-59953Y124474D01*
X-60423Y123424D01*
X-60580Y122479D01*
X-57290D01*
G01X-54358Y123424D02*
X-53888Y122899D01*
X-53340Y122584D01*
X-52635Y122479D01*
X-51930Y122689D01*
X-51382Y123109D01*
X-50990Y123844D01*
X-50912Y124684D01*
X-51068Y125524D01*
X-51460Y126049D01*
X-52008Y126469D01*
X-52557Y126574D01*
X-53105Y126469D01*
X-53810Y126049D01*
X-53575Y128779D01*
X-51460D01*
G01X-47823Y125104D02*
X-47275Y125839D01*
X-46805Y126259D01*
X-46178Y126469D01*
X-45630Y126259D01*
X-45238Y125839D01*
X-44925Y125209D01*
X-44847Y124474D01*
X-44925Y123844D01*
X-45238Y123214D01*
X-45708Y122689D01*
X-46257Y122479D01*
X-46883Y122689D01*
X-47432Y123319D01*
X-47745Y124264D01*
X-47823Y125314D01*
X-47667Y126679D01*
X-47432Y127414D01*
X-47040Y128149D01*
X-46492Y128674D01*
X-45943Y128779D01*
X-45395Y128569D01*
X-45003Y128044D01*
G01X-40035Y122269D02*
X-40192Y122374D01*
Y122584D01*
X-40035Y122689D01*
X-39878Y122584D01*
Y122374D01*
X-40035Y122269D01*
G01X-35223Y127729D02*
X-34753Y128359D01*
X-34205Y128674D01*
X-33578Y128779D01*
X-32795Y128569D01*
X-32247Y128044D01*
X-32090Y127414D01*
X-32168Y126784D01*
X-32482Y126259D01*
X-34048Y125209D01*
X-34753Y124474D01*
X-35223Y123424D01*
X-35380Y122479D01*
X-32090D01*
G01X-28767Y123214D02*
X-28218Y122689D01*
X-27592Y122479D01*
X-26965Y122689D01*
X-26417Y123319D01*
X-26025Y124264D01*
X-25868Y125209D01*
Y126364D01*
X-26025Y127309D01*
X-26417Y128149D01*
X-26887Y128569D01*
X-27435Y128779D01*
X-28062Y128569D01*
X-28532Y128149D01*
X-28845Y127519D01*
X-29002Y126679D01*
X-28845Y125944D01*
X-28453Y125209D01*
X-27983Y124789D01*
X-27435Y124684D01*
X-26808Y124894D01*
X-26338Y125419D01*
X-25868Y126364D01*
G01X-69154Y281600D02*
X-68684Y282230D01*
X-68136Y282545D01*
X-67509Y282650D01*
X-66726Y282440D01*
X-66178Y281915D01*
X-66021Y281285D01*
X-66099Y280655D01*
X-66413Y280130D01*
X-67979Y279080D01*
X-68684Y278345D01*
X-69154Y277295D01*
X-69311Y276350D01*
X-66021D01*
G01X-61523D02*
X-61366Y277715D01*
X-61131Y278870D01*
X-60818Y279920D01*
X-60426Y281075D01*
X-59799Y282650D01*
X-62933D01*
G01X-56398Y277085D02*
X-55849Y276560D01*
X-55223Y276350D01*
X-54596Y276560D01*
X-54048Y277190D01*
X-53656Y278135D01*
X-53499Y279080D01*
Y280235D01*
X-53656Y281180D01*
X-54048Y282020D01*
X-54518Y282440D01*
X-55066Y282650D01*
X-55693Y282440D01*
X-56163Y282020D01*
X-56476Y281390D01*
X-56633Y280550D01*
X-56476Y279815D01*
X-56084Y279080D01*
X-55614Y278660D01*
X-55066Y278555D01*
X-54439Y278765D01*
X-53969Y279290D01*
X-53499Y280235D01*
G01X-50489Y277295D02*
X-50019Y276770D01*
X-49471Y276455D01*
X-48766Y276350D01*
X-48061Y276560D01*
X-47513Y276980D01*
X-47121Y277715D01*
X-47043Y278555D01*
X-47199Y279395D01*
X-47591Y279920D01*
X-48139Y280340D01*
X-48688Y280445D01*
X-49236Y280340D01*
X-49941Y279920D01*
X-49706Y282650D01*
X-47591D01*
G01X-42466Y276140D02*
X-42623Y276245D01*
Y276455D01*
X-42466Y276560D01*
X-42309Y276455D01*
Y276245D01*
X-42466Y276140D01*
G01X-36166Y282650D02*
X-36793Y282440D01*
X-37263Y281915D01*
X-37576Y281285D01*
X-37811Y280445D01*
X-37889Y279500D01*
X-37811Y278555D01*
X-37576Y277715D01*
X-37263Y277085D01*
X-36793Y276560D01*
X-36166Y276350D01*
X-35539Y276560D01*
X-35069Y277085D01*
X-34756Y277715D01*
X-34521Y278555D01*
X-34443Y279500D01*
X-34521Y280445D01*
X-34756Y281285D01*
X-35069Y281915D01*
X-35539Y282440D01*
X-36166Y282650D01*
G01X-29866D02*
X-30493Y282440D01*
X-30963Y281915D01*
X-31276Y281285D01*
X-31511Y280445D01*
X-31589Y279500D01*
X-31511Y278555D01*
X-31276Y277715D01*
X-30963Y277085D01*
X-30493Y276560D01*
X-29866Y276350D01*
X-29239Y276560D01*
X-28769Y277085D01*
X-28456Y277715D01*
X-28221Y278555D01*
X-28143Y279500D01*
X-28221Y280445D01*
X-28456Y281285D01*
X-28769Y281915D01*
X-29239Y282440D01*
X-29866Y282650D01*
G01X-66422Y412350D02*
Y418650D01*
X-69320Y414135D01*
X-65404D01*
G01X-61062Y412350D02*
Y418650D01*
X-62002Y417390D01*
G01Y412350D02*
X-60122D01*
G01X-56485Y413295D02*
X-56015Y412770D01*
X-55467Y412455D01*
X-54762Y412350D01*
X-54057Y412560D01*
X-53509Y412980D01*
X-53117Y413715D01*
X-53039Y414555D01*
X-53195Y415395D01*
X-53587Y415920D01*
X-54135Y416340D01*
X-54684Y416445D01*
X-55232Y416340D01*
X-55937Y415920D01*
X-55702Y418650D01*
X-53587D01*
G01X-50185Y413295D02*
X-49715Y412770D01*
X-49167Y412455D01*
X-48462Y412350D01*
X-47757Y412560D01*
X-47209Y412980D01*
X-46817Y413715D01*
X-46739Y414555D01*
X-46895Y415395D01*
X-47287Y415920D01*
X-47835Y416340D01*
X-48384Y416445D01*
X-48932Y416340D01*
X-49637Y415920D01*
X-49402Y418650D01*
X-47287D01*
G01X-42162Y412140D02*
X-42319Y412245D01*
Y412455D01*
X-42162Y412560D01*
X-42005Y412455D01*
Y412245D01*
X-42162Y412140D01*
G01X-35862Y418650D02*
X-36489Y418440D01*
X-36959Y417915D01*
X-37272Y417285D01*
X-37507Y416445D01*
X-37585Y415500D01*
X-37507Y414555D01*
X-37272Y413715D01*
X-36959Y413085D01*
X-36489Y412560D01*
X-35862Y412350D01*
X-35235Y412560D01*
X-34765Y413085D01*
X-34452Y413715D01*
X-34217Y414555D01*
X-34139Y415500D01*
X-34217Y416445D01*
X-34452Y417285D01*
X-34765Y417915D01*
X-35235Y418440D01*
X-35862Y418650D01*
G01X-29562D02*
X-30189Y418440D01*
X-30659Y417915D01*
X-30972Y417285D01*
X-31207Y416445D01*
X-31285Y415500D01*
X-31207Y414555D01*
X-30972Y413715D01*
X-30659Y413085D01*
X-30189Y412560D01*
X-29562Y412350D01*
X-28935Y412560D01*
X-28465Y413085D01*
X-28152Y413715D01*
X-27917Y414555D01*
X-27839Y415500D01*
X-27917Y416445D01*
X-28152Y417285D01*
X-28465Y417915D01*
X-28935Y418440D01*
X-29562Y418650D01*
G01X-61397Y1814543D02*
Y1820843D01*
X-62337Y1819583D01*
G01Y1814543D02*
X-60457D01*
G01X-55097D02*
X-54549Y1814648D01*
X-53922Y1814963D01*
X-53530Y1815488D01*
X-53374Y1816223D01*
X-53530Y1816958D01*
X-54000Y1817588D01*
X-54705Y1817903D01*
X-55489D01*
X-55959Y1818113D01*
X-56350Y1818638D01*
X-56507Y1819373D01*
X-56272Y1820108D01*
X-55724Y1820633D01*
X-55097Y1820843D01*
X-54470Y1820633D01*
X-53922Y1820108D01*
X-53687Y1819373D01*
X-53844Y1818638D01*
X-54235Y1818113D01*
X-54705Y1817903D01*
X-55489D01*
X-56194Y1817588D01*
X-56664Y1816958D01*
X-56820Y1816223D01*
X-56664Y1815488D01*
X-56272Y1814963D01*
X-55645Y1814648D01*
X-55097Y1814543D01*
G01X-48797D02*
Y1820843D01*
X-49737Y1819583D01*
G01Y1814543D02*
X-47857D01*
G01X-42654D02*
X-42497Y1815908D01*
X-42262Y1817063D01*
X-41949Y1818113D01*
X-41557Y1819268D01*
X-40930Y1820843D01*
X-44064D01*
G01X-37685Y1817168D02*
X-37137Y1817903D01*
X-36667Y1818323D01*
X-36040Y1818533D01*
X-35492Y1818323D01*
X-35100Y1817903D01*
X-34787Y1817273D01*
X-34709Y1816538D01*
X-34787Y1815908D01*
X-35100Y1815278D01*
X-35570Y1814753D01*
X-36119Y1814543D01*
X-36745Y1814753D01*
X-37294Y1815383D01*
X-37607Y1816328D01*
X-37685Y1817378D01*
X-37529Y1818743D01*
X-37294Y1819478D01*
X-36902Y1820213D01*
X-36354Y1820738D01*
X-35805Y1820843D01*
X-35257Y1820633D01*
X-34865Y1820108D01*
G01X-29897Y1814333D02*
X-30054Y1814438D01*
Y1814648D01*
X-29897Y1814753D01*
X-29740Y1814648D01*
Y1814438D01*
X-29897Y1814333D01*
G01X-24929Y1815278D02*
X-24380Y1814753D01*
X-23754Y1814543D01*
X-23127Y1814753D01*
X-22579Y1815383D01*
X-22187Y1816328D01*
X-22030Y1817273D01*
Y1818428D01*
X-22187Y1819373D01*
X-22579Y1820213D01*
X-23049Y1820633D01*
X-23597Y1820843D01*
X-24224Y1820633D01*
X-24694Y1820213D01*
X-25007Y1819583D01*
X-25164Y1818743D01*
X-25007Y1818008D01*
X-24615Y1817273D01*
X-24145Y1816853D01*
X-23597Y1816748D01*
X-22970Y1816958D01*
X-22500Y1817483D01*
X-22030Y1818428D01*
G01X-19020Y1815803D02*
X-18550Y1815068D01*
X-17924Y1814648D01*
X-17219Y1814543D01*
X-16592Y1814648D01*
X-15965Y1815173D01*
X-15574Y1815803D01*
X-15495Y1816433D01*
X-15652Y1817168D01*
X-16200Y1817693D01*
X-16749Y1817903D01*
X-17454D01*
G01X-16749D02*
X-16279Y1818218D01*
X-15887Y1818743D01*
X-15730Y1819373D01*
X-15887Y1820003D01*
X-16279Y1820528D01*
X-16984Y1820843D01*
X-17689Y1820738D01*
X-18394Y1820318D01*
G01X0Y-31358D02*
X-627Y-31568D01*
X-1097Y-32093D01*
X-1410Y-32723D01*
X-1645Y-33563D01*
X-1723Y-34508D01*
X-1645Y-35453D01*
X-1410Y-36293D01*
X-1097Y-36923D01*
X-627Y-37448D01*
X0Y-37658D01*
X627Y-37448D01*
X1097Y-36923D01*
X1410Y-36293D01*
X1645Y-35453D01*
X1723Y-34508D01*
X1645Y-33563D01*
X1410Y-32723D01*
X1097Y-32093D01*
X627Y-31568D01*
X0Y-31358D01*
G01X6705Y-124160D02*
X7332Y-124685D01*
X8037Y-125000D01*
X8663D01*
X9290Y-124685D01*
X9760Y-124160D01*
X9995Y-123425D01*
X9838Y-122690D01*
X9447Y-122060D01*
X8742Y-121640D01*
X7802Y-121430D01*
X7253Y-121010D01*
X7018Y-120275D01*
X7175Y-119540D01*
X7567Y-119015D01*
X8115Y-118700D01*
X8663D01*
X9212Y-118910D01*
X9682Y-119435D01*
G01X13005Y-125000D02*
Y-118700D01*
G01X16295D02*
Y-125000D01*
G01Y-121850D02*
X13005D01*
G01X20010Y-118700D02*
X21890D01*
G01X20950D02*
Y-125000D01*
G01X20010D02*
X21890D01*
G01X28817D02*
X25683D01*
Y-118700D01*
X28817D01*
G01X27563Y-121745D02*
X25683D01*
G01X31748Y-125000D02*
Y-118700D01*
X35352Y-125000D01*
Y-118700D01*
G01X39693Y-126155D02*
X40007Y-124790D01*
G01X46150Y-118700D02*
Y-125000D01*
G01X44348Y-118700D02*
X47952D01*
G01X50492Y-125000D02*
X52450Y-118700D01*
X54408Y-125000D01*
G01X53703Y-122795D02*
X51197D01*
G01X57810Y-118700D02*
X59690D01*
G01X58750D02*
Y-125000D01*
G01X57810D02*
X59690D01*
G01X62700Y-118700D02*
X63797Y-125000D01*
X65050Y-118700D01*
X66303Y-125000D01*
X67400Y-118700D01*
G01X69392Y-125000D02*
X71350Y-118700D01*
X73308Y-125000D01*
G01X72603Y-122795D02*
X70097D01*
G01X75848Y-125000D02*
Y-118700D01*
X79452Y-125000D01*
Y-118700D01*
G01X88683Y-125000D02*
Y-118700D01*
X90642D01*
X91268Y-119015D01*
X91660Y-119435D01*
X91817Y-120275D01*
X91660Y-121115D01*
X91190Y-121640D01*
X90642Y-121955D01*
X88683D01*
G01X90642D02*
X91817Y-125000D01*
G01X96550Y-125210D02*
X96393Y-125105D01*
Y-124895D01*
X96550Y-124790D01*
X96707Y-124895D01*
Y-125105D01*
X96550Y-125210D01*
G01X102850Y-125000D02*
X102223Y-124895D01*
X101675Y-124475D01*
X101205Y-123845D01*
X100892Y-123110D01*
X100735Y-122270D01*
Y-121430D01*
X100892Y-120590D01*
X101205Y-119855D01*
X101675Y-119225D01*
X102223Y-118805D01*
X102850Y-118700D01*
X103477Y-118805D01*
X104025Y-119225D01*
X104495Y-119855D01*
X104808Y-120590D01*
X104965Y-121430D01*
Y-122270D01*
X104808Y-123110D01*
X104495Y-123845D01*
X104025Y-124475D01*
X103477Y-124895D01*
X102850Y-125000D01*
G01X109150Y-125210D02*
X108993Y-125105D01*
Y-124895D01*
X109150Y-124790D01*
X109307Y-124895D01*
Y-125105D01*
X109150Y-125210D01*
G01X117173Y-119225D02*
X116703Y-118910D01*
X116155Y-118700D01*
X115528D01*
X114823Y-119015D01*
X114275Y-119540D01*
X113883Y-120170D01*
X113570Y-121220D01*
X113492Y-122165D01*
X113648Y-123110D01*
X113883Y-123740D01*
X114353Y-124370D01*
X114902Y-124790D01*
X115450Y-125000D01*
X115998D01*
X116547Y-124790D01*
X117017Y-124475D01*
X117408Y-124055D01*
G01X121750Y-125210D02*
X121593Y-125105D01*
Y-124895D01*
X121750Y-124790D01*
X121907Y-124895D01*
Y-125105D01*
X121750Y-125210D01*
G01X6627Y-115000D02*
Y-108700D01*
G01X9603D02*
X6627Y-112585D01*
G01X10073Y-115000D02*
X7958Y-110800D01*
G01X12927Y-108700D02*
Y-113215D01*
X13240Y-114160D01*
X13867Y-114790D01*
X14650Y-115000D01*
X15433Y-114790D01*
X16060Y-114160D01*
X16373Y-113215D01*
Y-108700D01*
G01X22517Y-115000D02*
X19383D01*
Y-108700D01*
X22517D01*
G01X21263Y-111745D02*
X19383D01*
G01X26310Y-108700D02*
X28190D01*
G01X27250D02*
Y-115000D01*
G01X26310D02*
X28190D01*
G01X38205Y-114160D02*
X38832Y-114685D01*
X39537Y-115000D01*
X40163D01*
X40790Y-114685D01*
X41260Y-114160D01*
X41495Y-113425D01*
X41338Y-112690D01*
X40947Y-112060D01*
X40242Y-111640D01*
X39302Y-111430D01*
X38753Y-111010D01*
X38518Y-110275D01*
X38675Y-109540D01*
X39067Y-109015D01*
X39615Y-108700D01*
X40163D01*
X40712Y-108910D01*
X41182Y-109435D01*
G01X44505Y-115000D02*
Y-108700D01*
G01X47795D02*
Y-115000D01*
G01Y-111850D02*
X44505D01*
G01X50492Y-115000D02*
X52450Y-108700D01*
X54408Y-115000D01*
G01X53703Y-112795D02*
X51197D01*
G01X56948Y-115000D02*
Y-108700D01*
X60552Y-115000D01*
Y-108700D01*
G01X69705Y-115000D02*
Y-108700D01*
G01X72995D02*
Y-115000D01*
G01Y-111850D02*
X69705D01*
G01X76005Y-114160D02*
X76632Y-114685D01*
X77337Y-115000D01*
X77963D01*
X78590Y-114685D01*
X79060Y-114160D01*
X79295Y-113425D01*
X79138Y-112690D01*
X78747Y-112060D01*
X78042Y-111640D01*
X77102Y-111430D01*
X76553Y-111010D01*
X76318Y-110275D01*
X76475Y-109540D01*
X76867Y-109015D01*
X77415Y-108700D01*
X77963D01*
X78512Y-108910D01*
X78982Y-109435D01*
G01X83010Y-108700D02*
X84890D01*
G01X83950D02*
Y-115000D01*
G01X83010D02*
X84890D01*
G01X88292D02*
X90250Y-108700D01*
X92208Y-115000D01*
G01X91503Y-112795D02*
X88997D01*
G01X94748Y-115000D02*
Y-108700D01*
X98352Y-115000D01*
Y-108700D01*
G01X103320Y-111850D02*
X104887D01*
Y-113740D01*
X104417Y-114370D01*
X103868Y-114790D01*
X103085Y-115000D01*
X102302Y-114790D01*
X101753Y-114370D01*
X101283Y-113740D01*
X100970Y-113005D01*
X100813Y-112165D01*
Y-111430D01*
X100970Y-110800D01*
X101283Y-110065D01*
X101753Y-109435D01*
X102223Y-109015D01*
X102850Y-108700D01*
X103398D01*
X104025Y-108910D01*
X104495Y-109330D01*
G01X108993Y-116155D02*
X109307Y-114790D01*
G01X115450Y-108700D02*
Y-115000D01*
G01X113648Y-108700D02*
X117252D01*
G01X119792Y-115000D02*
X121750Y-108700D01*
X123708Y-115000D01*
G01X123003Y-112795D02*
X120497D01*
G01X128050Y-115000D02*
X127423Y-114895D01*
X126875Y-114475D01*
X126405Y-113845D01*
X126092Y-113110D01*
X125935Y-112270D01*
Y-111430D01*
X126092Y-110590D01*
X126405Y-109855D01*
X126875Y-109225D01*
X127423Y-108805D01*
X128050Y-108700D01*
X128677Y-108805D01*
X129225Y-109225D01*
X129695Y-109855D01*
X130008Y-110590D01*
X130165Y-111430D01*
Y-112270D01*
X130008Y-113110D01*
X129695Y-113845D01*
X129225Y-114475D01*
X128677Y-114895D01*
X128050Y-115000D01*
G01X140650D02*
Y-112165D01*
X139083Y-108700D01*
G01X142217D02*
X140650Y-112165D01*
G01X145227Y-108700D02*
Y-113215D01*
X145540Y-114160D01*
X146167Y-114790D01*
X146950Y-115000D01*
X147733Y-114790D01*
X148360Y-114160D01*
X148673Y-113215D01*
Y-108700D01*
G01X151292Y-115000D02*
X153250Y-108700D01*
X155208Y-115000D01*
G01X154503Y-112795D02*
X151997D01*
G01X157748Y-115000D02*
Y-108700D01*
X161352Y-115000D01*
Y-108700D01*
G01X30650Y-92300D02*
X28130Y-91883D01*
X25925Y-90217D01*
X24035Y-87717D01*
X22775Y-84800D01*
X22145Y-81467D01*
Y-78133D01*
X22775Y-74800D01*
X24035Y-71883D01*
X25925Y-69384D01*
X28130Y-67717D01*
X30650Y-67300D01*
X33170Y-67717D01*
X35375Y-69384D01*
X37265Y-71883D01*
X38525Y-74800D01*
X39155Y-78133D01*
Y-81467D01*
X38525Y-84800D01*
X37265Y-87717D01*
X35375Y-90217D01*
X33170Y-91883D01*
X30650Y-92300D01*
G01X33170Y-85633D02*
X36950Y-92300D01*
G01X50495Y-75634D02*
Y-87300D01*
X51755Y-90217D01*
X53645Y-91883D01*
X55850Y-92300D01*
X58055Y-91883D01*
X59945Y-90217D01*
X61205Y-87300D01*
G01Y-92300D02*
Y-75634D01*
G01X86720Y-92300D02*
Y-75634D01*
G01Y-78550D02*
X85460Y-76884D01*
X83570Y-76050D01*
X81365Y-75634D01*
X79160Y-76467D01*
X77270Y-78133D01*
X76010Y-80634D01*
X75380Y-83967D01*
X76010Y-87300D01*
X77270Y-89801D01*
X79160Y-91467D01*
X81365Y-92300D01*
X83570Y-91883D01*
X85460Y-90634D01*
X86720Y-88967D01*
G01X100895Y-92300D02*
Y-75634D01*
G01Y-79800D02*
X102155Y-77717D01*
X104045Y-76050D01*
X106565Y-75634D01*
X108770Y-76050D01*
X110660Y-77717D01*
X111605Y-80634D01*
Y-92300D01*
G01X131450Y-67300D02*
Y-92300D01*
G01X127040Y-75634D02*
X135860D01*
G01X162320Y-92300D02*
Y-75634D01*
G01Y-78550D02*
X161060Y-76884D01*
X159170Y-76050D01*
X156965Y-75634D01*
X154760Y-76467D01*
X152870Y-78133D01*
X151610Y-80634D01*
X150980Y-83967D01*
X151610Y-87300D01*
X152870Y-89801D01*
X154760Y-91467D01*
X156965Y-92300D01*
X159170Y-91883D01*
X161060Y-90634D01*
X162320Y-88967D01*
G01X6548Y-105000D02*
Y-98700D01*
X10152Y-105000D01*
Y-98700D01*
G01X14650Y-105000D02*
X14023Y-104895D01*
X13475Y-104475D01*
X13005Y-103845D01*
X12692Y-103110D01*
X12535Y-102270D01*
Y-101430D01*
X12692Y-100590D01*
X13005Y-99855D01*
X13475Y-99225D01*
X14023Y-98805D01*
X14650Y-98700D01*
X15277Y-98805D01*
X15825Y-99225D01*
X16295Y-99855D01*
X16608Y-100590D01*
X16765Y-101430D01*
Y-102270D01*
X16608Y-103110D01*
X16295Y-103845D01*
X15825Y-104475D01*
X15277Y-104895D01*
X14650Y-105000D01*
G01X20950Y-105210D02*
X20793Y-105105D01*
Y-104895D01*
X20950Y-104790D01*
X21107Y-104895D01*
Y-105105D01*
X20950Y-105210D01*
G01X27250Y-105000D02*
Y-98700D01*
X26310Y-99960D01*
G01Y-105000D02*
X28190D01*
G01X33550D02*
X34098Y-104895D01*
X34725Y-104580D01*
X35117Y-104055D01*
X35273Y-103320D01*
X35117Y-102585D01*
X34647Y-101955D01*
X33942Y-101640D01*
X33158D01*
X32688Y-101430D01*
X32297Y-100905D01*
X32140Y-100170D01*
X32375Y-99435D01*
X32923Y-98910D01*
X33550Y-98700D01*
X34177Y-98910D01*
X34725Y-99435D01*
X34960Y-100170D01*
X34803Y-100905D01*
X34412Y-101430D01*
X33942Y-101640D01*
X33158D01*
X32453Y-101955D01*
X31983Y-102585D01*
X31827Y-103320D01*
X31983Y-104055D01*
X32375Y-104580D01*
X33002Y-104895D01*
X33550Y-105000D01*
G01X39850D02*
X40398Y-104895D01*
X41025Y-104580D01*
X41417Y-104055D01*
X41573Y-103320D01*
X41417Y-102585D01*
X40947Y-101955D01*
X40242Y-101640D01*
X39458D01*
X38988Y-101430D01*
X38597Y-100905D01*
X38440Y-100170D01*
X38675Y-99435D01*
X39223Y-98910D01*
X39850Y-98700D01*
X40477Y-98910D01*
X41025Y-99435D01*
X41260Y-100170D01*
X41103Y-100905D01*
X40712Y-101430D01*
X40242Y-101640D01*
X39458D01*
X38753Y-101955D01*
X38283Y-102585D01*
X38127Y-103320D01*
X38283Y-104055D01*
X38675Y-104580D01*
X39302Y-104895D01*
X39850Y-105000D01*
G01X45993Y-106155D02*
X46307Y-104790D01*
G01X50100Y-98700D02*
X51197Y-105000D01*
X52450Y-98700D01*
X53703Y-105000D01*
X54800Y-98700D01*
G01X60317Y-105000D02*
X57183D01*
Y-98700D01*
X60317D01*
G01X59063Y-101745D02*
X57183D01*
G01X63248Y-105000D02*
Y-98700D01*
X66852Y-105000D01*
Y-98700D01*
G01X76005Y-105000D02*
Y-98700D01*
G01X79295D02*
Y-105000D01*
G01Y-101850D02*
X76005D01*
G01X81600Y-98700D02*
X82697Y-105000D01*
X83950Y-98700D01*
X85203Y-105000D01*
X86300Y-98700D01*
G01X88292Y-105000D02*
X90250Y-98700D01*
X92208Y-105000D01*
G01X91503Y-102795D02*
X88997D01*
G01X101362Y-99750D02*
X101832Y-99120D01*
X102380Y-98805D01*
X103007Y-98700D01*
X103790Y-98910D01*
X104338Y-99435D01*
X104495Y-100065D01*
X104417Y-100695D01*
X104103Y-101220D01*
X102537Y-102270D01*
X101832Y-103005D01*
X101362Y-104055D01*
X101205Y-105000D01*
X104495D01*
G01X107348D02*
Y-98700D01*
X110952Y-105000D01*
Y-98700D01*
G01X113727Y-105000D02*
Y-98700D01*
X115293D01*
X115920Y-99015D01*
X116390Y-99435D01*
X116782Y-100065D01*
X117095Y-100800D01*
X117173Y-101850D01*
X117095Y-102900D01*
X116782Y-103635D01*
X116390Y-104265D01*
X115920Y-104685D01*
X115293Y-105000D01*
X113727D01*
G01X126483D02*
Y-98700D01*
X128442D01*
X129068Y-99015D01*
X129460Y-99435D01*
X129617Y-100275D01*
X129460Y-101115D01*
X128990Y-101640D01*
X128442Y-101955D01*
X126483D01*
G01X128442D02*
X129617Y-105000D01*
G01X132627D02*
Y-98700D01*
X134193D01*
X134820Y-99015D01*
X135290Y-99435D01*
X135682Y-100065D01*
X135995Y-100800D01*
X136073Y-101850D01*
X135995Y-102900D01*
X135682Y-103635D01*
X135290Y-104265D01*
X134820Y-104685D01*
X134193Y-105000D01*
X132627D01*
G01X140650Y-105210D02*
X140493Y-105105D01*
Y-104895D01*
X140650Y-104790D01*
X140807Y-104895D01*
Y-105105D01*
X140650Y-105210D01*
G01X12631Y-31138D02*
X12001Y-30668D01*
X11686Y-30120D01*
X11581Y-29493D01*
X11791Y-28710D01*
X12316Y-28162D01*
X12946Y-28005D01*
X13576Y-28083D01*
X14101Y-28397D01*
X15151Y-29963D01*
X15886Y-30668D01*
X16936Y-31138D01*
X17881Y-31295D01*
Y-28005D01*
G01X11581Y-23350D02*
X11791Y-23977D01*
X12316Y-24447D01*
X12946Y-24760D01*
X13786Y-24995D01*
X14731Y-25073D01*
X15676Y-24995D01*
X16516Y-24760D01*
X17146Y-24447D01*
X17671Y-23977D01*
X17881Y-23350D01*
X17671Y-22723D01*
X17146Y-22253D01*
X16516Y-21940D01*
X15676Y-21705D01*
X14731Y-21627D01*
X13786Y-21705D01*
X12946Y-21940D01*
X12316Y-22253D01*
X11791Y-22723D01*
X11581Y-23350D01*
G01X17881Y-16110D02*
X11581D01*
X16096Y-19008D01*
Y-15092D01*
G01X18091Y-10750D02*
X17986Y-10907D01*
X17776D01*
X17671Y-10750D01*
X17776Y-10593D01*
X17986D01*
X18091Y-10750D01*
G01X17881Y-4607D02*
X16516Y-4450D01*
X15361Y-4215D01*
X14311Y-3902D01*
X13156Y-3510D01*
X11581Y-2883D01*
Y-6017D01*
G01X12631Y362D02*
X12001Y832D01*
X11686Y1380D01*
X11581Y2007D01*
X11791Y2790D01*
X12316Y3338D01*
X12946Y3495D01*
X13576Y3417D01*
X14101Y3103D01*
X15151Y1537D01*
X15886Y832D01*
X16936Y362D01*
X17881Y205D01*
Y3495D01*
G01X36181Y-27796D02*
X35551Y-27326D01*
X35236Y-26778D01*
X35131Y-26151D01*
X35341Y-25368D01*
X35866Y-24820D01*
X36496Y-24663D01*
X37126Y-24741D01*
X37651Y-25055D01*
X38701Y-26621D01*
X39436Y-27326D01*
X40486Y-27796D01*
X41431Y-27953D01*
Y-24663D01*
G01X36181Y-21496D02*
X35551Y-21026D01*
X35236Y-20478D01*
X35131Y-19851D01*
X35341Y-19068D01*
X35866Y-18520D01*
X36496Y-18363D01*
X37126Y-18441D01*
X37651Y-18755D01*
X38701Y-20321D01*
X39436Y-21026D01*
X40486Y-21496D01*
X41431Y-21653D01*
Y-18363D01*
G01Y-13865D02*
X40066Y-13708D01*
X38911Y-13473D01*
X37861Y-13160D01*
X36706Y-12768D01*
X35131Y-12141D01*
Y-15275D01*
G01X41641Y-7408D02*
X41536Y-7565D01*
X41326D01*
X41221Y-7408D01*
X41326Y-7251D01*
X41536D01*
X41641Y-7408D01*
G01X40486Y-2831D02*
X41011Y-2361D01*
X41326Y-1813D01*
X41431Y-1108D01*
X41221Y-403D01*
X40801Y145D01*
X40066Y537D01*
X39226Y615D01*
X38386Y459D01*
X37861Y67D01*
X37441Y-481D01*
X37336Y-1030D01*
X37441Y-1578D01*
X37861Y-2283D01*
X35131Y-2048D01*
Y67D01*
G01X38806Y3704D02*
X38071Y4252D01*
X37651Y4722D01*
X37441Y5349D01*
X37651Y5897D01*
X38071Y6289D01*
X38701Y6602D01*
X39436Y6680D01*
X40066Y6602D01*
X40696Y6289D01*
X41221Y5819D01*
X41431Y5270D01*
X41221Y4644D01*
X40591Y4095D01*
X39646Y3782D01*
X38596Y3704D01*
X37231Y3860D01*
X36496Y4095D01*
X35761Y4487D01*
X35236Y5035D01*
X35131Y5584D01*
X35341Y6132D01*
X35866Y6524D01*
G01X48206Y2102840D02*
X41906D01*
X46421Y2099942D01*
Y2103858D01*
G01X47261Y2106477D02*
X47786Y2106947D01*
X48101Y2107495D01*
X48206Y2108200D01*
X47996Y2108905D01*
X47576Y2109453D01*
X46841Y2109845D01*
X46001Y2109923D01*
X45161Y2109767D01*
X44636Y2109375D01*
X44216Y2108827D01*
X44111Y2108278D01*
X44216Y2107730D01*
X44636Y2107025D01*
X41906Y2107260D01*
Y2109375D01*
G01Y2114500D02*
X42116Y2113873D01*
X42641Y2113403D01*
X43271Y2113090D01*
X44111Y2112855D01*
X45056Y2112777D01*
X46001Y2112855D01*
X46841Y2113090D01*
X47471Y2113403D01*
X47996Y2113873D01*
X48206Y2114500D01*
X47996Y2115127D01*
X47471Y2115597D01*
X46841Y2115910D01*
X46001Y2116145D01*
X45056Y2116223D01*
X44111Y2116145D01*
X43271Y2115910D01*
X42641Y2115597D01*
X42116Y2115127D01*
X41906Y2114500D01*
G01X48416Y2120800D02*
X48311Y2120643D01*
X48101D01*
X47996Y2120800D01*
X48101Y2120957D01*
X48311D01*
X48416Y2120800D01*
G01X47261Y2125377D02*
X47786Y2125847D01*
X48101Y2126395D01*
X48206Y2127100D01*
X47996Y2127805D01*
X47576Y2128353D01*
X46841Y2128745D01*
X46001Y2128823D01*
X45161Y2128667D01*
X44636Y2128275D01*
X44216Y2127727D01*
X44111Y2127178D01*
X44216Y2126630D01*
X44636Y2125925D01*
X41906Y2126160D01*
Y2128275D01*
G01X45581Y2131912D02*
X44846Y2132460D01*
X44426Y2132930D01*
X44216Y2133557D01*
X44426Y2134105D01*
X44846Y2134497D01*
X45476Y2134810D01*
X46211Y2134888D01*
X46841Y2134810D01*
X47471Y2134497D01*
X47996Y2134027D01*
X48206Y2133478D01*
X47996Y2132852D01*
X47366Y2132303D01*
X46421Y2131990D01*
X45371Y2131912D01*
X44006Y2132068D01*
X43271Y2132303D01*
X42536Y2132695D01*
X42011Y2133243D01*
X41906Y2133792D01*
X42116Y2134340D01*
X42641Y2134732D01*
G01X57184Y-104288D02*
X57709Y-103818D01*
X58024Y-103270D01*
X58129Y-102565D01*
X57919Y-101860D01*
X57499Y-101312D01*
X56764Y-100920D01*
X55924Y-100842D01*
X55084Y-100998D01*
X54559Y-101390D01*
X54139Y-101938D01*
X54034Y-102487D01*
X54139Y-103035D01*
X54559Y-103740D01*
X51829Y-103505D01*
Y-101390D01*
G01X58129Y-95325D02*
X51829D01*
X56344Y-98223D01*
Y-94307D01*
G01X57394Y-91297D02*
X57919Y-90748D01*
X58129Y-90122D01*
X57919Y-89495D01*
X57289Y-88947D01*
X56344Y-88555D01*
X55399Y-88398D01*
X54244D01*
X53299Y-88555D01*
X52459Y-88947D01*
X52039Y-89417D01*
X51829Y-89965D01*
X52039Y-90592D01*
X52459Y-91062D01*
X53089Y-91375D01*
X53929Y-91532D01*
X54664Y-91375D01*
X55399Y-90983D01*
X55819Y-90513D01*
X55924Y-89965D01*
X55714Y-89338D01*
X55189Y-88868D01*
X54244Y-88398D01*
G01X58339Y-83665D02*
X58234Y-83822D01*
X58024D01*
X57919Y-83665D01*
X58024Y-83508D01*
X58234D01*
X58339Y-83665D01*
G01X58129Y-77522D02*
X56764Y-77365D01*
X55609Y-77130D01*
X54559Y-76817D01*
X53404Y-76425D01*
X51829Y-75798D01*
Y-78932D01*
G01X57394Y-72397D02*
X57919Y-71848D01*
X58129Y-71222D01*
X57919Y-70595D01*
X57289Y-70047D01*
X56344Y-69655D01*
X55399Y-69498D01*
X54244D01*
X53299Y-69655D01*
X52459Y-70047D01*
X52039Y-70517D01*
X51829Y-71065D01*
X52039Y-71692D01*
X52459Y-72162D01*
X53089Y-72475D01*
X53929Y-72632D01*
X54664Y-72475D01*
X55399Y-72083D01*
X55819Y-71613D01*
X55924Y-71065D01*
X55714Y-70438D01*
X55189Y-69968D01*
X54244Y-69498D01*
G01X65879Y-54078D02*
X65144Y-53530D01*
X64724Y-53060D01*
X64514Y-52433D01*
X64724Y-51885D01*
X65144Y-51493D01*
X65774Y-51180D01*
X66509Y-51102D01*
X67139Y-51180D01*
X67769Y-51493D01*
X68294Y-51963D01*
X68504Y-52512D01*
X68294Y-53138D01*
X67664Y-53687D01*
X66719Y-54000D01*
X65669Y-54078D01*
X64304Y-53922D01*
X63569Y-53687D01*
X62834Y-53295D01*
X62309Y-52747D01*
X62204Y-52198D01*
X62414Y-51650D01*
X62939Y-51258D01*
G01X67559Y-48013D02*
X68084Y-47543D01*
X68399Y-46995D01*
X68504Y-46290D01*
X68294Y-45585D01*
X67874Y-45037D01*
X67139Y-44645D01*
X66299Y-44567D01*
X65459Y-44723D01*
X64934Y-45115D01*
X64514Y-45663D01*
X64409Y-46212D01*
X64514Y-46760D01*
X64934Y-47465D01*
X62204Y-47230D01*
Y-45115D01*
G01X67244Y-41713D02*
X67979Y-41243D01*
X68399Y-40617D01*
X68504Y-39912D01*
X68399Y-39285D01*
X67874Y-38658D01*
X67244Y-38267D01*
X66614Y-38188D01*
X65879Y-38345D01*
X65354Y-38893D01*
X65144Y-39442D01*
Y-40147D01*
G01Y-39442D02*
X64829Y-38972D01*
X64304Y-38580D01*
X63674Y-38423D01*
X63044Y-38580D01*
X62519Y-38972D01*
X62204Y-39677D01*
X62309Y-40382D01*
X62729Y-41087D01*
G01X68714Y-33690D02*
X68609Y-33847D01*
X68399D01*
X68294Y-33690D01*
X68399Y-33533D01*
X68609D01*
X68714Y-33690D01*
G01X67559Y-29113D02*
X68084Y-28643D01*
X68399Y-28095D01*
X68504Y-27390D01*
X68294Y-26685D01*
X67874Y-26137D01*
X67139Y-25745D01*
X66299Y-25667D01*
X65459Y-25823D01*
X64934Y-26215D01*
X64514Y-26763D01*
X64409Y-27312D01*
X64514Y-27860D01*
X64934Y-28565D01*
X62204Y-28330D01*
Y-26215D01*
G01X68504Y-20150D02*
X62204D01*
X66719Y-23048D01*
Y-19132D01*
G01X57184Y-35626D02*
X57709Y-35156D01*
X58024Y-34608D01*
X58129Y-33903D01*
X57919Y-33198D01*
X57499Y-32650D01*
X56764Y-32258D01*
X55924Y-32180D01*
X55084Y-32336D01*
X54559Y-32728D01*
X54139Y-33276D01*
X54034Y-33825D01*
X54139Y-34373D01*
X54559Y-35078D01*
X51829Y-34843D01*
Y-32728D01*
G01X58129Y-26663D02*
X51829D01*
X56344Y-29561D01*
Y-25645D01*
G01X57394Y-22635D02*
X57919Y-22086D01*
X58129Y-21460D01*
X57919Y-20833D01*
X57289Y-20285D01*
X56344Y-19893D01*
X55399Y-19736D01*
X54244D01*
X53299Y-19893D01*
X52459Y-20285D01*
X52039Y-20755D01*
X51829Y-21303D01*
X52039Y-21930D01*
X52459Y-22400D01*
X53089Y-22713D01*
X53929Y-22870D01*
X54664Y-22713D01*
X55399Y-22321D01*
X55819Y-21851D01*
X55924Y-21303D01*
X55714Y-20676D01*
X55189Y-20206D01*
X54244Y-19736D01*
G01X58339Y-15003D02*
X58234Y-15160D01*
X58024D01*
X57919Y-15003D01*
X58024Y-14846D01*
X58234D01*
X58339Y-15003D01*
G01X58129Y-8860D02*
X56764Y-8703D01*
X55609Y-8468D01*
X54559Y-8155D01*
X53404Y-7763D01*
X51829Y-7136D01*
Y-10270D01*
G01X57394Y-3735D02*
X57919Y-3186D01*
X58129Y-2560D01*
X57919Y-1933D01*
X57289Y-1385D01*
X56344Y-993D01*
X55399Y-836D01*
X54244D01*
X53299Y-993D01*
X52459Y-1385D01*
X52039Y-1855D01*
X51829Y-2403D01*
X52039Y-3030D01*
X52459Y-3500D01*
X53089Y-3813D01*
X53929Y-3970D01*
X54664Y-3813D01*
X55399Y-3421D01*
X55819Y-2951D01*
X55924Y-2403D01*
X55714Y-1776D01*
X55189Y-1306D01*
X54244Y-836D01*
G01X57459Y2128130D02*
X57984Y2128600D01*
X58299Y2129148D01*
X58404Y2129853D01*
X58194Y2130558D01*
X57774Y2131106D01*
X57039Y2131498D01*
X56199Y2131576D01*
X55359Y2131420D01*
X54834Y2131028D01*
X54414Y2130480D01*
X54309Y2129931D01*
X54414Y2129383D01*
X54834Y2128678D01*
X52104Y2128913D01*
Y2131028D01*
G01X57459Y2134430D02*
X57984Y2134900D01*
X58299Y2135448D01*
X58404Y2136153D01*
X58194Y2136858D01*
X57774Y2137406D01*
X57039Y2137798D01*
X56199Y2137876D01*
X55359Y2137720D01*
X54834Y2137328D01*
X54414Y2136780D01*
X54309Y2136231D01*
X54414Y2135683D01*
X54834Y2134978D01*
X52104Y2135213D01*
Y2137328D01*
G01X53154Y2140965D02*
X52524Y2141435D01*
X52209Y2141983D01*
X52104Y2142610D01*
X52314Y2143393D01*
X52839Y2143941D01*
X53469Y2144098D01*
X54099Y2144020D01*
X54624Y2143706D01*
X55674Y2142140D01*
X56409Y2141435D01*
X57459Y2140965D01*
X58404Y2140808D01*
Y2144098D01*
G01X58614Y2148753D02*
X58509Y2148596D01*
X58299D01*
X58194Y2148753D01*
X58299Y2148910D01*
X58509D01*
X58614Y2148753D01*
G01X57459Y2153330D02*
X57984Y2153800D01*
X58299Y2154348D01*
X58404Y2155053D01*
X58194Y2155758D01*
X57774Y2156306D01*
X57039Y2156698D01*
X56199Y2156776D01*
X55359Y2156620D01*
X54834Y2156228D01*
X54414Y2155680D01*
X54309Y2155131D01*
X54414Y2154583D01*
X54834Y2153878D01*
X52104Y2154113D01*
Y2156228D01*
G01X58404Y2162293D02*
X52104D01*
X56619Y2159395D01*
Y2163311D01*
G01X100840Y2107840D02*
X101365Y2108389D01*
X101575Y2109015D01*
X101365Y2109642D01*
X100735Y2110190D01*
X99790Y2110582D01*
X98845Y2110739D01*
X97690D01*
X96745Y2110582D01*
X95905Y2110190D01*
X95485Y2109720D01*
X95275Y2109172D01*
X95485Y2108545D01*
X95905Y2108075D01*
X96535Y2107762D01*
X97375Y2107605D01*
X98110Y2107762D01*
X98845Y2108154D01*
X99265Y2108624D01*
X99370Y2109172D01*
X99160Y2109799D01*
X98635Y2110269D01*
X97690Y2110739D01*
G01X101575Y2115472D02*
X101470Y2116020D01*
X101155Y2116647D01*
X100630Y2117039D01*
X99895Y2117195D01*
X99160Y2117039D01*
X98530Y2116569D01*
X98215Y2115864D01*
Y2115080D01*
X98005Y2114610D01*
X97480Y2114219D01*
X96745Y2114062D01*
X96010Y2114297D01*
X95485Y2114845D01*
X95275Y2115472D01*
X95485Y2116099D01*
X96010Y2116647D01*
X96745Y2116882D01*
X97480Y2116725D01*
X98005Y2116334D01*
X98215Y2115864D01*
Y2115080D01*
X98530Y2114375D01*
X99160Y2113905D01*
X99895Y2113749D01*
X100630Y2113905D01*
X101155Y2114297D01*
X101470Y2114924D01*
X101575Y2115472D01*
G01Y2122712D02*
X95275D01*
X99790Y2119814D01*
Y2123730D01*
G01X101785Y2128072D02*
X101680Y2127915D01*
X101470D01*
X101365Y2128072D01*
X101470Y2128229D01*
X101680D01*
X101785Y2128072D01*
G01X96325Y2132884D02*
X95695Y2133354D01*
X95380Y2133902D01*
X95275Y2134529D01*
X95485Y2135312D01*
X96010Y2135860D01*
X96640Y2136017D01*
X97270Y2135939D01*
X97795Y2135625D01*
X98845Y2134059D01*
X99580Y2133354D01*
X100630Y2132884D01*
X101575Y2132727D01*
Y2136017D01*
G01X100630Y2138949D02*
X101155Y2139419D01*
X101470Y2139967D01*
X101575Y2140672D01*
X101365Y2141377D01*
X100945Y2141925D01*
X100210Y2142317D01*
X99370Y2142395D01*
X98530Y2142239D01*
X98005Y2141847D01*
X97585Y2141299D01*
X97480Y2140750D01*
X97585Y2140202D01*
X98005Y2139497D01*
X95275Y2139732D01*
Y2141847D01*
G01X166535Y-52709D02*
X160235D01*
X161495Y-53649D01*
G01X166535D02*
Y-51769D01*
G01X163910Y-47897D02*
X163175Y-47349D01*
X162755Y-46879D01*
X162545Y-46252D01*
X162755Y-45704D01*
X163175Y-45312D01*
X163805Y-44999D01*
X164540Y-44921D01*
X165170Y-44999D01*
X165800Y-45312D01*
X166325Y-45782D01*
X166535Y-46331D01*
X166325Y-46957D01*
X165695Y-47506D01*
X164750Y-47819D01*
X163700Y-47897D01*
X162335Y-47741D01*
X161600Y-47506D01*
X160865Y-47114D01*
X160340Y-46566D01*
X160235Y-46017D01*
X160445Y-45469D01*
X160970Y-45077D01*
G01X165275Y-41832D02*
X166010Y-41362D01*
X166430Y-40736D01*
X166535Y-40031D01*
X166430Y-39404D01*
X165905Y-38777D01*
X165275Y-38386D01*
X164645Y-38307D01*
X163910Y-38464D01*
X163385Y-39012D01*
X163175Y-39561D01*
Y-40266D01*
G01Y-39561D02*
X162860Y-39091D01*
X162335Y-38699D01*
X161705Y-38542D01*
X161075Y-38699D01*
X160550Y-39091D01*
X160235Y-39796D01*
X160340Y-40501D01*
X160760Y-41206D01*
G01X165275Y-35532D02*
X166010Y-35062D01*
X166430Y-34436D01*
X166535Y-33731D01*
X166430Y-33104D01*
X165905Y-32477D01*
X165275Y-32086D01*
X164645Y-32007D01*
X163910Y-32164D01*
X163385Y-32712D01*
X163175Y-33261D01*
Y-33966D01*
G01Y-33261D02*
X162860Y-32791D01*
X162335Y-32399D01*
X161705Y-32242D01*
X161075Y-32399D01*
X160550Y-32791D01*
X160235Y-33496D01*
X160340Y-34201D01*
X160760Y-34906D01*
G01X166745Y-27509D02*
X166640Y-27666D01*
X166430D01*
X166325Y-27509D01*
X166430Y-27352D01*
X166640D01*
X166745Y-27509D01*
G01X166535Y-21209D02*
X166430Y-20661D01*
X166115Y-20034D01*
X165590Y-19642D01*
X164855Y-19486D01*
X164120Y-19642D01*
X163490Y-20112D01*
X163175Y-20817D01*
Y-21601D01*
X162965Y-22071D01*
X162440Y-22462D01*
X161705Y-22619D01*
X160970Y-22384D01*
X160445Y-21836D01*
X160235Y-21209D01*
X160445Y-20582D01*
X160970Y-20034D01*
X161705Y-19799D01*
X162440Y-19956D01*
X162965Y-20347D01*
X163175Y-20817D01*
Y-21601D01*
X163490Y-22306D01*
X164120Y-22776D01*
X164855Y-22932D01*
X165590Y-22776D01*
X166115Y-22384D01*
X166430Y-21757D01*
X166535Y-21209D01*
G01X165590Y-16632D02*
X166115Y-16162D01*
X166430Y-15614D01*
X166535Y-14909D01*
X166325Y-14204D01*
X165905Y-13656D01*
X165170Y-13264D01*
X164330Y-13186D01*
X163490Y-13342D01*
X162965Y-13734D01*
X162545Y-14282D01*
X162440Y-14831D01*
X162545Y-15379D01*
X162965Y-16084D01*
X160235Y-15849D01*
Y-13734D01*
G01X168622Y2209497D02*
Y2215797D01*
X165724Y2211282D01*
X169640D01*
G01X173982Y2215797D02*
X173355Y2215587D01*
X172885Y2215062D01*
X172572Y2214432D01*
X172337Y2213592D01*
X172259Y2212647D01*
X172337Y2211702D01*
X172572Y2210862D01*
X172885Y2210232D01*
X173355Y2209707D01*
X173982Y2209497D01*
X174609Y2209707D01*
X175079Y2210232D01*
X175392Y2210862D01*
X175627Y2211702D01*
X175705Y2212647D01*
X175627Y2213592D01*
X175392Y2214432D01*
X175079Y2215062D01*
X174609Y2215587D01*
X173982Y2215797D01*
G01X178559Y2210442D02*
X179029Y2209917D01*
X179577Y2209602D01*
X180282Y2209497D01*
X180987Y2209707D01*
X181535Y2210127D01*
X181927Y2210862D01*
X182005Y2211702D01*
X181849Y2212542D01*
X181457Y2213067D01*
X180909Y2213487D01*
X180360Y2213592D01*
X179812Y2213487D01*
X179107Y2213067D01*
X179342Y2215797D01*
X181457D01*
G01X184859Y2210442D02*
X185329Y2209917D01*
X185877Y2209602D01*
X186582Y2209497D01*
X187287Y2209707D01*
X187835Y2210127D01*
X188227Y2210862D01*
X188305Y2211702D01*
X188149Y2212542D01*
X187757Y2213067D01*
X187209Y2213487D01*
X186660Y2213592D01*
X186112Y2213487D01*
X185407Y2213067D01*
X185642Y2215797D01*
X187757D01*
G01X192882Y2209287D02*
X192725Y2209392D01*
Y2209602D01*
X192882Y2209707D01*
X193039Y2209602D01*
Y2209392D01*
X192882Y2209287D01*
G01X199182Y2209497D02*
Y2215797D01*
X198242Y2214537D01*
G01Y2209497D02*
X200122D01*
G01X203994Y2214747D02*
X204464Y2215377D01*
X205012Y2215692D01*
X205639Y2215797D01*
X206422Y2215587D01*
X206970Y2215062D01*
X207127Y2214432D01*
X207049Y2213802D01*
X206735Y2213277D01*
X205169Y2212227D01*
X204464Y2211492D01*
X203994Y2210442D01*
X203837Y2209497D01*
X207127D01*
G01X202000Y-72000D02*
Y-80000D01*
X206000D01*
G01X213800D02*
Y-74667D01*
G01Y-75600D02*
X213400Y-75067D01*
X212800Y-74800D01*
X212100Y-74667D01*
X211400Y-74933D01*
X210800Y-75467D01*
X210400Y-76267D01*
X210200Y-77333D01*
X210400Y-78400D01*
X210800Y-79200D01*
X211400Y-79733D01*
X212100Y-80000D01*
X212800Y-79867D01*
X213400Y-79467D01*
X213800Y-78934D01*
G01X217900Y-82400D02*
X218500Y-82667D01*
X219300Y-82400D01*
X219800Y-81867D01*
X220200Y-81200D01*
X220800Y-79067D01*
X222100Y-74667D01*
G01X218900D02*
X220800Y-79067D01*
G01X226500Y-76400D02*
X229700D01*
X229400Y-75467D01*
X228900Y-74933D01*
X228200Y-74667D01*
X227500Y-74800D01*
X226900Y-75200D01*
X226500Y-76133D01*
X226300Y-76934D01*
Y-77733D01*
X226500Y-78533D01*
X227000Y-79333D01*
X227600Y-79867D01*
X228300Y-80000D01*
X229000Y-79733D01*
X229700Y-78934D01*
G01X234600Y-80000D02*
Y-74667D01*
G01Y-75733D02*
X235100Y-75200D01*
X235600Y-74800D01*
X236300Y-74667D01*
X236800Y-74800D01*
X237400Y-75200D01*
G01X225500Y-122000D02*
Y-130000D01*
G01X223200Y-122000D02*
X227800D01*
G01X233500Y-124667D02*
Y-130000D01*
G01Y-122533D02*
X233300Y-122400D01*
Y-122133D01*
X233500Y-122000D01*
X233700Y-122133D01*
Y-122400D01*
X233500Y-122533D01*
G01X239800Y-130000D02*
Y-124667D01*
G01Y-126000D02*
X240200Y-125333D01*
X240800Y-124800D01*
X241600Y-124667D01*
X242300Y-124800D01*
X242900Y-125333D01*
X243200Y-126267D01*
Y-130000D01*
G01X251300D02*
Y-124667D01*
G01Y-125600D02*
X250900Y-125067D01*
X250300Y-124800D01*
X249600Y-124667D01*
X248900Y-124933D01*
X248300Y-125467D01*
X247900Y-126267D01*
X247700Y-127333D01*
X247900Y-128400D01*
X248300Y-129200D01*
X248900Y-129733D01*
X249600Y-130000D01*
X250300Y-129867D01*
X250900Y-129467D01*
X251300Y-128934D01*
G01X226100Y-105000D02*
Y-97000D01*
X229900D01*
G01X228500Y-100867D02*
X226100D01*
G01X233500Y-105000D02*
X236000Y-97000D01*
X238500Y-105000D01*
G01X237600Y-102200D02*
X234400D01*
G01X244800Y-100733D02*
X245200Y-100333D01*
X245500Y-99667D01*
X245700Y-98733D01*
X245500Y-97933D01*
X245100Y-97400D01*
X244400Y-97000D01*
X241700D01*
Y-105000D01*
X245000D01*
X245700Y-104467D01*
X246100Y-103667D01*
X246300Y-102733D01*
X246100Y-101800D01*
X245500Y-101000D01*
X244800Y-100733D01*
X241700D01*
G01X308977Y-50389D02*
X309712Y-49919D01*
X310132Y-49293D01*
X310237Y-48588D01*
X310132Y-47961D01*
X309607Y-47334D01*
X308977Y-46943D01*
X308347Y-46864D01*
X307612Y-47021D01*
X307087Y-47569D01*
X306877Y-48118D01*
Y-48823D01*
G01Y-48118D02*
X306562Y-47648D01*
X306037Y-47256D01*
X305407Y-47099D01*
X304777Y-47256D01*
X304252Y-47648D01*
X303937Y-48353D01*
X304042Y-49058D01*
X304462Y-49763D01*
G01X303937Y-42366D02*
X304147Y-42993D01*
X304672Y-43463D01*
X305302Y-43776D01*
X306142Y-44011D01*
X307087Y-44089D01*
X308032Y-44011D01*
X308872Y-43776D01*
X309502Y-43463D01*
X310027Y-42993D01*
X310237Y-42366D01*
X310027Y-41739D01*
X309502Y-41269D01*
X308872Y-40956D01*
X308032Y-40721D01*
X307087Y-40643D01*
X306142Y-40721D01*
X305302Y-40956D01*
X304672Y-41269D01*
X304147Y-41739D01*
X303937Y-42366D01*
G01X310237Y-36223D02*
X308872Y-36066D01*
X307717Y-35831D01*
X306667Y-35518D01*
X305512Y-35126D01*
X303937Y-34499D01*
Y-37633D01*
G01Y-29766D02*
X304147Y-30393D01*
X304672Y-30863D01*
X305302Y-31176D01*
X306142Y-31411D01*
X307087Y-31489D01*
X308032Y-31411D01*
X308872Y-31176D01*
X309502Y-30863D01*
X310027Y-30393D01*
X310237Y-29766D01*
X310027Y-29139D01*
X309502Y-28669D01*
X308872Y-28356D01*
X308032Y-28121D01*
X307087Y-28043D01*
X306142Y-28121D01*
X305302Y-28356D01*
X304672Y-28669D01*
X304147Y-29139D01*
X303937Y-29766D01*
G01X310447Y-23466D02*
X310342Y-23623D01*
X310132D01*
X310027Y-23466D01*
X310132Y-23309D01*
X310342D01*
X310447Y-23466D01*
G01X310237Y-17166D02*
X310132Y-16618D01*
X309817Y-15991D01*
X309292Y-15599D01*
X308557Y-15443D01*
X307822Y-15599D01*
X307192Y-16069D01*
X306877Y-16774D01*
Y-17558D01*
X306667Y-18028D01*
X306142Y-18419D01*
X305407Y-18576D01*
X304672Y-18341D01*
X304147Y-17793D01*
X303937Y-17166D01*
X304147Y-16539D01*
X304672Y-15991D01*
X305407Y-15756D01*
X306142Y-15913D01*
X306667Y-16304D01*
X306877Y-16774D01*
Y-17558D01*
X307192Y-18263D01*
X307822Y-18733D01*
X308557Y-18889D01*
X309292Y-18733D01*
X309817Y-18341D01*
X310132Y-17714D01*
X310237Y-17166D01*
G01Y-11023D02*
X308872Y-10866D01*
X307717Y-10631D01*
X306667Y-10318D01*
X305512Y-9926D01*
X303937Y-9299D01*
Y-12433D01*
G01X328600Y-123333D02*
X329200Y-122533D01*
X329900Y-122133D01*
X330700Y-122000D01*
X331700Y-122267D01*
X332400Y-122933D01*
X332600Y-123733D01*
X332500Y-124534D01*
X332100Y-125200D01*
X330100Y-126533D01*
X329200Y-127467D01*
X328600Y-128800D01*
X328400Y-130000D01*
X332600D01*
G01X338500Y-122000D02*
X337700Y-122267D01*
X337100Y-122933D01*
X336700Y-123733D01*
X336400Y-124800D01*
X336300Y-126000D01*
X336400Y-127200D01*
X336700Y-128267D01*
X337100Y-129067D01*
X337700Y-129733D01*
X338500Y-130000D01*
X339300Y-129733D01*
X339900Y-129067D01*
X340300Y-128267D01*
X340600Y-127200D01*
X340700Y-126000D01*
X340600Y-124800D01*
X340300Y-123733D01*
X339900Y-122933D01*
X339300Y-122267D01*
X338500Y-122000D01*
G01X346500Y-130000D02*
Y-122000D01*
X345300Y-123600D01*
G01Y-130000D02*
X347700D01*
G01X352300Y-128400D02*
X352900Y-129333D01*
X353700Y-129867D01*
X354600Y-130000D01*
X355400Y-129867D01*
X356200Y-129200D01*
X356700Y-128400D01*
X356800Y-127600D01*
X356600Y-126667D01*
X355900Y-126000D01*
X355200Y-125733D01*
X354300D01*
G01X355200D02*
X355800Y-125333D01*
X356300Y-124667D01*
X356500Y-123867D01*
X356300Y-123067D01*
X355800Y-122400D01*
X354900Y-122000D01*
X354000Y-122133D01*
X353100Y-122667D01*
G01X360700Y-130267D02*
X364300Y-122000D01*
G01X370500D02*
X369700Y-122267D01*
X369100Y-122933D01*
X368700Y-123733D01*
X368400Y-124800D01*
X368300Y-126000D01*
X368400Y-127200D01*
X368700Y-128267D01*
X369100Y-129067D01*
X369700Y-129733D01*
X370500Y-130000D01*
X371300Y-129733D01*
X371900Y-129067D01*
X372300Y-128267D01*
X372600Y-127200D01*
X372700Y-126000D01*
X372600Y-124800D01*
X372300Y-123733D01*
X371900Y-122933D01*
X371300Y-122267D01*
X370500Y-122000D01*
G01X378500Y-130000D02*
Y-122000D01*
X377300Y-123600D01*
G01Y-130000D02*
X379700D01*
G01X384700Y-130267D02*
X388300Y-122000D01*
G01X394500D02*
X393700Y-122267D01*
X393100Y-122933D01*
X392700Y-123733D01*
X392400Y-124800D01*
X392300Y-126000D01*
X392400Y-127200D01*
X392700Y-128267D01*
X393100Y-129067D01*
X393700Y-129733D01*
X394500Y-130000D01*
X395300Y-129733D01*
X395900Y-129067D01*
X396300Y-128267D01*
X396600Y-127200D01*
X396700Y-126000D01*
X396600Y-124800D01*
X396300Y-123733D01*
X395900Y-122933D01*
X395300Y-122267D01*
X394500Y-122000D01*
G01X400800Y-129067D02*
X401500Y-129733D01*
X402300Y-130000D01*
X403100Y-129733D01*
X403800Y-128934D01*
X404300Y-127733D01*
X404500Y-126533D01*
Y-125067D01*
X404300Y-123867D01*
X403800Y-122800D01*
X403200Y-122267D01*
X402500Y-122000D01*
X401700Y-122267D01*
X401100Y-122800D01*
X400700Y-123600D01*
X400500Y-124667D01*
X400700Y-125600D01*
X401200Y-126533D01*
X401800Y-127067D01*
X402500Y-127200D01*
X403300Y-126934D01*
X403900Y-126267D01*
X404500Y-125067D01*
G01X328300Y-105000D02*
Y-97000D01*
X330300D01*
X331100Y-97400D01*
X331700Y-97933D01*
X332200Y-98733D01*
X332600Y-99667D01*
X332700Y-101000D01*
X332600Y-102333D01*
X332200Y-103267D01*
X331700Y-104067D01*
X331100Y-104600D01*
X330300Y-105000D01*
X328300D01*
G01X336000D02*
X338500Y-97000D01*
X341000Y-105000D01*
G01X340100Y-102200D02*
X336900D01*
G01X346500Y-97000D02*
Y-105000D01*
G01X344200Y-97000D02*
X348800D01*
G01X352600Y-101667D02*
X353300Y-100733D01*
X353900Y-100200D01*
X354700Y-99933D01*
X355400Y-100200D01*
X355900Y-100733D01*
X356300Y-101533D01*
X356400Y-102467D01*
X356300Y-103267D01*
X355900Y-104067D01*
X355300Y-104733D01*
X354600Y-105000D01*
X353800Y-104733D01*
X353100Y-103934D01*
X352700Y-102733D01*
X352600Y-101400D01*
X352800Y-99667D01*
X353100Y-98733D01*
X353600Y-97800D01*
X354300Y-97133D01*
X355000Y-97000D01*
X355700Y-97267D01*
X356200Y-97933D01*
G01X359900Y-105000D02*
Y-97000D01*
X362500Y-103667D01*
X365100Y-97000D01*
Y-105000D01*
G01X370500Y-97000D02*
Y-105000D01*
G01X368200Y-97000D02*
X372800D01*
G01X379300Y-100733D02*
X379700Y-100333D01*
X380000Y-99667D01*
X380200Y-98733D01*
X380000Y-97933D01*
X379600Y-97400D01*
X378900Y-97000D01*
X376200D01*
Y-105000D01*
X379500D01*
X380200Y-104467D01*
X380600Y-103667D01*
X380800Y-102733D01*
X380600Y-101800D01*
X380000Y-101000D01*
X379300Y-100733D01*
X376200D01*
G01X386500Y-105000D02*
X387200Y-104867D01*
X388000Y-104467D01*
X388500Y-103800D01*
X388700Y-102867D01*
X388500Y-101934D01*
X387900Y-101133D01*
X387000Y-100733D01*
X386000D01*
X385400Y-100467D01*
X384900Y-99800D01*
X384700Y-98867D01*
X385000Y-97933D01*
X385700Y-97267D01*
X386500Y-97000D01*
X387300Y-97267D01*
X388000Y-97933D01*
X388300Y-98867D01*
X388100Y-99800D01*
X387600Y-100467D01*
X387000Y-100733D01*
X386000D01*
X385100Y-101133D01*
X384500Y-101934D01*
X384300Y-102867D01*
X384500Y-103800D01*
X385000Y-104467D01*
X385800Y-104867D01*
X386500Y-105000D01*
G01X394500D02*
X395200Y-104867D01*
X396000Y-104467D01*
X396500Y-103800D01*
X396700Y-102867D01*
X396500Y-101934D01*
X395900Y-101133D01*
X395000Y-100733D01*
X394000D01*
X393400Y-100467D01*
X392900Y-99800D01*
X392700Y-98867D01*
X393000Y-97933D01*
X393700Y-97267D01*
X394500Y-97000D01*
X395300Y-97267D01*
X396000Y-97933D01*
X396300Y-98867D01*
X396100Y-99800D01*
X395600Y-100467D01*
X395000Y-100733D01*
X394000D01*
X393100Y-101133D01*
X392500Y-101934D01*
X392300Y-102867D01*
X392500Y-103800D01*
X393000Y-104467D01*
X393800Y-104867D01*
X394500Y-105000D01*
G01X400000D02*
X402500Y-97000D01*
X405000Y-105000D01*
G01X404100Y-102200D02*
X400900D01*
G01X410500Y-97000D02*
X409700Y-97267D01*
X409100Y-97933D01*
X408700Y-98733D01*
X408400Y-99800D01*
X408300Y-101000D01*
X408400Y-102200D01*
X408700Y-103267D01*
X409100Y-104067D01*
X409700Y-104733D01*
X410500Y-105000D01*
X411300Y-104733D01*
X411900Y-104067D01*
X412300Y-103267D01*
X412600Y-102200D01*
X412700Y-101000D01*
X412600Y-99800D01*
X412300Y-98733D01*
X411900Y-97933D01*
X411300Y-97267D01*
X410500Y-97000D01*
G01X350500Y-72000D02*
Y-80000D01*
G01X348200Y-72000D02*
X352800D01*
G01X356600Y-76667D02*
X357300Y-75733D01*
X357900Y-75200D01*
X358700Y-74933D01*
X359400Y-75200D01*
X359900Y-75733D01*
X360300Y-76533D01*
X360400Y-77467D01*
X360300Y-78267D01*
X359900Y-79067D01*
X359300Y-79733D01*
X358600Y-80000D01*
X357800Y-79733D01*
X357100Y-78934D01*
X356700Y-77733D01*
X356600Y-76400D01*
X356800Y-74667D01*
X357100Y-73733D01*
X357600Y-72800D01*
X358300Y-72133D01*
X359000Y-72000D01*
X359700Y-72267D01*
X360200Y-72933D01*
G01X363900Y-80000D02*
Y-72000D01*
X366500Y-78667D01*
X369100Y-72000D01*
Y-80000D01*
G01X375100Y-76000D02*
X377100D01*
Y-78400D01*
X376500Y-79200D01*
X375800Y-79733D01*
X374800Y-80000D01*
X373800Y-79733D01*
X373100Y-79200D01*
X372500Y-78400D01*
X372100Y-77467D01*
X371900Y-76400D01*
Y-75467D01*
X372100Y-74667D01*
X372500Y-73733D01*
X373100Y-72933D01*
X373700Y-72400D01*
X374500Y-72000D01*
X375200D01*
X376000Y-72267D01*
X376600Y-72800D01*
G01X379500Y-82667D02*
X385500D01*
G01X388500Y-80000D02*
Y-72000D01*
X390900D01*
X391700Y-72400D01*
X392300Y-73333D01*
X392500Y-74400D01*
X392300Y-75467D01*
X391800Y-76267D01*
X390900Y-76667D01*
X388500D01*
G01X396300Y-80000D02*
Y-72000D01*
X398300D01*
X399100Y-72400D01*
X399700Y-72933D01*
X400200Y-73733D01*
X400600Y-74667D01*
X400700Y-76000D01*
X400600Y-77333D01*
X400200Y-78267D01*
X399700Y-79067D01*
X399100Y-79600D01*
X398300Y-80000D01*
X396300D01*
G01X407300Y-75733D02*
X407700Y-75333D01*
X408000Y-74667D01*
X408200Y-73733D01*
X408000Y-72933D01*
X407600Y-72400D01*
X406900Y-72000D01*
X404200D01*
Y-80000D01*
X407500D01*
X408200Y-79467D01*
X408600Y-78667D01*
X408800Y-77733D01*
X408600Y-76800D01*
X408000Y-76000D01*
X407300Y-75733D01*
X404200D01*
G01X411500Y-82667D02*
X417500D01*
G01X420000Y-80000D02*
X422500Y-72000D01*
X425000Y-80000D01*
G01X424100Y-77200D02*
X420900D01*
G01X427500Y-82667D02*
X433500D01*
G01X439300Y-75733D02*
X439700Y-75333D01*
X440000Y-74667D01*
X440200Y-73733D01*
X440000Y-72933D01*
X439600Y-72400D01*
X438900Y-72000D01*
X436200D01*
Y-80000D01*
X439500D01*
X440200Y-79467D01*
X440600Y-78667D01*
X440800Y-77733D01*
X440600Y-76800D01*
X440000Y-76000D01*
X439300Y-75733D01*
X436200D01*
G01X444300Y-80000D02*
Y-72000D01*
X446300D01*
X447100Y-72400D01*
X447700Y-72933D01*
X448200Y-73733D01*
X448600Y-74667D01*
X448700Y-76000D01*
X448600Y-77333D01*
X448200Y-78267D01*
X447700Y-79067D01*
X447100Y-79600D01*
X446300Y-80000D01*
X444300D01*
G01X361732Y-54095D02*
X362467Y-53625D01*
X362887Y-52999D01*
X362992Y-52294D01*
X362887Y-51667D01*
X362362Y-51040D01*
X361732Y-50649D01*
X361102Y-50570D01*
X360367Y-50727D01*
X359842Y-51275D01*
X359632Y-51824D01*
Y-52529D01*
G01Y-51824D02*
X359317Y-51354D01*
X358792Y-50962D01*
X358162Y-50805D01*
X357532Y-50962D01*
X357007Y-51354D01*
X356692Y-52059D01*
X356797Y-52764D01*
X357217Y-53469D01*
G01X362047Y-47795D02*
X362572Y-47325D01*
X362887Y-46777D01*
X362992Y-46072D01*
X362782Y-45367D01*
X362362Y-44819D01*
X361627Y-44427D01*
X360787Y-44349D01*
X359947Y-44505D01*
X359422Y-44897D01*
X359002Y-45445D01*
X358897Y-45994D01*
X359002Y-46542D01*
X359422Y-47247D01*
X356692Y-47012D01*
Y-44897D01*
G01X362257Y-41104D02*
X362782Y-40555D01*
X362992Y-39929D01*
X362782Y-39302D01*
X362152Y-38754D01*
X361207Y-38362D01*
X360262Y-38205D01*
X359107D01*
X358162Y-38362D01*
X357322Y-38754D01*
X356902Y-39224D01*
X356692Y-39772D01*
X356902Y-40399D01*
X357322Y-40869D01*
X357952Y-41182D01*
X358792Y-41339D01*
X359527Y-41182D01*
X360262Y-40790D01*
X360682Y-40320D01*
X360787Y-39772D01*
X360577Y-39145D01*
X360052Y-38675D01*
X359107Y-38205D01*
G01X362992Y-33472D02*
X362887Y-32924D01*
X362572Y-32297D01*
X362047Y-31905D01*
X361312Y-31749D01*
X360577Y-31905D01*
X359947Y-32375D01*
X359632Y-33080D01*
Y-33864D01*
X359422Y-34334D01*
X358897Y-34725D01*
X358162Y-34882D01*
X357427Y-34647D01*
X356902Y-34099D01*
X356692Y-33472D01*
X356902Y-32845D01*
X357427Y-32297D01*
X358162Y-32062D01*
X358897Y-32219D01*
X359422Y-32610D01*
X359632Y-33080D01*
Y-33864D01*
X359947Y-34569D01*
X360577Y-35039D01*
X361312Y-35195D01*
X362047Y-35039D01*
X362572Y-34647D01*
X362887Y-34020D01*
X362992Y-33472D01*
G01X363202Y-27172D02*
X363097Y-27329D01*
X362887D01*
X362782Y-27172D01*
X362887Y-27015D01*
X363097D01*
X363202Y-27172D01*
G01X362992Y-19932D02*
X356692D01*
X361207Y-22830D01*
Y-18914D01*
G01X357742Y-16060D02*
X357112Y-15590D01*
X356797Y-15042D01*
X356692Y-14415D01*
X356902Y-13632D01*
X357427Y-13084D01*
X358057Y-12927D01*
X358687Y-13005D01*
X359212Y-13319D01*
X360262Y-14885D01*
X360997Y-15590D01*
X362047Y-16060D01*
X362992Y-16217D01*
Y-12927D01*
G01X390034Y-56115D02*
X390769Y-55645D01*
X391189Y-55019D01*
X391294Y-54314D01*
X391189Y-53687D01*
X390664Y-53060D01*
X390034Y-52669D01*
X389404Y-52590D01*
X388669Y-52747D01*
X388144Y-53295D01*
X387934Y-53844D01*
Y-54549D01*
G01Y-53844D02*
X387619Y-53374D01*
X387094Y-52982D01*
X386464Y-52825D01*
X385834Y-52982D01*
X385309Y-53374D01*
X384994Y-54079D01*
X385099Y-54784D01*
X385519Y-55489D01*
G01X391294Y-48249D02*
X389929Y-48092D01*
X388774Y-47857D01*
X387724Y-47544D01*
X386569Y-47152D01*
X384994Y-46525D01*
Y-49659D01*
G01X390034Y-43515D02*
X390769Y-43045D01*
X391189Y-42419D01*
X391294Y-41714D01*
X391189Y-41087D01*
X390664Y-40460D01*
X390034Y-40069D01*
X389404Y-39990D01*
X388669Y-40147D01*
X388144Y-40695D01*
X387934Y-41244D01*
Y-41949D01*
G01Y-41244D02*
X387619Y-40774D01*
X387094Y-40382D01*
X386464Y-40225D01*
X385834Y-40382D01*
X385309Y-40774D01*
X384994Y-41479D01*
X385099Y-42184D01*
X385519Y-42889D01*
G01X390034Y-37215D02*
X390769Y-36745D01*
X391189Y-36119D01*
X391294Y-35414D01*
X391189Y-34787D01*
X390664Y-34160D01*
X390034Y-33769D01*
X389404Y-33690D01*
X388669Y-33847D01*
X388144Y-34395D01*
X387934Y-34944D01*
Y-35649D01*
G01Y-34944D02*
X387619Y-34474D01*
X387094Y-34082D01*
X386464Y-33925D01*
X385834Y-34082D01*
X385309Y-34474D01*
X384994Y-35179D01*
X385099Y-35884D01*
X385519Y-36589D01*
G01X391504Y-29192D02*
X391399Y-29349D01*
X391189D01*
X391084Y-29192D01*
X391189Y-29035D01*
X391399D01*
X391504Y-29192D01*
G01X391294Y-22892D02*
X391189Y-22344D01*
X390874Y-21717D01*
X390349Y-21325D01*
X389614Y-21169D01*
X388879Y-21325D01*
X388249Y-21795D01*
X387934Y-22500D01*
Y-23284D01*
X387724Y-23754D01*
X387199Y-24145D01*
X386464Y-24302D01*
X385729Y-24067D01*
X385204Y-23519D01*
X384994Y-22892D01*
X385204Y-22265D01*
X385729Y-21717D01*
X386464Y-21482D01*
X387199Y-21639D01*
X387724Y-22030D01*
X387934Y-22500D01*
Y-23284D01*
X388249Y-23989D01*
X388879Y-24459D01*
X389614Y-24615D01*
X390349Y-24459D01*
X390874Y-24067D01*
X391189Y-23440D01*
X391294Y-22892D01*
G01X390349Y-18315D02*
X390874Y-17845D01*
X391189Y-17297D01*
X391294Y-16592D01*
X391084Y-15887D01*
X390664Y-15339D01*
X389929Y-14947D01*
X389089Y-14869D01*
X388249Y-15025D01*
X387724Y-15417D01*
X387304Y-15965D01*
X387199Y-16514D01*
X387304Y-17062D01*
X387724Y-17767D01*
X384994Y-17532D01*
Y-15417D01*
G01X407597Y389396D02*
X408067Y388661D01*
X408693Y388241D01*
X409398Y388136D01*
X410025Y388241D01*
X410652Y388766D01*
X411043Y389396D01*
X411122Y390026D01*
X410965Y390761D01*
X410417Y391286D01*
X409868Y391496D01*
X409163D01*
G01X409868D02*
X410338Y391811D01*
X410730Y392336D01*
X410887Y392966D01*
X410730Y393596D01*
X410338Y394121D01*
X409633Y394436D01*
X408928Y394331D01*
X408223Y393911D01*
G01X415620Y388136D02*
X416168Y388241D01*
X416795Y388556D01*
X417187Y389081D01*
X417343Y389816D01*
X417187Y390551D01*
X416717Y391181D01*
X416012Y391496D01*
X415228D01*
X414758Y391706D01*
X414367Y392231D01*
X414210Y392966D01*
X414445Y393701D01*
X414993Y394226D01*
X415620Y394436D01*
X416247Y394226D01*
X416795Y393701D01*
X417030Y392966D01*
X416873Y392231D01*
X416482Y391706D01*
X416012Y391496D01*
X415228D01*
X414523Y391181D01*
X414053Y390551D01*
X413897Y389816D01*
X414053Y389081D01*
X414445Y388556D01*
X415072Y388241D01*
X415620Y388136D01*
G01X420432Y393386D02*
X420902Y394016D01*
X421450Y394331D01*
X422077Y394436D01*
X422860Y394226D01*
X423408Y393701D01*
X423565Y393071D01*
X423487Y392441D01*
X423173Y391916D01*
X421607Y390866D01*
X420902Y390131D01*
X420432Y389081D01*
X420275Y388136D01*
X423565D01*
G01X426497Y389081D02*
X426967Y388556D01*
X427515Y388241D01*
X428220Y388136D01*
X428925Y388346D01*
X429473Y388766D01*
X429865Y389501D01*
X429943Y390341D01*
X429787Y391181D01*
X429395Y391706D01*
X428847Y392126D01*
X428298Y392231D01*
X427750Y392126D01*
X427045Y391706D01*
X427280Y394436D01*
X429395D01*
G01X434520Y387926D02*
X434363Y388031D01*
Y388241D01*
X434520Y388346D01*
X434677Y388241D01*
Y388031D01*
X434520Y387926D01*
G01X439332Y393386D02*
X439802Y394016D01*
X440350Y394331D01*
X440977Y394436D01*
X441760Y394226D01*
X442308Y393701D01*
X442465Y393071D01*
X442387Y392441D01*
X442073Y391916D01*
X440507Y390866D01*
X439802Y390131D01*
X439332Y389081D01*
X439175Y388136D01*
X442465D01*
G01X447120Y394436D02*
X446493Y394226D01*
X446023Y393701D01*
X445710Y393071D01*
X445475Y392231D01*
X445397Y391286D01*
X445475Y390341D01*
X445710Y389501D01*
X446023Y388871D01*
X446493Y388346D01*
X447120Y388136D01*
X447747Y388346D01*
X448217Y388871D01*
X448530Y389501D01*
X448765Y390341D01*
X448843Y391286D01*
X448765Y392231D01*
X448530Y393071D01*
X448217Y393701D01*
X447747Y394226D01*
X447120Y394436D01*
G01X419218Y29305D02*
X419688Y29935D01*
X420236Y30250D01*
X420863Y30355D01*
X421646Y30145D01*
X422194Y29620D01*
X422351Y28990D01*
X422273Y28360D01*
X421959Y27835D01*
X420393Y26785D01*
X419688Y26050D01*
X419218Y25000D01*
X419061Y24055D01*
X422351D01*
G01X426849D02*
X427006Y25420D01*
X427241Y26575D01*
X427554Y27625D01*
X427946Y28780D01*
X428573Y30355D01*
X425439D01*
G01X431818Y29305D02*
X432288Y29935D01*
X432836Y30250D01*
X433463Y30355D01*
X434246Y30145D01*
X434794Y29620D01*
X434951Y28990D01*
X434873Y28360D01*
X434559Y27835D01*
X432993Y26785D01*
X432288Y26050D01*
X431818Y25000D01*
X431661Y24055D01*
X434951D01*
G01X439606Y23845D02*
X439449Y23950D01*
Y24160D01*
X439606Y24265D01*
X439763Y24160D01*
Y23950D01*
X439606Y23845D01*
G01X445906Y30355D02*
X445279Y30145D01*
X444809Y29620D01*
X444496Y28990D01*
X444261Y28150D01*
X444183Y27205D01*
X444261Y26260D01*
X444496Y25420D01*
X444809Y24790D01*
X445279Y24265D01*
X445906Y24055D01*
X446533Y24265D01*
X447003Y24790D01*
X447316Y25420D01*
X447551Y26260D01*
X447629Y27205D01*
X447551Y28150D01*
X447316Y28990D01*
X447003Y29620D01*
X446533Y30145D01*
X445906Y30355D01*
G01X450483Y25000D02*
X450953Y24475D01*
X451501Y24160D01*
X452206Y24055D01*
X452911Y24265D01*
X453459Y24685D01*
X453851Y25420D01*
X453929Y26260D01*
X453773Y27100D01*
X453381Y27625D01*
X452833Y28045D01*
X452284Y28150D01*
X451736Y28045D01*
X451031Y27625D01*
X451266Y30355D01*
X453381D01*
G01X418983Y39585D02*
X419453Y38850D01*
X420079Y38430D01*
X420784Y38325D01*
X421411Y38430D01*
X422038Y38955D01*
X422429Y39585D01*
X422508Y40215D01*
X422351Y40950D01*
X421803Y41475D01*
X421254Y41685D01*
X420549D01*
G01X421254D02*
X421724Y42000D01*
X422116Y42525D01*
X422273Y43155D01*
X422116Y43785D01*
X421724Y44310D01*
X421019Y44625D01*
X420314Y44520D01*
X419609Y44100D01*
G01X425518Y43575D02*
X425988Y44205D01*
X426536Y44520D01*
X427163Y44625D01*
X427946Y44415D01*
X428494Y43890D01*
X428651Y43260D01*
X428573Y42630D01*
X428259Y42105D01*
X426693Y41055D01*
X425988Y40320D01*
X425518Y39270D01*
X425361Y38325D01*
X428651D01*
G01X431583Y39270D02*
X432053Y38745D01*
X432601Y38430D01*
X433306Y38325D01*
X434011Y38535D01*
X434559Y38955D01*
X434951Y39690D01*
X435029Y40530D01*
X434873Y41370D01*
X434481Y41895D01*
X433933Y42315D01*
X433384Y42420D01*
X432836Y42315D01*
X432131Y41895D01*
X432366Y44625D01*
X434481D01*
G01X439606Y38115D02*
X439449Y38220D01*
Y38430D01*
X439606Y38535D01*
X439763Y38430D01*
Y38220D01*
X439606Y38115D01*
G01X444418Y43575D02*
X444888Y44205D01*
X445436Y44520D01*
X446063Y44625D01*
X446846Y44415D01*
X447394Y43890D01*
X447551Y43260D01*
X447473Y42630D01*
X447159Y42105D01*
X445593Y41055D01*
X444888Y40320D01*
X444418Y39270D01*
X444261Y38325D01*
X447551D01*
G01X452206Y44625D02*
X451579Y44415D01*
X451109Y43890D01*
X450796Y43260D01*
X450561Y42420D01*
X450483Y41475D01*
X450561Y40530D01*
X450796Y39690D01*
X451109Y39060D01*
X451579Y38535D01*
X452206Y38325D01*
X452833Y38535D01*
X453303Y39060D01*
X453616Y39690D01*
X453851Y40530D01*
X453929Y41475D01*
X453851Y42420D01*
X453616Y43260D01*
X453303Y43890D01*
X452833Y44415D01*
X452206Y44625D01*
G01X433244Y124015D02*
Y130315D01*
X432304Y129055D01*
G01Y124015D02*
X434184D01*
G01X438056Y129265D02*
X438526Y129895D01*
X439074Y130210D01*
X439701Y130315D01*
X440484Y130105D01*
X441032Y129580D01*
X441189Y128950D01*
X441111Y128320D01*
X440797Y127795D01*
X439231Y126745D01*
X438526Y126010D01*
X438056Y124960D01*
X437899Y124015D01*
X441189D01*
G01X445687D02*
X445844Y125380D01*
X446079Y126535D01*
X446392Y127585D01*
X446784Y128740D01*
X447411Y130315D01*
X444277D01*
G01X452144Y124015D02*
Y130315D01*
X451204Y129055D01*
G01Y124015D02*
X453084D01*
G01X458444Y123805D02*
X458287Y123910D01*
Y124120D01*
X458444Y124225D01*
X458601Y124120D01*
Y123910D01*
X458444Y123805D01*
G01X463256Y126640D02*
X463804Y127375D01*
X464274Y127795D01*
X464901Y128005D01*
X465449Y127795D01*
X465841Y127375D01*
X466154Y126745D01*
X466232Y126010D01*
X466154Y125380D01*
X465841Y124750D01*
X465371Y124225D01*
X464822Y124015D01*
X464196Y124225D01*
X463647Y124855D01*
X463334Y125800D01*
X463256Y126850D01*
X463412Y128215D01*
X463647Y128950D01*
X464039Y129685D01*
X464587Y130210D01*
X465136Y130315D01*
X465684Y130105D01*
X466076Y129580D01*
G01X469321Y124960D02*
X469791Y124435D01*
X470339Y124120D01*
X471044Y124015D01*
X471749Y124225D01*
X472297Y124645D01*
X472689Y125380D01*
X472767Y126220D01*
X472611Y127060D01*
X472219Y127585D01*
X471671Y128005D01*
X471122Y128110D01*
X470574Y128005D01*
X469869Y127585D01*
X470104Y130315D01*
X472219D01*
G01X420969Y204305D02*
X421439Y204935D01*
X421987Y205250D01*
X422614Y205355D01*
X423397Y205145D01*
X423945Y204620D01*
X424102Y203990D01*
X424024Y203360D01*
X423710Y202835D01*
X422144Y201785D01*
X421439Y201050D01*
X420969Y200000D01*
X420812Y199055D01*
X424102D01*
G01X428757Y205355D02*
X428130Y205145D01*
X427660Y204620D01*
X427347Y203990D01*
X427112Y203150D01*
X427034Y202205D01*
X427112Y201260D01*
X427347Y200420D01*
X427660Y199790D01*
X428130Y199265D01*
X428757Y199055D01*
X429384Y199265D01*
X429854Y199790D01*
X430167Y200420D01*
X430402Y201260D01*
X430480Y202205D01*
X430402Y203150D01*
X430167Y203990D01*
X429854Y204620D01*
X429384Y205145D01*
X428757Y205355D01*
G01X433569Y204305D02*
X434039Y204935D01*
X434587Y205250D01*
X435214Y205355D01*
X435997Y205145D01*
X436545Y204620D01*
X436702Y203990D01*
X436624Y203360D01*
X436310Y202835D01*
X434744Y201785D01*
X434039Y201050D01*
X433569Y200000D01*
X433412Y199055D01*
X436702D01*
G01X439869Y204305D02*
X440339Y204935D01*
X440887Y205250D01*
X441514Y205355D01*
X442297Y205145D01*
X442845Y204620D01*
X443002Y203990D01*
X442924Y203360D01*
X442610Y202835D01*
X441044Y201785D01*
X440339Y201050D01*
X439869Y200000D01*
X439712Y199055D01*
X443002D01*
G01X447657Y198845D02*
X447500Y198950D01*
Y199160D01*
X447657Y199265D01*
X447814Y199160D01*
Y198950D01*
X447657Y198845D01*
G01X453957Y205355D02*
X453330Y205145D01*
X452860Y204620D01*
X452547Y203990D01*
X452312Y203150D01*
X452234Y202205D01*
X452312Y201260D01*
X452547Y200420D01*
X452860Y199790D01*
X453330Y199265D01*
X453957Y199055D01*
X454584Y199265D01*
X455054Y199790D01*
X455367Y200420D01*
X455602Y201260D01*
X455680Y202205D01*
X455602Y203150D01*
X455367Y203990D01*
X455054Y204620D01*
X454584Y205145D01*
X453957Y205355D01*
G01X458534Y200000D02*
X459004Y199475D01*
X459552Y199160D01*
X460257Y199055D01*
X460962Y199265D01*
X461510Y199685D01*
X461902Y200420D01*
X461980Y201260D01*
X461824Y202100D01*
X461432Y202625D01*
X460884Y203045D01*
X460335Y203150D01*
X459787Y203045D01*
X459082Y202625D01*
X459317Y205355D01*
X461432D01*
G01X418106Y216374D02*
X418576Y217004D01*
X419124Y217319D01*
X419751Y217424D01*
X420534Y217214D01*
X421082Y216689D01*
X421239Y216059D01*
X421161Y215429D01*
X420847Y214904D01*
X419281Y213854D01*
X418576Y213119D01*
X418106Y212069D01*
X417949Y211124D01*
X421239D01*
G01X425894Y217424D02*
X425267Y217214D01*
X424797Y216689D01*
X424484Y216059D01*
X424249Y215219D01*
X424171Y214274D01*
X424249Y213329D01*
X424484Y212489D01*
X424797Y211859D01*
X425267Y211334D01*
X425894Y211124D01*
X426521Y211334D01*
X426991Y211859D01*
X427304Y212489D01*
X427539Y213329D01*
X427617Y214274D01*
X427539Y215219D01*
X427304Y216059D01*
X426991Y216689D01*
X426521Y217214D01*
X425894Y217424D01*
G01X432037Y211124D02*
X432194Y212489D01*
X432429Y213644D01*
X432742Y214694D01*
X433134Y215849D01*
X433761Y217424D01*
X430627D01*
G01X436771Y212069D02*
X437241Y211544D01*
X437789Y211229D01*
X438494Y211124D01*
X439199Y211334D01*
X439747Y211754D01*
X440139Y212489D01*
X440217Y213329D01*
X440061Y214169D01*
X439669Y214694D01*
X439121Y215114D01*
X438572Y215219D01*
X438024Y215114D01*
X437319Y214694D01*
X437554Y217424D01*
X439669D01*
G01X444794Y210914D02*
X444637Y211019D01*
Y211229D01*
X444794Y211334D01*
X444951Y211229D01*
Y211019D01*
X444794Y210914D01*
G01X449606Y216374D02*
X450076Y217004D01*
X450624Y217319D01*
X451251Y217424D01*
X452034Y217214D01*
X452582Y216689D01*
X452739Y216059D01*
X452661Y215429D01*
X452347Y214904D01*
X450781Y213854D01*
X450076Y213119D01*
X449606Y212069D01*
X449449Y211124D01*
X452739D01*
G01X457394Y217424D02*
X456767Y217214D01*
X456297Y216689D01*
X455984Y216059D01*
X455749Y215219D01*
X455671Y214274D01*
X455749Y213329D01*
X455984Y212489D01*
X456297Y211859D01*
X456767Y211334D01*
X457394Y211124D01*
X458021Y211334D01*
X458491Y211859D01*
X458804Y212489D01*
X459039Y213329D01*
X459117Y214274D01*
X459039Y215219D01*
X458804Y216059D01*
X458491Y216689D01*
X458021Y217214D01*
X457394Y217424D01*
G01X412650Y375315D02*
X413120Y374580D01*
X413746Y374160D01*
X414451Y374055D01*
X415078Y374160D01*
X415705Y374685D01*
X416096Y375315D01*
X416175Y375945D01*
X416018Y376680D01*
X415470Y377205D01*
X414921Y377415D01*
X414216D01*
G01X414921D02*
X415391Y377730D01*
X415783Y378255D01*
X415940Y378885D01*
X415783Y379515D01*
X415391Y380040D01*
X414686Y380355D01*
X413981Y380250D01*
X413276Y379830D01*
G01X420516Y374055D02*
X420673Y375420D01*
X420908Y376575D01*
X421221Y377625D01*
X421613Y378780D01*
X422240Y380355D01*
X419106D01*
G01X426816Y374055D02*
X426973Y375420D01*
X427208Y376575D01*
X427521Y377625D01*
X427913Y378780D01*
X428540Y380355D01*
X425406D01*
G01X431785Y379305D02*
X432255Y379935D01*
X432803Y380250D01*
X433430Y380355D01*
X434213Y380145D01*
X434761Y379620D01*
X434918Y378990D01*
X434840Y378360D01*
X434526Y377835D01*
X432960Y376785D01*
X432255Y376050D01*
X431785Y375000D01*
X431628Y374055D01*
X434918D01*
G01X439573Y373845D02*
X439416Y373950D01*
Y374160D01*
X439573Y374265D01*
X439730Y374160D01*
Y373950D01*
X439573Y373845D01*
G01X445873Y380355D02*
X445246Y380145D01*
X444776Y379620D01*
X444463Y378990D01*
X444228Y378150D01*
X444150Y377205D01*
X444228Y376260D01*
X444463Y375420D01*
X444776Y374790D01*
X445246Y374265D01*
X445873Y374055D01*
X446500Y374265D01*
X446970Y374790D01*
X447283Y375420D01*
X447518Y376260D01*
X447596Y377205D01*
X447518Y378150D01*
X447283Y378990D01*
X446970Y379620D01*
X446500Y380145D01*
X445873Y380355D01*
G01X450450Y375000D02*
X450920Y374475D01*
X451468Y374160D01*
X452173Y374055D01*
X452878Y374265D01*
X453426Y374685D01*
X453818Y375420D01*
X453896Y376260D01*
X453740Y377100D01*
X453348Y377625D01*
X452800Y378045D01*
X452251Y378150D01*
X451703Y378045D01*
X450998Y377625D01*
X451233Y380355D01*
X453348D01*
G01X433510Y425629D02*
Y431929D01*
X430612Y427414D01*
X434528D01*
G01X437382Y430879D02*
X437852Y431509D01*
X438400Y431824D01*
X439027Y431929D01*
X439810Y431719D01*
X440358Y431194D01*
X440515Y430564D01*
X440437Y429934D01*
X440123Y429409D01*
X438557Y428359D01*
X437852Y427624D01*
X437382Y426574D01*
X437225Y425629D01*
X440515D01*
G01X445170D02*
X445718Y425734D01*
X446345Y426049D01*
X446737Y426574D01*
X446893Y427309D01*
X446737Y428044D01*
X446267Y428674D01*
X445562Y428989D01*
X444778D01*
X444308Y429199D01*
X443917Y429724D01*
X443760Y430459D01*
X443995Y431194D01*
X444543Y431719D01*
X445170Y431929D01*
X445797Y431719D01*
X446345Y431194D01*
X446580Y430459D01*
X446423Y429724D01*
X446032Y429199D01*
X445562Y428989D01*
X444778D01*
X444073Y428674D01*
X443603Y428044D01*
X443447Y427309D01*
X443603Y426574D01*
X443995Y426049D01*
X444622Y425734D01*
X445170Y425629D01*
G01X451313D02*
X451470Y426994D01*
X451705Y428149D01*
X452018Y429199D01*
X452410Y430354D01*
X453037Y431929D01*
X449903D01*
G01X457770Y425419D02*
X457613Y425524D01*
Y425734D01*
X457770Y425839D01*
X457927Y425734D01*
Y425524D01*
X457770Y425419D01*
G01X463913Y425629D02*
X464070Y426994D01*
X464305Y428149D01*
X464618Y429199D01*
X465010Y430354D01*
X465637Y431929D01*
X462503D01*
G01X469038Y426364D02*
X469587Y425839D01*
X470213Y425629D01*
X470840Y425839D01*
X471388Y426469D01*
X471780Y427414D01*
X471937Y428359D01*
Y429514D01*
X471780Y430459D01*
X471388Y431299D01*
X470918Y431719D01*
X470370Y431929D01*
X469743Y431719D01*
X469273Y431299D01*
X468960Y430669D01*
X468803Y429829D01*
X468960Y429094D01*
X469352Y428359D01*
X469822Y427939D01*
X470370Y427834D01*
X470997Y428044D01*
X471467Y428569D01*
X471937Y429514D01*
G01X421039Y474015D02*
Y480315D01*
X418141Y475800D01*
X422057D01*
G01X426242Y474015D02*
X426399Y475380D01*
X426634Y476535D01*
X426947Y477585D01*
X427339Y478740D01*
X427966Y480315D01*
X424832D01*
G01X432542Y474015D02*
X432699Y475380D01*
X432934Y476535D01*
X433247Y477585D01*
X433639Y478740D01*
X434266Y480315D01*
X431132D01*
G01X438999Y474015D02*
Y480315D01*
X438059Y479055D01*
G01Y474015D02*
X439939D01*
G01X445299Y473805D02*
X445142Y473910D01*
Y474120D01*
X445299Y474225D01*
X445456Y474120D01*
Y473910D01*
X445299Y473805D01*
G01X450111Y476640D02*
X450659Y477375D01*
X451129Y477795D01*
X451756Y478005D01*
X452304Y477795D01*
X452696Y477375D01*
X453009Y476745D01*
X453087Y476010D01*
X453009Y475380D01*
X452696Y474750D01*
X452226Y474225D01*
X451677Y474015D01*
X451051Y474225D01*
X450502Y474855D01*
X450189Y475800D01*
X450111Y476850D01*
X450267Y478215D01*
X450502Y478950D01*
X450894Y479685D01*
X451442Y480210D01*
X451991Y480315D01*
X452539Y480105D01*
X452931Y479580D01*
G01X456176Y474960D02*
X456646Y474435D01*
X457194Y474120D01*
X457899Y474015D01*
X458604Y474225D01*
X459152Y474645D01*
X459544Y475380D01*
X459622Y476220D01*
X459466Y477060D01*
X459074Y477585D01*
X458526Y478005D01*
X457977Y478110D01*
X457429Y478005D01*
X456724Y477585D01*
X456959Y480315D01*
X459074D01*
G01X427302Y550000D02*
X427772Y549475D01*
X428320Y549160D01*
X429025Y549055D01*
X429730Y549265D01*
X430278Y549685D01*
X430670Y550420D01*
X430748Y551260D01*
X430592Y552100D01*
X430200Y552625D01*
X429652Y553045D01*
X429103Y553150D01*
X428555Y553045D01*
X427850Y552625D01*
X428085Y555355D01*
X430200D01*
G01X433602Y550000D02*
X434072Y549475D01*
X434620Y549160D01*
X435325Y549055D01*
X436030Y549265D01*
X436578Y549685D01*
X436970Y550420D01*
X437048Y551260D01*
X436892Y552100D01*
X436500Y552625D01*
X435952Y553045D01*
X435403Y553150D01*
X434855Y553045D01*
X434150Y552625D01*
X434385Y555355D01*
X436500D01*
G01X440137Y554305D02*
X440607Y554935D01*
X441155Y555250D01*
X441782Y555355D01*
X442565Y555145D01*
X443113Y554620D01*
X443270Y553990D01*
X443192Y553360D01*
X442878Y552835D01*
X441312Y551785D01*
X440607Y551050D01*
X440137Y550000D01*
X439980Y549055D01*
X443270D01*
G01X446437Y554305D02*
X446907Y554935D01*
X447455Y555250D01*
X448082Y555355D01*
X448865Y555145D01*
X449413Y554620D01*
X449570Y553990D01*
X449492Y553360D01*
X449178Y552835D01*
X447612Y551785D01*
X446907Y551050D01*
X446437Y550000D01*
X446280Y549055D01*
X449570D01*
G01X454225Y548845D02*
X454068Y548950D01*
Y549160D01*
X454225Y549265D01*
X454382Y549160D01*
Y548950D01*
X454225Y548845D01*
G01X460525Y555355D02*
X459898Y555145D01*
X459428Y554620D01*
X459115Y553990D01*
X458880Y553150D01*
X458802Y552205D01*
X458880Y551260D01*
X459115Y550420D01*
X459428Y549790D01*
X459898Y549265D01*
X460525Y549055D01*
X461152Y549265D01*
X461622Y549790D01*
X461935Y550420D01*
X462170Y551260D01*
X462248Y552205D01*
X462170Y553150D01*
X461935Y553990D01*
X461622Y554620D01*
X461152Y555145D01*
X460525Y555355D01*
G01X465102Y550000D02*
X465572Y549475D01*
X466120Y549160D01*
X466825Y549055D01*
X467530Y549265D01*
X468078Y549685D01*
X468470Y550420D01*
X468548Y551260D01*
X468392Y552100D01*
X468000Y552625D01*
X467452Y553045D01*
X466903Y553150D01*
X466355Y553045D01*
X465650Y552625D01*
X465885Y555355D01*
X468000D01*
G01X417533Y564073D02*
X418003Y563548D01*
X418551Y563233D01*
X419256Y563128D01*
X419961Y563338D01*
X420509Y563758D01*
X420901Y564493D01*
X420979Y565333D01*
X420823Y566173D01*
X420431Y566698D01*
X419883Y567118D01*
X419334Y567223D01*
X418786Y567118D01*
X418081Y566698D01*
X418316Y569428D01*
X420431D01*
G01X423833Y564073D02*
X424303Y563548D01*
X424851Y563233D01*
X425556Y563128D01*
X426261Y563338D01*
X426809Y563758D01*
X427201Y564493D01*
X427279Y565333D01*
X427123Y566173D01*
X426731Y566698D01*
X426183Y567118D01*
X425634Y567223D01*
X425086Y567118D01*
X424381Y566698D01*
X424616Y569428D01*
X426731D01*
G01X431699Y563128D02*
X431856Y564493D01*
X432091Y565648D01*
X432404Y566698D01*
X432796Y567853D01*
X433423Y569428D01*
X430289D01*
G01X436433Y564073D02*
X436903Y563548D01*
X437451Y563233D01*
X438156Y563128D01*
X438861Y563338D01*
X439409Y563758D01*
X439801Y564493D01*
X439879Y565333D01*
X439723Y566173D01*
X439331Y566698D01*
X438783Y567118D01*
X438234Y567223D01*
X437686Y567118D01*
X436981Y566698D01*
X437216Y569428D01*
X439331D01*
G01X444456Y562918D02*
X444299Y563023D01*
Y563233D01*
X444456Y563338D01*
X444613Y563233D01*
Y563023D01*
X444456Y562918D01*
G01X449268Y568378D02*
X449738Y569008D01*
X450286Y569323D01*
X450913Y569428D01*
X451696Y569218D01*
X452244Y568693D01*
X452401Y568063D01*
X452323Y567433D01*
X452009Y566908D01*
X450443Y565858D01*
X449738Y565123D01*
X449268Y564073D01*
X449111Y563128D01*
X452401D01*
G01X457056Y569428D02*
X456429Y569218D01*
X455959Y568693D01*
X455646Y568063D01*
X455411Y567223D01*
X455333Y566278D01*
X455411Y565333D01*
X455646Y564493D01*
X455959Y563863D01*
X456429Y563338D01*
X457056Y563128D01*
X457683Y563338D01*
X458153Y563863D01*
X458466Y564493D01*
X458701Y565333D01*
X458779Y566278D01*
X458701Y567223D01*
X458466Y568063D01*
X458153Y568693D01*
X457683Y569218D01*
X457056Y569428D01*
G01X430368Y724055D02*
X430525Y725420D01*
X430760Y726575D01*
X431073Y727625D01*
X431465Y728780D01*
X432092Y730355D01*
X428958D01*
G01X435337Y729305D02*
X435807Y729935D01*
X436355Y730250D01*
X436982Y730355D01*
X437765Y730145D01*
X438313Y729620D01*
X438470Y728990D01*
X438392Y728360D01*
X438078Y727835D01*
X436512Y726785D01*
X435807Y726050D01*
X435337Y725000D01*
X435180Y724055D01*
X438470D01*
G01X442968D02*
X443125Y725420D01*
X443360Y726575D01*
X443673Y727625D01*
X444065Y728780D01*
X444692Y730355D01*
X441558D01*
G01X447937Y729305D02*
X448407Y729935D01*
X448955Y730250D01*
X449582Y730355D01*
X450365Y730145D01*
X450913Y729620D01*
X451070Y728990D01*
X450992Y728360D01*
X450678Y727835D01*
X449112Y726785D01*
X448407Y726050D01*
X447937Y725000D01*
X447780Y724055D01*
X451070D01*
G01X455725Y723845D02*
X455568Y723950D01*
Y724160D01*
X455725Y724265D01*
X455882Y724160D01*
Y723950D01*
X455725Y723845D01*
G01X462025Y730355D02*
X461398Y730145D01*
X460928Y729620D01*
X460615Y728990D01*
X460380Y728150D01*
X460302Y727205D01*
X460380Y726260D01*
X460615Y725420D01*
X460928Y724790D01*
X461398Y724265D01*
X462025Y724055D01*
X462652Y724265D01*
X463122Y724790D01*
X463435Y725420D01*
X463670Y726260D01*
X463748Y727205D01*
X463670Y728150D01*
X463435Y728990D01*
X463122Y729620D01*
X462652Y730145D01*
X462025Y730355D01*
G01X466602Y725000D02*
X467072Y724475D01*
X467620Y724160D01*
X468325Y724055D01*
X469030Y724265D01*
X469578Y724685D01*
X469970Y725420D01*
X470048Y726260D01*
X469892Y727100D01*
X469500Y727625D01*
X468952Y728045D01*
X468403Y728150D01*
X467855Y728045D01*
X467150Y727625D01*
X467385Y730355D01*
X469500D01*
G01X424978Y739964D02*
X425135Y741329D01*
X425370Y742484D01*
X425683Y743534D01*
X426075Y744689D01*
X426702Y746264D01*
X423568D01*
G01X429712Y741224D02*
X430182Y740489D01*
X430808Y740069D01*
X431513Y739964D01*
X432140Y740069D01*
X432767Y740594D01*
X433158Y741224D01*
X433237Y741854D01*
X433080Y742589D01*
X432532Y743114D01*
X431983Y743324D01*
X431278D01*
G01X431983D02*
X432453Y743639D01*
X432845Y744164D01*
X433002Y744794D01*
X432845Y745424D01*
X432453Y745949D01*
X431748Y746264D01*
X431043Y746159D01*
X430338Y745739D01*
G01X436247Y745214D02*
X436717Y745844D01*
X437265Y746159D01*
X437892Y746264D01*
X438675Y746054D01*
X439223Y745529D01*
X439380Y744899D01*
X439302Y744269D01*
X438988Y743744D01*
X437422Y742694D01*
X436717Y741959D01*
X436247Y740909D01*
X436090Y739964D01*
X439380D01*
G01X442312Y740909D02*
X442782Y740384D01*
X443330Y740069D01*
X444035Y739964D01*
X444740Y740174D01*
X445288Y740594D01*
X445680Y741329D01*
X445758Y742169D01*
X445602Y743009D01*
X445210Y743534D01*
X444662Y743954D01*
X444113Y744059D01*
X443565Y743954D01*
X442860Y743534D01*
X443095Y746264D01*
X445210D01*
G01X450335Y739754D02*
X450178Y739859D01*
Y740069D01*
X450335Y740174D01*
X450492Y740069D01*
Y739859D01*
X450335Y739754D01*
G01X455147Y745214D02*
X455617Y745844D01*
X456165Y746159D01*
X456792Y746264D01*
X457575Y746054D01*
X458123Y745529D01*
X458280Y744899D01*
X458202Y744269D01*
X457888Y743744D01*
X456322Y742694D01*
X455617Y741959D01*
X455147Y740909D01*
X454990Y739964D01*
X458280D01*
G01X462935Y746264D02*
X462308Y746054D01*
X461838Y745529D01*
X461525Y744899D01*
X461290Y744059D01*
X461212Y743114D01*
X461290Y742169D01*
X461525Y741329D01*
X461838Y740699D01*
X462308Y740174D01*
X462935Y739964D01*
X463562Y740174D01*
X464032Y740699D01*
X464345Y741329D01*
X464580Y742169D01*
X464658Y743114D01*
X464580Y744059D01*
X464345Y744899D01*
X464032Y745529D01*
X463562Y746054D01*
X462935Y746264D01*
G01X432899Y824015D02*
X433447Y824120D01*
X434074Y824435D01*
X434466Y824960D01*
X434622Y825695D01*
X434466Y826430D01*
X433996Y827060D01*
X433291Y827375D01*
X432507D01*
X432037Y827585D01*
X431646Y828110D01*
X431489Y828845D01*
X431724Y829580D01*
X432272Y830105D01*
X432899Y830315D01*
X433526Y830105D01*
X434074Y829580D01*
X434309Y828845D01*
X434152Y828110D01*
X433761Y827585D01*
X433291Y827375D01*
X432507D01*
X431802Y827060D01*
X431332Y826430D01*
X431176Y825695D01*
X431332Y824960D01*
X431724Y824435D01*
X432351Y824120D01*
X432899Y824015D01*
G01X437711Y829265D02*
X438181Y829895D01*
X438729Y830210D01*
X439356Y830315D01*
X440139Y830105D01*
X440687Y829580D01*
X440844Y828950D01*
X440766Y828320D01*
X440452Y827795D01*
X438886Y826745D01*
X438181Y826010D01*
X437711Y824960D01*
X437554Y824015D01*
X440844D01*
G01X445342D02*
X445499Y825380D01*
X445734Y826535D01*
X446047Y827585D01*
X446439Y828740D01*
X447066Y830315D01*
X443932D01*
G01X451799Y824015D02*
Y830315D01*
X450859Y829055D01*
G01Y824015D02*
X452739D01*
G01X458099Y823805D02*
X457942Y823910D01*
Y824120D01*
X458099Y824225D01*
X458256Y824120D01*
Y823910D01*
X458099Y823805D01*
G01X462911Y826640D02*
X463459Y827375D01*
X463929Y827795D01*
X464556Y828005D01*
X465104Y827795D01*
X465496Y827375D01*
X465809Y826745D01*
X465887Y826010D01*
X465809Y825380D01*
X465496Y824750D01*
X465026Y824225D01*
X464477Y824015D01*
X463851Y824225D01*
X463302Y824855D01*
X462989Y825800D01*
X462911Y826850D01*
X463067Y828215D01*
X463302Y828950D01*
X463694Y829685D01*
X464242Y830210D01*
X464791Y830315D01*
X465339Y830105D01*
X465731Y829580D01*
G01X468976Y824960D02*
X469446Y824435D01*
X469994Y824120D01*
X470699Y824015D01*
X471404Y824225D01*
X471952Y824645D01*
X472344Y825380D01*
X472422Y826220D01*
X472266Y827060D01*
X471874Y827585D01*
X471326Y828005D01*
X470777Y828110D01*
X470229Y828005D01*
X469524Y827585D01*
X469759Y830315D01*
X471874D01*
G01X425033Y1074055D02*
Y1080355D01*
X424093Y1079095D01*
G01Y1074055D02*
X425973D01*
G01X431333Y1080355D02*
X430706Y1080145D01*
X430236Y1079620D01*
X429923Y1078990D01*
X429688Y1078150D01*
X429610Y1077205D01*
X429688Y1076260D01*
X429923Y1075420D01*
X430236Y1074790D01*
X430706Y1074265D01*
X431333Y1074055D01*
X431960Y1074265D01*
X432430Y1074790D01*
X432743Y1075420D01*
X432978Y1076260D01*
X433056Y1077205D01*
X432978Y1078150D01*
X432743Y1078990D01*
X432430Y1079620D01*
X431960Y1080145D01*
X431333Y1080355D01*
G01X437476Y1074055D02*
X437633Y1075420D01*
X437868Y1076575D01*
X438181Y1077625D01*
X438573Y1078780D01*
X439200Y1080355D01*
X436066D01*
G01X443776Y1074055D02*
X443933Y1075420D01*
X444168Y1076575D01*
X444481Y1077625D01*
X444873Y1078780D01*
X445500Y1080355D01*
X442366D01*
G01X448745Y1079305D02*
X449215Y1079935D01*
X449763Y1080250D01*
X450390Y1080355D01*
X451173Y1080145D01*
X451721Y1079620D01*
X451878Y1078990D01*
X451800Y1078360D01*
X451486Y1077835D01*
X449920Y1076785D01*
X449215Y1076050D01*
X448745Y1075000D01*
X448588Y1074055D01*
X451878D01*
G01X456533Y1073845D02*
X456376Y1073950D01*
Y1074160D01*
X456533Y1074265D01*
X456690Y1074160D01*
Y1073950D01*
X456533Y1073845D01*
G01X462833Y1080355D02*
X462206Y1080145D01*
X461736Y1079620D01*
X461423Y1078990D01*
X461188Y1078150D01*
X461110Y1077205D01*
X461188Y1076260D01*
X461423Y1075420D01*
X461736Y1074790D01*
X462206Y1074265D01*
X462833Y1074055D01*
X463460Y1074265D01*
X463930Y1074790D01*
X464243Y1075420D01*
X464478Y1076260D01*
X464556Y1077205D01*
X464478Y1078150D01*
X464243Y1078990D01*
X463930Y1079620D01*
X463460Y1080145D01*
X462833Y1080355D01*
G01X467410Y1075000D02*
X467880Y1074475D01*
X468428Y1074160D01*
X469133Y1074055D01*
X469838Y1074265D01*
X470386Y1074685D01*
X470778Y1075420D01*
X470856Y1076260D01*
X470700Y1077100D01*
X470308Y1077625D01*
X469760Y1078045D01*
X469211Y1078150D01*
X468663Y1078045D01*
X467958Y1077625D01*
X468193Y1080355D01*
X470308D01*
G01X423012Y1089105D02*
Y1095405D01*
X422072Y1094145D01*
G01Y1089105D02*
X423952D01*
G01X429312Y1095405D02*
X428685Y1095195D01*
X428215Y1094670D01*
X427902Y1094040D01*
X427667Y1093200D01*
X427589Y1092255D01*
X427667Y1091310D01*
X427902Y1090470D01*
X428215Y1089840D01*
X428685Y1089315D01*
X429312Y1089105D01*
X429939Y1089315D01*
X430409Y1089840D01*
X430722Y1090470D01*
X430957Y1091310D01*
X431035Y1092255D01*
X430957Y1093200D01*
X430722Y1094040D01*
X430409Y1094670D01*
X429939Y1095195D01*
X429312Y1095405D01*
G01X435612Y1089105D02*
X436160Y1089210D01*
X436787Y1089525D01*
X437179Y1090050D01*
X437335Y1090785D01*
X437179Y1091520D01*
X436709Y1092150D01*
X436004Y1092465D01*
X435220D01*
X434750Y1092675D01*
X434359Y1093200D01*
X434202Y1093935D01*
X434437Y1094670D01*
X434985Y1095195D01*
X435612Y1095405D01*
X436239Y1095195D01*
X436787Y1094670D01*
X437022Y1093935D01*
X436865Y1093200D01*
X436474Y1092675D01*
X436004Y1092465D01*
X435220D01*
X434515Y1092150D01*
X434045Y1091520D01*
X433889Y1090785D01*
X434045Y1090050D01*
X434437Y1089525D01*
X435064Y1089210D01*
X435612Y1089105D01*
G01X440424Y1094355D02*
X440894Y1094985D01*
X441442Y1095300D01*
X442069Y1095405D01*
X442852Y1095195D01*
X443400Y1094670D01*
X443557Y1094040D01*
X443479Y1093410D01*
X443165Y1092885D01*
X441599Y1091835D01*
X440894Y1091100D01*
X440424Y1090050D01*
X440267Y1089105D01*
X443557D01*
G01X446489Y1090050D02*
X446959Y1089525D01*
X447507Y1089210D01*
X448212Y1089105D01*
X448917Y1089315D01*
X449465Y1089735D01*
X449857Y1090470D01*
X449935Y1091310D01*
X449779Y1092150D01*
X449387Y1092675D01*
X448839Y1093095D01*
X448290Y1093200D01*
X447742Y1093095D01*
X447037Y1092675D01*
X447272Y1095405D01*
X449387D01*
G01X454512Y1088895D02*
X454355Y1089000D01*
Y1089210D01*
X454512Y1089315D01*
X454669Y1089210D01*
Y1089000D01*
X454512Y1088895D01*
G01X459324Y1094355D02*
X459794Y1094985D01*
X460342Y1095300D01*
X460969Y1095405D01*
X461752Y1095195D01*
X462300Y1094670D01*
X462457Y1094040D01*
X462379Y1093410D01*
X462065Y1092885D01*
X460499Y1091835D01*
X459794Y1091100D01*
X459324Y1090050D01*
X459167Y1089105D01*
X462457D01*
G01X467112Y1095405D02*
X466485Y1095195D01*
X466015Y1094670D01*
X465702Y1094040D01*
X465467Y1093200D01*
X465389Y1092255D01*
X465467Y1091310D01*
X465702Y1090470D01*
X466015Y1089840D01*
X466485Y1089315D01*
X467112Y1089105D01*
X467739Y1089315D01*
X468209Y1089840D01*
X468522Y1090470D01*
X468757Y1091310D01*
X468835Y1092255D01*
X468757Y1093200D01*
X468522Y1094040D01*
X468209Y1094670D01*
X467739Y1095195D01*
X467112Y1095405D01*
G01X425353Y1599055D02*
Y1605355D01*
X424413Y1604095D01*
G01Y1599055D02*
X426293D01*
G01X430165Y1601680D02*
X430713Y1602415D01*
X431183Y1602835D01*
X431810Y1603045D01*
X432358Y1602835D01*
X432750Y1602415D01*
X433063Y1601785D01*
X433141Y1601050D01*
X433063Y1600420D01*
X432750Y1599790D01*
X432280Y1599265D01*
X431731Y1599055D01*
X431105Y1599265D01*
X430556Y1599895D01*
X430243Y1600840D01*
X430165Y1601890D01*
X430321Y1603255D01*
X430556Y1603990D01*
X430948Y1604725D01*
X431496Y1605250D01*
X432045Y1605355D01*
X432593Y1605145D01*
X432985Y1604620D01*
G01X437953Y1605355D02*
X437326Y1605145D01*
X436856Y1604620D01*
X436543Y1603990D01*
X436308Y1603150D01*
X436230Y1602205D01*
X436308Y1601260D01*
X436543Y1600420D01*
X436856Y1599790D01*
X437326Y1599265D01*
X437953Y1599055D01*
X438580Y1599265D01*
X439050Y1599790D01*
X439363Y1600420D01*
X439598Y1601260D01*
X439676Y1602205D01*
X439598Y1603150D01*
X439363Y1603990D01*
X439050Y1604620D01*
X438580Y1605145D01*
X437953Y1605355D01*
G01X442765Y1604305D02*
X443235Y1604935D01*
X443783Y1605250D01*
X444410Y1605355D01*
X445193Y1605145D01*
X445741Y1604620D01*
X445898Y1603990D01*
X445820Y1603360D01*
X445506Y1602835D01*
X443940Y1601785D01*
X443235Y1601050D01*
X442765Y1600000D01*
X442608Y1599055D01*
X445898D01*
G01X449065Y1604305D02*
X449535Y1604935D01*
X450083Y1605250D01*
X450710Y1605355D01*
X451493Y1605145D01*
X452041Y1604620D01*
X452198Y1603990D01*
X452120Y1603360D01*
X451806Y1602835D01*
X450240Y1601785D01*
X449535Y1601050D01*
X449065Y1600000D01*
X448908Y1599055D01*
X452198D01*
G01X456853Y1598845D02*
X456696Y1598950D01*
Y1599160D01*
X456853Y1599265D01*
X457010Y1599160D01*
Y1598950D01*
X456853Y1598845D01*
G01X463153Y1605355D02*
X462526Y1605145D01*
X462056Y1604620D01*
X461743Y1603990D01*
X461508Y1603150D01*
X461430Y1602205D01*
X461508Y1601260D01*
X461743Y1600420D01*
X462056Y1599790D01*
X462526Y1599265D01*
X463153Y1599055D01*
X463780Y1599265D01*
X464250Y1599790D01*
X464563Y1600420D01*
X464798Y1601260D01*
X464876Y1602205D01*
X464798Y1603150D01*
X464563Y1603990D01*
X464250Y1604620D01*
X463780Y1605145D01*
X463153Y1605355D01*
G01X467730Y1600000D02*
X468200Y1599475D01*
X468748Y1599160D01*
X469453Y1599055D01*
X470158Y1599265D01*
X470706Y1599685D01*
X471098Y1600420D01*
X471176Y1601260D01*
X471020Y1602100D01*
X470628Y1602625D01*
X470080Y1603045D01*
X469531Y1603150D01*
X468983Y1603045D01*
X468278Y1602625D01*
X468513Y1605355D01*
X470628D01*
G01X425522Y1616594D02*
Y1622894D01*
X424582Y1621634D01*
G01Y1616594D02*
X426462D01*
G01X430334Y1619219D02*
X430882Y1619954D01*
X431352Y1620374D01*
X431979Y1620584D01*
X432527Y1620374D01*
X432919Y1619954D01*
X433232Y1619324D01*
X433310Y1618589D01*
X433232Y1617959D01*
X432919Y1617329D01*
X432449Y1616804D01*
X431900Y1616594D01*
X431274Y1616804D01*
X430725Y1617434D01*
X430412Y1618379D01*
X430334Y1619429D01*
X430490Y1620794D01*
X430725Y1621529D01*
X431117Y1622264D01*
X431665Y1622789D01*
X432214Y1622894D01*
X432762Y1622684D01*
X433154Y1622159D01*
G01X438122Y1622894D02*
X437495Y1622684D01*
X437025Y1622159D01*
X436712Y1621529D01*
X436477Y1620689D01*
X436399Y1619744D01*
X436477Y1618799D01*
X436712Y1617959D01*
X437025Y1617329D01*
X437495Y1616804D01*
X438122Y1616594D01*
X438749Y1616804D01*
X439219Y1617329D01*
X439532Y1617959D01*
X439767Y1618799D01*
X439845Y1619744D01*
X439767Y1620689D01*
X439532Y1621529D01*
X439219Y1622159D01*
X438749Y1622684D01*
X438122Y1622894D01*
G01X444265Y1616594D02*
X444422Y1617959D01*
X444657Y1619114D01*
X444970Y1620164D01*
X445362Y1621319D01*
X445989Y1622894D01*
X442855D01*
G01X448999Y1617539D02*
X449469Y1617014D01*
X450017Y1616699D01*
X450722Y1616594D01*
X451427Y1616804D01*
X451975Y1617224D01*
X452367Y1617959D01*
X452445Y1618799D01*
X452289Y1619639D01*
X451897Y1620164D01*
X451349Y1620584D01*
X450800Y1620689D01*
X450252Y1620584D01*
X449547Y1620164D01*
X449782Y1622894D01*
X451897D01*
G01X457022Y1616384D02*
X456865Y1616489D01*
Y1616699D01*
X457022Y1616804D01*
X457179Y1616699D01*
Y1616489D01*
X457022Y1616384D01*
G01X461834Y1621844D02*
X462304Y1622474D01*
X462852Y1622789D01*
X463479Y1622894D01*
X464262Y1622684D01*
X464810Y1622159D01*
X464967Y1621529D01*
X464889Y1620899D01*
X464575Y1620374D01*
X463009Y1619324D01*
X462304Y1618589D01*
X461834Y1617539D01*
X461677Y1616594D01*
X464967D01*
G01X469622Y1622894D02*
X468995Y1622684D01*
X468525Y1622159D01*
X468212Y1621529D01*
X467977Y1620689D01*
X467899Y1619744D01*
X467977Y1618799D01*
X468212Y1617959D01*
X468525Y1617329D01*
X468995Y1616804D01*
X469622Y1616594D01*
X470249Y1616804D01*
X470719Y1617329D01*
X471032Y1617959D01*
X471267Y1618799D01*
X471345Y1619744D01*
X471267Y1620689D01*
X471032Y1621529D01*
X470719Y1622159D01*
X470249Y1622684D01*
X469622Y1622894D01*
G01X435139Y1792770D02*
Y1799070D01*
X434199Y1797810D01*
G01Y1792770D02*
X436079D01*
G01X441282D02*
X441439Y1794135D01*
X441674Y1795290D01*
X441987Y1796340D01*
X442379Y1797495D01*
X443006Y1799070D01*
X439872D01*
G01X447739Y1792770D02*
X448287Y1792875D01*
X448914Y1793190D01*
X449306Y1793715D01*
X449462Y1794450D01*
X449306Y1795185D01*
X448836Y1795815D01*
X448131Y1796130D01*
X447347D01*
X446877Y1796340D01*
X446486Y1796865D01*
X446329Y1797600D01*
X446564Y1798335D01*
X447112Y1798860D01*
X447739Y1799070D01*
X448366Y1798860D01*
X448914Y1798335D01*
X449149Y1797600D01*
X448992Y1796865D01*
X448601Y1796340D01*
X448131Y1796130D01*
X447347D01*
X446642Y1795815D01*
X446172Y1795185D01*
X446016Y1794450D01*
X446172Y1793715D01*
X446564Y1793190D01*
X447191Y1792875D01*
X447739Y1792770D01*
G01X452551Y1798020D02*
X453021Y1798650D01*
X453569Y1798965D01*
X454196Y1799070D01*
X454979Y1798860D01*
X455527Y1798335D01*
X455684Y1797705D01*
X455606Y1797075D01*
X455292Y1796550D01*
X453726Y1795500D01*
X453021Y1794765D01*
X452551Y1793715D01*
X452394Y1792770D01*
X455684D01*
G01X458616Y1793715D02*
X459086Y1793190D01*
X459634Y1792875D01*
X460339Y1792770D01*
X461044Y1792980D01*
X461592Y1793400D01*
X461984Y1794135D01*
X462062Y1794975D01*
X461906Y1795815D01*
X461514Y1796340D01*
X460966Y1796760D01*
X460417Y1796865D01*
X459869Y1796760D01*
X459164Y1796340D01*
X459399Y1799070D01*
X461514D01*
G01X466639Y1792560D02*
X466482Y1792665D01*
Y1792875D01*
X466639Y1792980D01*
X466796Y1792875D01*
Y1792665D01*
X466639Y1792560D01*
G01X471451Y1798020D02*
X471921Y1798650D01*
X472469Y1798965D01*
X473096Y1799070D01*
X473879Y1798860D01*
X474427Y1798335D01*
X474584Y1797705D01*
X474506Y1797075D01*
X474192Y1796550D01*
X472626Y1795500D01*
X471921Y1794765D01*
X471451Y1793715D01*
X471294Y1792770D01*
X474584D01*
G01X479239Y1799070D02*
X478612Y1798860D01*
X478142Y1798335D01*
X477829Y1797705D01*
X477594Y1796865D01*
X477516Y1795920D01*
X477594Y1794975D01*
X477829Y1794135D01*
X478142Y1793505D01*
X478612Y1792980D01*
X479239Y1792770D01*
X479866Y1792980D01*
X480336Y1793505D01*
X480649Y1794135D01*
X480884Y1794975D01*
X480962Y1795920D01*
X480884Y1796865D01*
X480649Y1797705D01*
X480336Y1798335D01*
X479866Y1798860D01*
X479239Y1799070D01*
G01X437497Y1949055D02*
Y1955355D01*
X436557Y1954095D01*
G01Y1949055D02*
X438437D01*
G01X442465Y1949790D02*
X443014Y1949265D01*
X443640Y1949055D01*
X444267Y1949265D01*
X444815Y1949895D01*
X445207Y1950840D01*
X445364Y1951785D01*
Y1952940D01*
X445207Y1953885D01*
X444815Y1954725D01*
X444345Y1955145D01*
X443797Y1955355D01*
X443170Y1955145D01*
X442700Y1954725D01*
X442387Y1954095D01*
X442230Y1953255D01*
X442387Y1952520D01*
X442779Y1951785D01*
X443249Y1951365D01*
X443797Y1951260D01*
X444424Y1951470D01*
X444894Y1951995D01*
X445364Y1952940D01*
G01X448374Y1950000D02*
X448844Y1949475D01*
X449392Y1949160D01*
X450097Y1949055D01*
X450802Y1949265D01*
X451350Y1949685D01*
X451742Y1950420D01*
X451820Y1951260D01*
X451664Y1952100D01*
X451272Y1952625D01*
X450724Y1953045D01*
X450175Y1953150D01*
X449627Y1953045D01*
X448922Y1952625D01*
X449157Y1955355D01*
X451272D01*
G01X454909Y1954305D02*
X455379Y1954935D01*
X455927Y1955250D01*
X456554Y1955355D01*
X457337Y1955145D01*
X457885Y1954620D01*
X458042Y1953990D01*
X457964Y1953360D01*
X457650Y1952835D01*
X456084Y1951785D01*
X455379Y1951050D01*
X454909Y1950000D01*
X454752Y1949055D01*
X458042D01*
G01X461209Y1954305D02*
X461679Y1954935D01*
X462227Y1955250D01*
X462854Y1955355D01*
X463637Y1955145D01*
X464185Y1954620D01*
X464342Y1953990D01*
X464264Y1953360D01*
X463950Y1952835D01*
X462384Y1951785D01*
X461679Y1951050D01*
X461209Y1950000D01*
X461052Y1949055D01*
X464342D01*
G01X468997Y1948845D02*
X468840Y1948950D01*
Y1949160D01*
X468997Y1949265D01*
X469154Y1949160D01*
Y1948950D01*
X468997Y1948845D01*
G01X475297Y1955355D02*
X474670Y1955145D01*
X474200Y1954620D01*
X473887Y1953990D01*
X473652Y1953150D01*
X473574Y1952205D01*
X473652Y1951260D01*
X473887Y1950420D01*
X474200Y1949790D01*
X474670Y1949265D01*
X475297Y1949055D01*
X475924Y1949265D01*
X476394Y1949790D01*
X476707Y1950420D01*
X476942Y1951260D01*
X477020Y1952205D01*
X476942Y1953150D01*
X476707Y1953990D01*
X476394Y1954620D01*
X475924Y1955145D01*
X475297Y1955355D01*
G01X479874Y1950000D02*
X480344Y1949475D01*
X480892Y1949160D01*
X481597Y1949055D01*
X482302Y1949265D01*
X482850Y1949685D01*
X483242Y1950420D01*
X483320Y1951260D01*
X483164Y1952100D01*
X482772Y1952625D01*
X482224Y1953045D01*
X481675Y1953150D01*
X481127Y1953045D01*
X480422Y1952625D01*
X480657Y1955355D01*
X482772D01*
G01X433791Y1966918D02*
Y1973218D01*
X432851Y1971958D01*
G01Y1966918D02*
X434731D01*
G01X438759Y1967653D02*
X439308Y1967128D01*
X439934Y1966918D01*
X440561Y1967128D01*
X441109Y1967758D01*
X441501Y1968703D01*
X441658Y1969648D01*
Y1970803D01*
X441501Y1971748D01*
X441109Y1972588D01*
X440639Y1973008D01*
X440091Y1973218D01*
X439464Y1973008D01*
X438994Y1972588D01*
X438681Y1971958D01*
X438524Y1971118D01*
X438681Y1970383D01*
X439073Y1969648D01*
X439543Y1969228D01*
X440091Y1969123D01*
X440718Y1969333D01*
X441188Y1969858D01*
X441658Y1970803D01*
G01X444668Y1967863D02*
X445138Y1967338D01*
X445686Y1967023D01*
X446391Y1966918D01*
X447096Y1967128D01*
X447644Y1967548D01*
X448036Y1968283D01*
X448114Y1969123D01*
X447958Y1969963D01*
X447566Y1970488D01*
X447018Y1970908D01*
X446469Y1971013D01*
X445921Y1970908D01*
X445216Y1970488D01*
X445451Y1973218D01*
X447566D01*
G01X452534Y1966918D02*
X452691Y1968283D01*
X452926Y1969438D01*
X453239Y1970488D01*
X453631Y1971643D01*
X454258Y1973218D01*
X451124D01*
G01X457268Y1967863D02*
X457738Y1967338D01*
X458286Y1967023D01*
X458991Y1966918D01*
X459696Y1967128D01*
X460244Y1967548D01*
X460636Y1968283D01*
X460714Y1969123D01*
X460558Y1969963D01*
X460166Y1970488D01*
X459618Y1970908D01*
X459069Y1971013D01*
X458521Y1970908D01*
X457816Y1970488D01*
X458051Y1973218D01*
X460166D01*
G01X465291Y1966708D02*
X465134Y1966813D01*
Y1967023D01*
X465291Y1967128D01*
X465448Y1967023D01*
Y1966813D01*
X465291Y1966708D01*
G01X470103Y1972168D02*
X470573Y1972798D01*
X471121Y1973113D01*
X471748Y1973218D01*
X472531Y1973008D01*
X473079Y1972483D01*
X473236Y1971853D01*
X473158Y1971223D01*
X472844Y1970698D01*
X471278Y1969648D01*
X470573Y1968913D01*
X470103Y1967863D01*
X469946Y1966918D01*
X473236D01*
G01X477891Y1973218D02*
X477264Y1973008D01*
X476794Y1972483D01*
X476481Y1971853D01*
X476246Y1971013D01*
X476168Y1970068D01*
X476246Y1969123D01*
X476481Y1968283D01*
X476794Y1967653D01*
X477264Y1967128D01*
X477891Y1966918D01*
X478518Y1967128D01*
X478988Y1967653D01*
X479301Y1968283D01*
X479536Y1969123D01*
X479614Y1970068D01*
X479536Y1971013D01*
X479301Y1971853D01*
X478988Y1972483D01*
X478518Y1973008D01*
X477891Y1973218D01*
G01X417905Y2108832D02*
X411605D01*
X416120Y2105934D01*
Y2109850D01*
G01X411605Y2114192D02*
X411815Y2113565D01*
X412340Y2113095D01*
X412970Y2112782D01*
X413810Y2112547D01*
X414755Y2112469D01*
X415700Y2112547D01*
X416540Y2112782D01*
X417170Y2113095D01*
X417695Y2113565D01*
X417905Y2114192D01*
X417695Y2114819D01*
X417170Y2115289D01*
X416540Y2115602D01*
X415700Y2115837D01*
X414755Y2115915D01*
X413810Y2115837D01*
X412970Y2115602D01*
X412340Y2115289D01*
X411815Y2114819D01*
X411605Y2114192D01*
G01X416960Y2118769D02*
X417485Y2119239D01*
X417800Y2119787D01*
X417905Y2120492D01*
X417695Y2121197D01*
X417275Y2121745D01*
X416540Y2122137D01*
X415700Y2122215D01*
X414860Y2122059D01*
X414335Y2121667D01*
X413915Y2121119D01*
X413810Y2120570D01*
X413915Y2120022D01*
X414335Y2119317D01*
X411605Y2119552D01*
Y2121667D01*
G01X416960Y2125069D02*
X417485Y2125539D01*
X417800Y2126087D01*
X417905Y2126792D01*
X417695Y2127497D01*
X417275Y2128045D01*
X416540Y2128437D01*
X415700Y2128515D01*
X414860Y2128359D01*
X414335Y2127967D01*
X413915Y2127419D01*
X413810Y2126870D01*
X413915Y2126322D01*
X414335Y2125617D01*
X411605Y2125852D01*
Y2127967D01*
G01X418115Y2133092D02*
X418010Y2132935D01*
X417800D01*
X417695Y2133092D01*
X417800Y2133249D01*
X418010D01*
X418115Y2133092D01*
G01X417905Y2139392D02*
X411605D01*
X412865Y2138452D01*
G01X417905D02*
Y2140332D01*
G01X412655Y2144204D02*
X412025Y2144674D01*
X411710Y2145222D01*
X411605Y2145849D01*
X411815Y2146632D01*
X412340Y2147180D01*
X412970Y2147337D01*
X413600Y2147259D01*
X414125Y2146945D01*
X415175Y2145379D01*
X415910Y2144674D01*
X416960Y2144204D01*
X417905Y2144047D01*
Y2147337D01*
G01X443000Y-130000D02*
X445500Y-122000D01*
X448000Y-130000D01*
G01X447100Y-127200D02*
X443900D01*
G01X442974Y75630D02*
X443131Y76995D01*
X443366Y78150D01*
X443679Y79200D01*
X444071Y80355D01*
X444698Y81930D01*
X441564D01*
G01X449431Y75630D02*
X449979Y75735D01*
X450606Y76050D01*
X450998Y76575D01*
X451154Y77310D01*
X450998Y78045D01*
X450528Y78675D01*
X449823Y78990D01*
X449039D01*
X448569Y79200D01*
X448178Y79725D01*
X448021Y80460D01*
X448256Y81195D01*
X448804Y81720D01*
X449431Y81930D01*
X450058Y81720D01*
X450606Y81195D01*
X450841Y80460D01*
X450684Y79725D01*
X450293Y79200D01*
X449823Y78990D01*
X449039D01*
X448334Y78675D01*
X447864Y78045D01*
X447708Y77310D01*
X447864Y76575D01*
X448256Y76050D01*
X448883Y75735D01*
X449431Y75630D01*
G01X455574D02*
X455731Y76995D01*
X455966Y78150D01*
X456279Y79200D01*
X456671Y80355D01*
X457298Y81930D01*
X454164D01*
G01X462031Y75420D02*
X461874Y75525D01*
Y75735D01*
X462031Y75840D01*
X462188Y75735D01*
Y75525D01*
X462031Y75420D01*
G01X468331Y75630D02*
X468879Y75735D01*
X469506Y76050D01*
X469898Y76575D01*
X470054Y77310D01*
X469898Y78045D01*
X469428Y78675D01*
X468723Y78990D01*
X467939D01*
X467469Y79200D01*
X467078Y79725D01*
X466921Y80460D01*
X467156Y81195D01*
X467704Y81720D01*
X468331Y81930D01*
X468958Y81720D01*
X469506Y81195D01*
X469741Y80460D01*
X469584Y79725D01*
X469193Y79200D01*
X468723Y78990D01*
X467939D01*
X467234Y78675D01*
X466764Y78045D01*
X466608Y77310D01*
X466764Y76575D01*
X467156Y76050D01*
X467783Y75735D01*
X468331Y75630D01*
G01X474631Y81930D02*
X474004Y81720D01*
X473534Y81195D01*
X473221Y80565D01*
X472986Y79725D01*
X472908Y78780D01*
X472986Y77835D01*
X473221Y76995D01*
X473534Y76365D01*
X474004Y75840D01*
X474631Y75630D01*
X475258Y75840D01*
X475728Y76365D01*
X476041Y76995D01*
X476276Y77835D01*
X476354Y78780D01*
X476276Y79725D01*
X476041Y80565D01*
X475728Y81195D01*
X475258Y81720D01*
X474631Y81930D01*
G01X443882Y255880D02*
X444352Y256510D01*
X444900Y256825D01*
X445527Y256930D01*
X446310Y256720D01*
X446858Y256195D01*
X447015Y255565D01*
X446937Y254935D01*
X446623Y254410D01*
X445057Y253360D01*
X444352Y252625D01*
X443882Y251575D01*
X443725Y250630D01*
X447015D01*
G01X449947Y251575D02*
X450417Y251050D01*
X450965Y250735D01*
X451670Y250630D01*
X452375Y250840D01*
X452923Y251260D01*
X453315Y251995D01*
X453393Y252835D01*
X453237Y253675D01*
X452845Y254200D01*
X452297Y254620D01*
X451748Y254725D01*
X451200Y254620D01*
X450495Y254200D01*
X450730Y256930D01*
X452845D01*
G01X456247Y251890D02*
X456717Y251155D01*
X457343Y250735D01*
X458048Y250630D01*
X458675Y250735D01*
X459302Y251260D01*
X459693Y251890D01*
X459772Y252520D01*
X459615Y253255D01*
X459067Y253780D01*
X458518Y253990D01*
X457813D01*
G01X458518D02*
X458988Y254305D01*
X459380Y254830D01*
X459537Y255460D01*
X459380Y256090D01*
X458988Y256615D01*
X458283Y256930D01*
X457578Y256825D01*
X456873Y256405D01*
G01X464113Y250630D02*
X464270Y251995D01*
X464505Y253150D01*
X464818Y254200D01*
X465210Y255355D01*
X465837Y256930D01*
X462703D01*
G01X470570Y250420D02*
X470413Y250525D01*
Y250735D01*
X470570Y250840D01*
X470727Y250735D01*
Y250525D01*
X470570Y250420D01*
G01X476870Y250630D02*
X477418Y250735D01*
X478045Y251050D01*
X478437Y251575D01*
X478593Y252310D01*
X478437Y253045D01*
X477967Y253675D01*
X477262Y253990D01*
X476478D01*
X476008Y254200D01*
X475617Y254725D01*
X475460Y255460D01*
X475695Y256195D01*
X476243Y256720D01*
X476870Y256930D01*
X477497Y256720D01*
X478045Y256195D01*
X478280Y255460D01*
X478123Y254725D01*
X477732Y254200D01*
X477262Y253990D01*
X476478D01*
X475773Y253675D01*
X475303Y253045D01*
X475147Y252310D01*
X475303Y251575D01*
X475695Y251050D01*
X476322Y250735D01*
X476870Y250630D01*
G01X483170Y256930D02*
X482543Y256720D01*
X482073Y256195D01*
X481760Y255565D01*
X481525Y254725D01*
X481447Y253780D01*
X481525Y252835D01*
X481760Y251995D01*
X482073Y251365D01*
X482543Y250840D01*
X483170Y250630D01*
X483797Y250840D01*
X484267Y251365D01*
X484580Y251995D01*
X484815Y252835D01*
X484893Y253780D01*
X484815Y254725D01*
X484580Y255565D01*
X484267Y256195D01*
X483797Y256720D01*
X483170Y256930D01*
G01X438932Y306378D02*
X439402Y305643D01*
X440028Y305223D01*
X440733Y305118D01*
X441360Y305223D01*
X441987Y305748D01*
X442378Y306378D01*
X442457Y307008D01*
X442300Y307743D01*
X441752Y308268D01*
X441203Y308478D01*
X440498D01*
G01X441203D02*
X441673Y308793D01*
X442065Y309318D01*
X442222Y309948D01*
X442065Y310578D01*
X441673Y311103D01*
X440968Y311418D01*
X440263Y311313D01*
X439558Y310893D01*
G01X446955Y311418D02*
X446328Y311208D01*
X445858Y310683D01*
X445545Y310053D01*
X445310Y309213D01*
X445232Y308268D01*
X445310Y307323D01*
X445545Y306483D01*
X445858Y305853D01*
X446328Y305328D01*
X446955Y305118D01*
X447582Y305328D01*
X448052Y305853D01*
X448365Y306483D01*
X448600Y307323D01*
X448678Y308268D01*
X448600Y309213D01*
X448365Y310053D01*
X448052Y310683D01*
X447582Y311208D01*
X446955Y311418D01*
G01X453255Y305118D02*
X453803Y305223D01*
X454430Y305538D01*
X454822Y306063D01*
X454978Y306798D01*
X454822Y307533D01*
X454352Y308163D01*
X453647Y308478D01*
X452863D01*
X452393Y308688D01*
X452002Y309213D01*
X451845Y309948D01*
X452080Y310683D01*
X452628Y311208D01*
X453255Y311418D01*
X453882Y311208D01*
X454430Y310683D01*
X454665Y309948D01*
X454508Y309213D01*
X454117Y308688D01*
X453647Y308478D01*
X452863D01*
X452158Y308163D01*
X451688Y307533D01*
X451532Y306798D01*
X451688Y306063D01*
X452080Y305538D01*
X452707Y305223D01*
X453255Y305118D01*
G01X458067Y310368D02*
X458537Y310998D01*
X459085Y311313D01*
X459712Y311418D01*
X460495Y311208D01*
X461043Y310683D01*
X461200Y310053D01*
X461122Y309423D01*
X460808Y308898D01*
X459242Y307848D01*
X458537Y307113D01*
X458067Y306063D01*
X457910Y305118D01*
X461200D01*
G01X465855Y304908D02*
X465698Y305013D01*
Y305223D01*
X465855Y305328D01*
X466012Y305223D01*
Y305013D01*
X465855Y304908D01*
G01X470667Y307743D02*
X471215Y308478D01*
X471685Y308898D01*
X472312Y309108D01*
X472860Y308898D01*
X473252Y308478D01*
X473565Y307848D01*
X473643Y307113D01*
X473565Y306483D01*
X473252Y305853D01*
X472782Y305328D01*
X472233Y305118D01*
X471607Y305328D01*
X471058Y305958D01*
X470745Y306903D01*
X470667Y307953D01*
X470823Y309318D01*
X471058Y310053D01*
X471450Y310788D01*
X471998Y311313D01*
X472547Y311418D01*
X473095Y311208D01*
X473487Y310683D01*
G01X478455Y305118D02*
X479003Y305223D01*
X479630Y305538D01*
X480022Y306063D01*
X480178Y306798D01*
X480022Y307533D01*
X479552Y308163D01*
X478847Y308478D01*
X478063D01*
X477593Y308688D01*
X477202Y309213D01*
X477045Y309948D01*
X477280Y310683D01*
X477828Y311208D01*
X478455Y311418D01*
X479082Y311208D01*
X479630Y310683D01*
X479865Y309948D01*
X479708Y309213D01*
X479317Y308688D01*
X478847Y308478D01*
X478063D01*
X477358Y308163D01*
X476888Y307533D01*
X476732Y306798D01*
X476888Y306063D01*
X477280Y305538D01*
X477907Y305223D01*
X478455Y305118D01*
G01X438978Y899790D02*
X439527Y899265D01*
X440153Y899055D01*
X440780Y899265D01*
X441328Y899895D01*
X441720Y900840D01*
X441877Y901785D01*
Y902940D01*
X441720Y903885D01*
X441328Y904725D01*
X440858Y905145D01*
X440310Y905355D01*
X439683Y905145D01*
X439213Y904725D01*
X438900Y904095D01*
X438743Y903255D01*
X438900Y902520D01*
X439292Y901785D01*
X439762Y901365D01*
X440310Y901260D01*
X440937Y901470D01*
X441407Y901995D01*
X441877Y902940D01*
G01X446610Y905355D02*
X445983Y905145D01*
X445513Y904620D01*
X445200Y903990D01*
X444965Y903150D01*
X444887Y902205D01*
X444965Y901260D01*
X445200Y900420D01*
X445513Y899790D01*
X445983Y899265D01*
X446610Y899055D01*
X447237Y899265D01*
X447707Y899790D01*
X448020Y900420D01*
X448255Y901260D01*
X448333Y902205D01*
X448255Y903150D01*
X448020Y903990D01*
X447707Y904620D01*
X447237Y905145D01*
X446610Y905355D01*
G01X451422Y904305D02*
X451892Y904935D01*
X452440Y905250D01*
X453067Y905355D01*
X453850Y905145D01*
X454398Y904620D01*
X454555Y903990D01*
X454477Y903360D01*
X454163Y902835D01*
X452597Y901785D01*
X451892Y901050D01*
X451422Y900000D01*
X451265Y899055D01*
X454555D01*
G01X457722Y904305D02*
X458192Y904935D01*
X458740Y905250D01*
X459367Y905355D01*
X460150Y905145D01*
X460698Y904620D01*
X460855Y903990D01*
X460777Y903360D01*
X460463Y902835D01*
X458897Y901785D01*
X458192Y901050D01*
X457722Y900000D01*
X457565Y899055D01*
X460855D01*
G01X465510Y898845D02*
X465353Y898950D01*
Y899160D01*
X465510Y899265D01*
X465667Y899160D01*
Y898950D01*
X465510Y898845D01*
G01X471810Y905355D02*
X471183Y905145D01*
X470713Y904620D01*
X470400Y903990D01*
X470165Y903150D01*
X470087Y902205D01*
X470165Y901260D01*
X470400Y900420D01*
X470713Y899790D01*
X471183Y899265D01*
X471810Y899055D01*
X472437Y899265D01*
X472907Y899790D01*
X473220Y900420D01*
X473455Y901260D01*
X473533Y902205D01*
X473455Y903150D01*
X473220Y903990D01*
X472907Y904620D01*
X472437Y905145D01*
X471810Y905355D01*
G01X476387Y900000D02*
X476857Y899475D01*
X477405Y899160D01*
X478110Y899055D01*
X478815Y899265D01*
X479363Y899685D01*
X479755Y900420D01*
X479833Y901260D01*
X479677Y902100D01*
X479285Y902625D01*
X478737Y903045D01*
X478188Y903150D01*
X477640Y903045D01*
X476935Y902625D01*
X477170Y905355D01*
X479285D01*
G01X442346Y918725D02*
X442895Y918200D01*
X443521Y917990D01*
X444148Y918200D01*
X444696Y918830D01*
X445088Y919775D01*
X445245Y920720D01*
Y921875D01*
X445088Y922820D01*
X444696Y923660D01*
X444226Y924080D01*
X443678Y924290D01*
X443051Y924080D01*
X442581Y923660D01*
X442268Y923030D01*
X442111Y922190D01*
X442268Y921455D01*
X442660Y920720D01*
X443130Y920300D01*
X443678Y920195D01*
X444305Y920405D01*
X444775Y920930D01*
X445245Y921875D01*
G01X449978Y924290D02*
X449351Y924080D01*
X448881Y923555D01*
X448568Y922925D01*
X448333Y922085D01*
X448255Y921140D01*
X448333Y920195D01*
X448568Y919355D01*
X448881Y918725D01*
X449351Y918200D01*
X449978Y917990D01*
X450605Y918200D01*
X451075Y918725D01*
X451388Y919355D01*
X451623Y920195D01*
X451701Y921140D01*
X451623Y922085D01*
X451388Y922925D01*
X451075Y923555D01*
X450605Y924080D01*
X449978Y924290D01*
G01X456121Y917990D02*
X456278Y919355D01*
X456513Y920510D01*
X456826Y921560D01*
X457218Y922715D01*
X457845Y924290D01*
X454711D01*
G01X460855Y918935D02*
X461325Y918410D01*
X461873Y918095D01*
X462578Y917990D01*
X463283Y918200D01*
X463831Y918620D01*
X464223Y919355D01*
X464301Y920195D01*
X464145Y921035D01*
X463753Y921560D01*
X463205Y921980D01*
X462656Y922085D01*
X462108Y921980D01*
X461403Y921560D01*
X461638Y924290D01*
X463753D01*
G01X468878Y917780D02*
X468721Y917885D01*
Y918095D01*
X468878Y918200D01*
X469035Y918095D01*
Y917885D01*
X468878Y917780D01*
G01X473690Y923240D02*
X474160Y923870D01*
X474708Y924185D01*
X475335Y924290D01*
X476118Y924080D01*
X476666Y923555D01*
X476823Y922925D01*
X476745Y922295D01*
X476431Y921770D01*
X474865Y920720D01*
X474160Y919985D01*
X473690Y918935D01*
X473533Y917990D01*
X476823D01*
G01X481478Y924290D02*
X480851Y924080D01*
X480381Y923555D01*
X480068Y922925D01*
X479833Y922085D01*
X479755Y921140D01*
X479833Y920195D01*
X480068Y919355D01*
X480381Y918725D01*
X480851Y918200D01*
X481478Y917990D01*
X482105Y918200D01*
X482575Y918725D01*
X482888Y919355D01*
X483123Y920195D01*
X483201Y921140D01*
X483123Y922085D01*
X482888Y922925D01*
X482575Y923555D01*
X482105Y924080D01*
X481478Y924290D01*
G01X451307Y1424055D02*
Y1430355D01*
X450367Y1429095D01*
G01Y1424055D02*
X452247D01*
G01X458547D02*
Y1430355D01*
X455649Y1425840D01*
X459565D01*
G01X462419Y1429305D02*
X462889Y1429935D01*
X463437Y1430250D01*
X464064Y1430355D01*
X464847Y1430145D01*
X465395Y1429620D01*
X465552Y1428990D01*
X465474Y1428360D01*
X465160Y1427835D01*
X463594Y1426785D01*
X462889Y1426050D01*
X462419Y1425000D01*
X462262Y1424055D01*
X465552D01*
G01X470050D02*
X470207Y1425420D01*
X470442Y1426575D01*
X470755Y1427625D01*
X471147Y1428780D01*
X471774Y1430355D01*
X468640D01*
G01X475019Y1429305D02*
X475489Y1429935D01*
X476037Y1430250D01*
X476664Y1430355D01*
X477447Y1430145D01*
X477995Y1429620D01*
X478152Y1428990D01*
X478074Y1428360D01*
X477760Y1427835D01*
X476194Y1426785D01*
X475489Y1426050D01*
X475019Y1425000D01*
X474862Y1424055D01*
X478152D01*
G01X482807Y1423845D02*
X482650Y1423950D01*
Y1424160D01*
X482807Y1424265D01*
X482964Y1424160D01*
Y1423950D01*
X482807Y1423845D01*
G01X489107Y1430355D02*
X488480Y1430145D01*
X488010Y1429620D01*
X487697Y1428990D01*
X487462Y1428150D01*
X487384Y1427205D01*
X487462Y1426260D01*
X487697Y1425420D01*
X488010Y1424790D01*
X488480Y1424265D01*
X489107Y1424055D01*
X489734Y1424265D01*
X490204Y1424790D01*
X490517Y1425420D01*
X490752Y1426260D01*
X490830Y1427205D01*
X490752Y1428150D01*
X490517Y1428990D01*
X490204Y1429620D01*
X489734Y1430145D01*
X489107Y1430355D01*
G01X493684Y1425000D02*
X494154Y1424475D01*
X494702Y1424160D01*
X495407Y1424055D01*
X496112Y1424265D01*
X496660Y1424685D01*
X497052Y1425420D01*
X497130Y1426260D01*
X496974Y1427100D01*
X496582Y1427625D01*
X496034Y1428045D01*
X495485Y1428150D01*
X494937Y1428045D01*
X494232Y1427625D01*
X494467Y1430355D01*
X496582D01*
G01X440865Y1439085D02*
Y1445385D01*
X439925Y1444125D01*
G01Y1439085D02*
X441805D01*
G01X448105D02*
Y1445385D01*
X445207Y1440870D01*
X449123D01*
G01X451742Y1440345D02*
X452212Y1439610D01*
X452838Y1439190D01*
X453543Y1439085D01*
X454170Y1439190D01*
X454797Y1439715D01*
X455188Y1440345D01*
X455267Y1440975D01*
X455110Y1441710D01*
X454562Y1442235D01*
X454013Y1442445D01*
X453308D01*
G01X454013D02*
X454483Y1442760D01*
X454875Y1443285D01*
X455032Y1443915D01*
X454875Y1444545D01*
X454483Y1445070D01*
X453778Y1445385D01*
X453073Y1445280D01*
X452368Y1444860D01*
G01X458277Y1444335D02*
X458747Y1444965D01*
X459295Y1445280D01*
X459922Y1445385D01*
X460705Y1445175D01*
X461253Y1444650D01*
X461410Y1444020D01*
X461332Y1443390D01*
X461018Y1442865D01*
X459452Y1441815D01*
X458747Y1441080D01*
X458277Y1440030D01*
X458120Y1439085D01*
X461410D01*
G01X464342Y1440030D02*
X464812Y1439505D01*
X465360Y1439190D01*
X466065Y1439085D01*
X466770Y1439295D01*
X467318Y1439715D01*
X467710Y1440450D01*
X467788Y1441290D01*
X467632Y1442130D01*
X467240Y1442655D01*
X466692Y1443075D01*
X466143Y1443180D01*
X465595Y1443075D01*
X464890Y1442655D01*
X465125Y1445385D01*
X467240D01*
G01X472365Y1438875D02*
X472208Y1438980D01*
Y1439190D01*
X472365Y1439295D01*
X472522Y1439190D01*
Y1438980D01*
X472365Y1438875D01*
G01X477177Y1444335D02*
X477647Y1444965D01*
X478195Y1445280D01*
X478822Y1445385D01*
X479605Y1445175D01*
X480153Y1444650D01*
X480310Y1444020D01*
X480232Y1443390D01*
X479918Y1442865D01*
X478352Y1441815D01*
X477647Y1441080D01*
X477177Y1440030D01*
X477020Y1439085D01*
X480310D01*
G01X484965Y1445385D02*
X484338Y1445175D01*
X483868Y1444650D01*
X483555Y1444020D01*
X483320Y1443180D01*
X483242Y1442235D01*
X483320Y1441290D01*
X483555Y1440450D01*
X483868Y1439820D01*
X484338Y1439295D01*
X484965Y1439085D01*
X485592Y1439295D01*
X486062Y1439820D01*
X486375Y1440450D01*
X486610Y1441290D01*
X486688Y1442235D01*
X486610Y1443180D01*
X486375Y1444020D01*
X486062Y1444650D01*
X485592Y1445175D01*
X484965Y1445385D01*
G01X452655Y1774055D02*
Y1780355D01*
X451715Y1779095D01*
G01Y1774055D02*
X453595D01*
G01X458798D02*
X458955Y1775420D01*
X459190Y1776575D01*
X459503Y1777625D01*
X459895Y1778780D01*
X460522Y1780355D01*
X457388D01*
G01X465098Y1774055D02*
X465255Y1775420D01*
X465490Y1776575D01*
X465803Y1777625D01*
X466195Y1778780D01*
X466822Y1780355D01*
X463688D01*
G01X471398Y1774055D02*
X471555Y1775420D01*
X471790Y1776575D01*
X472103Y1777625D01*
X472495Y1778780D01*
X473122Y1780355D01*
X469988D01*
G01X476367Y1779305D02*
X476837Y1779935D01*
X477385Y1780250D01*
X478012Y1780355D01*
X478795Y1780145D01*
X479343Y1779620D01*
X479500Y1778990D01*
X479422Y1778360D01*
X479108Y1777835D01*
X477542Y1776785D01*
X476837Y1776050D01*
X476367Y1775000D01*
X476210Y1774055D01*
X479500D01*
G01X484155Y1773845D02*
X483998Y1773950D01*
Y1774160D01*
X484155Y1774265D01*
X484312Y1774160D01*
Y1773950D01*
X484155Y1773845D01*
G01X490455Y1780355D02*
X489828Y1780145D01*
X489358Y1779620D01*
X489045Y1778990D01*
X488810Y1778150D01*
X488732Y1777205D01*
X488810Y1776260D01*
X489045Y1775420D01*
X489358Y1774790D01*
X489828Y1774265D01*
X490455Y1774055D01*
X491082Y1774265D01*
X491552Y1774790D01*
X491865Y1775420D01*
X492100Y1776260D01*
X492178Y1777205D01*
X492100Y1778150D01*
X491865Y1778990D01*
X491552Y1779620D01*
X491082Y1780145D01*
X490455Y1780355D01*
G01X495032Y1775000D02*
X495502Y1774475D01*
X496050Y1774160D01*
X496755Y1774055D01*
X497460Y1774265D01*
X498008Y1774685D01*
X498400Y1775420D01*
X498478Y1776260D01*
X498322Y1777100D01*
X497930Y1777625D01*
X497382Y1778045D01*
X496833Y1778150D01*
X496285Y1778045D01*
X495580Y1777625D01*
X495815Y1780355D01*
X497930D01*
G01X459258Y2045603D02*
X459728Y2046233D01*
X460276Y2046548D01*
X460903Y2046653D01*
X461686Y2046443D01*
X462234Y2045918D01*
X462391Y2045288D01*
X462313Y2044658D01*
X461999Y2044133D01*
X460433Y2043083D01*
X459728Y2042348D01*
X459258Y2041298D01*
X459101Y2040353D01*
X462391D01*
G01X467046Y2046653D02*
X466419Y2046443D01*
X465949Y2045918D01*
X465636Y2045288D01*
X465401Y2044448D01*
X465323Y2043503D01*
X465401Y2042558D01*
X465636Y2041718D01*
X465949Y2041088D01*
X466419Y2040563D01*
X467046Y2040353D01*
X467673Y2040563D01*
X468143Y2041088D01*
X468456Y2041718D01*
X468691Y2042558D01*
X468769Y2043503D01*
X468691Y2044448D01*
X468456Y2045288D01*
X468143Y2045918D01*
X467673Y2046443D01*
X467046Y2046653D01*
G01X474286Y2040353D02*
Y2046653D01*
X471388Y2042138D01*
X475304D01*
G01X477923Y2041613D02*
X478393Y2040878D01*
X479019Y2040458D01*
X479724Y2040353D01*
X480351Y2040458D01*
X480978Y2040983D01*
X481369Y2041613D01*
X481448Y2042243D01*
X481291Y2042978D01*
X480743Y2043503D01*
X480194Y2043713D01*
X479489D01*
G01X480194D02*
X480664Y2044028D01*
X481056Y2044553D01*
X481213Y2045183D01*
X481056Y2045813D01*
X480664Y2046338D01*
X479959Y2046653D01*
X479254Y2046548D01*
X478549Y2046128D01*
G01X484223Y2041298D02*
X484693Y2040773D01*
X485241Y2040458D01*
X485946Y2040353D01*
X486651Y2040563D01*
X487199Y2040983D01*
X487591Y2041718D01*
X487669Y2042558D01*
X487513Y2043398D01*
X487121Y2043923D01*
X486573Y2044343D01*
X486024Y2044448D01*
X485476Y2044343D01*
X484771Y2043923D01*
X485006Y2046653D01*
X487121D01*
G01X492246Y2040143D02*
X492089Y2040248D01*
Y2040458D01*
X492246Y2040563D01*
X492403Y2040458D01*
Y2040248D01*
X492246Y2040143D01*
G01X498546Y2046653D02*
X497919Y2046443D01*
X497449Y2045918D01*
X497136Y2045288D01*
X496901Y2044448D01*
X496823Y2043503D01*
X496901Y2042558D01*
X497136Y2041718D01*
X497449Y2041088D01*
X497919Y2040563D01*
X498546Y2040353D01*
X499173Y2040563D01*
X499643Y2041088D01*
X499956Y2041718D01*
X500191Y2042558D01*
X500269Y2043503D01*
X500191Y2044448D01*
X499956Y2045288D01*
X499643Y2045918D01*
X499173Y2046443D01*
X498546Y2046653D01*
G01X503123Y2041613D02*
X503593Y2040878D01*
X504219Y2040458D01*
X504924Y2040353D01*
X505551Y2040458D01*
X506178Y2040983D01*
X506569Y2041613D01*
X506648Y2042243D01*
X506491Y2042978D01*
X505943Y2043503D01*
X505394Y2043713D01*
X504689D01*
G01X505394D02*
X505864Y2044028D01*
X506256Y2044553D01*
X506413Y2045183D01*
X506256Y2045813D01*
X505864Y2046338D01*
X505159Y2046653D01*
X504454Y2046548D01*
X503749Y2046128D01*
G01X473000Y-130000D02*
Y-122000D01*
X471800Y-123600D01*
G01Y-130000D02*
X474200D01*
G01X479100Y-126667D02*
X479800Y-125733D01*
X480400Y-125200D01*
X481200Y-124933D01*
X481900Y-125200D01*
X482400Y-125733D01*
X482800Y-126533D01*
X482900Y-127467D01*
X482800Y-128267D01*
X482400Y-129067D01*
X481800Y-129733D01*
X481100Y-130000D01*
X480300Y-129733D01*
X479600Y-128934D01*
X479200Y-127733D01*
X479100Y-126400D01*
X479300Y-124667D01*
X479600Y-123733D01*
X480100Y-122800D01*
X480800Y-122133D01*
X481500Y-122000D01*
X482200Y-122267D01*
X482700Y-122933D01*
G01X463434Y1249055D02*
Y1255355D01*
X462494Y1254095D01*
G01Y1249055D02*
X464374D01*
G01X468246Y1254305D02*
X468716Y1254935D01*
X469264Y1255250D01*
X469891Y1255355D01*
X470674Y1255145D01*
X471222Y1254620D01*
X471379Y1253990D01*
X471301Y1253360D01*
X470987Y1252835D01*
X469421Y1251785D01*
X468716Y1251050D01*
X468246Y1250000D01*
X468089Y1249055D01*
X471379D01*
G01X474311Y1250000D02*
X474781Y1249475D01*
X475329Y1249160D01*
X476034Y1249055D01*
X476739Y1249265D01*
X477287Y1249685D01*
X477679Y1250420D01*
X477757Y1251260D01*
X477601Y1252100D01*
X477209Y1252625D01*
X476661Y1253045D01*
X476112Y1253150D01*
X475564Y1253045D01*
X474859Y1252625D01*
X475094Y1255355D01*
X477209D01*
G01X480846Y1254305D02*
X481316Y1254935D01*
X481864Y1255250D01*
X482491Y1255355D01*
X483274Y1255145D01*
X483822Y1254620D01*
X483979Y1253990D01*
X483901Y1253360D01*
X483587Y1252835D01*
X482021Y1251785D01*
X481316Y1251050D01*
X480846Y1250000D01*
X480689Y1249055D01*
X483979D01*
G01X487146Y1254305D02*
X487616Y1254935D01*
X488164Y1255250D01*
X488791Y1255355D01*
X489574Y1255145D01*
X490122Y1254620D01*
X490279Y1253990D01*
X490201Y1253360D01*
X489887Y1252835D01*
X488321Y1251785D01*
X487616Y1251050D01*
X487146Y1250000D01*
X486989Y1249055D01*
X490279D01*
G01X494934Y1248845D02*
X494777Y1248950D01*
Y1249160D01*
X494934Y1249265D01*
X495091Y1249160D01*
Y1248950D01*
X494934Y1248845D01*
G01X501234Y1255355D02*
X500607Y1255145D01*
X500137Y1254620D01*
X499824Y1253990D01*
X499589Y1253150D01*
X499511Y1252205D01*
X499589Y1251260D01*
X499824Y1250420D01*
X500137Y1249790D01*
X500607Y1249265D01*
X501234Y1249055D01*
X501861Y1249265D01*
X502331Y1249790D01*
X502644Y1250420D01*
X502879Y1251260D01*
X502957Y1252205D01*
X502879Y1253150D01*
X502644Y1253990D01*
X502331Y1254620D01*
X501861Y1255145D01*
X501234Y1255355D01*
G01X505811Y1250000D02*
X506281Y1249475D01*
X506829Y1249160D01*
X507534Y1249055D01*
X508239Y1249265D01*
X508787Y1249685D01*
X509179Y1250420D01*
X509257Y1251260D01*
X509101Y1252100D01*
X508709Y1252625D01*
X508161Y1253045D01*
X507612Y1253150D01*
X507064Y1253045D01*
X506359Y1252625D01*
X506594Y1255355D01*
X508709D01*
G01X469497Y1269316D02*
Y1275616D01*
X468557Y1274356D01*
G01Y1269316D02*
X470437D01*
G01X474309Y1274566D02*
X474779Y1275196D01*
X475327Y1275511D01*
X475954Y1275616D01*
X476737Y1275406D01*
X477285Y1274881D01*
X477442Y1274251D01*
X477364Y1273621D01*
X477050Y1273096D01*
X475484Y1272046D01*
X474779Y1271311D01*
X474309Y1270261D01*
X474152Y1269316D01*
X477442D01*
G01X480374Y1270261D02*
X480844Y1269736D01*
X481392Y1269421D01*
X482097Y1269316D01*
X482802Y1269526D01*
X483350Y1269946D01*
X483742Y1270681D01*
X483820Y1271521D01*
X483664Y1272361D01*
X483272Y1272886D01*
X482724Y1273306D01*
X482175Y1273411D01*
X481627Y1273306D01*
X480922Y1272886D01*
X481157Y1275616D01*
X483272D01*
G01X488240Y1269316D02*
X488397Y1270681D01*
X488632Y1271836D01*
X488945Y1272886D01*
X489337Y1274041D01*
X489964Y1275616D01*
X486830D01*
G01X492974Y1270261D02*
X493444Y1269736D01*
X493992Y1269421D01*
X494697Y1269316D01*
X495402Y1269526D01*
X495950Y1269946D01*
X496342Y1270681D01*
X496420Y1271521D01*
X496264Y1272361D01*
X495872Y1272886D01*
X495324Y1273306D01*
X494775Y1273411D01*
X494227Y1273306D01*
X493522Y1272886D01*
X493757Y1275616D01*
X495872D01*
G01X500997Y1269106D02*
X500840Y1269211D01*
Y1269421D01*
X500997Y1269526D01*
X501154Y1269421D01*
Y1269211D01*
X500997Y1269106D01*
G01X505809Y1274566D02*
X506279Y1275196D01*
X506827Y1275511D01*
X507454Y1275616D01*
X508237Y1275406D01*
X508785Y1274881D01*
X508942Y1274251D01*
X508864Y1273621D01*
X508550Y1273096D01*
X506984Y1272046D01*
X506279Y1271311D01*
X505809Y1270261D01*
X505652Y1269316D01*
X508942D01*
G01X513597Y1275616D02*
X512970Y1275406D01*
X512500Y1274881D01*
X512187Y1274251D01*
X511952Y1273411D01*
X511874Y1272466D01*
X511952Y1271521D01*
X512187Y1270681D01*
X512500Y1270051D01*
X512970Y1269526D01*
X513597Y1269316D01*
X514224Y1269526D01*
X514694Y1270051D01*
X515007Y1270681D01*
X515242Y1271521D01*
X515320Y1272466D01*
X515242Y1273411D01*
X515007Y1274251D01*
X514694Y1274881D01*
X514224Y1275406D01*
X513597Y1275616D01*
G01X471721Y2005880D02*
X472191Y2006510D01*
X472739Y2006825D01*
X473366Y2006930D01*
X474149Y2006720D01*
X474697Y2006195D01*
X474854Y2005565D01*
X474776Y2004935D01*
X474462Y2004410D01*
X472896Y2003360D01*
X472191Y2002625D01*
X471721Y2001575D01*
X471564Y2000630D01*
X474854D01*
G01X479509Y2006930D02*
X478882Y2006720D01*
X478412Y2006195D01*
X478099Y2005565D01*
X477864Y2004725D01*
X477786Y2003780D01*
X477864Y2002835D01*
X478099Y2001995D01*
X478412Y2001365D01*
X478882Y2000840D01*
X479509Y2000630D01*
X480136Y2000840D01*
X480606Y2001365D01*
X480919Y2001995D01*
X481154Y2002835D01*
X481232Y2003780D01*
X481154Y2004725D01*
X480919Y2005565D01*
X480606Y2006195D01*
X480136Y2006720D01*
X479509Y2006930D01*
G01X485809D02*
X485182Y2006720D01*
X484712Y2006195D01*
X484399Y2005565D01*
X484164Y2004725D01*
X484086Y2003780D01*
X484164Y2002835D01*
X484399Y2001995D01*
X484712Y2001365D01*
X485182Y2000840D01*
X485809Y2000630D01*
X486436Y2000840D01*
X486906Y2001365D01*
X487219Y2001995D01*
X487454Y2002835D01*
X487532Y2003780D01*
X487454Y2004725D01*
X487219Y2005565D01*
X486906Y2006195D01*
X486436Y2006720D01*
X485809Y2006930D01*
G01X490386Y2001890D02*
X490856Y2001155D01*
X491482Y2000735D01*
X492187Y2000630D01*
X492814Y2000735D01*
X493441Y2001260D01*
X493832Y2001890D01*
X493911Y2002520D01*
X493754Y2003255D01*
X493206Y2003780D01*
X492657Y2003990D01*
X491952D01*
G01X492657D02*
X493127Y2004305D01*
X493519Y2004830D01*
X493676Y2005460D01*
X493519Y2006090D01*
X493127Y2006615D01*
X492422Y2006930D01*
X491717Y2006825D01*
X491012Y2006405D01*
G01X498252Y2000630D02*
X498409Y2001995D01*
X498644Y2003150D01*
X498957Y2004200D01*
X499349Y2005355D01*
X499976Y2006930D01*
X496842D01*
G01X504709Y2000420D02*
X504552Y2000525D01*
Y2000735D01*
X504709Y2000840D01*
X504866Y2000735D01*
Y2000525D01*
X504709Y2000420D01*
G01X511009Y2000630D02*
X511557Y2000735D01*
X512184Y2001050D01*
X512576Y2001575D01*
X512732Y2002310D01*
X512576Y2003045D01*
X512106Y2003675D01*
X511401Y2003990D01*
X510617D01*
X510147Y2004200D01*
X509756Y2004725D01*
X509599Y2005460D01*
X509834Y2006195D01*
X510382Y2006720D01*
X511009Y2006930D01*
X511636Y2006720D01*
X512184Y2006195D01*
X512419Y2005460D01*
X512262Y2004725D01*
X511871Y2004200D01*
X511401Y2003990D01*
X510617D01*
X509912Y2003675D01*
X509442Y2003045D01*
X509286Y2002310D01*
X509442Y2001575D01*
X509834Y2001050D01*
X510461Y2000735D01*
X511009Y2000630D01*
G01X517309Y2006930D02*
X516682Y2006720D01*
X516212Y2006195D01*
X515899Y2005565D01*
X515664Y2004725D01*
X515586Y2003780D01*
X515664Y2002835D01*
X515899Y2001995D01*
X516212Y2001365D01*
X516682Y2000840D01*
X517309Y2000630D01*
X517936Y2000840D01*
X518406Y2001365D01*
X518719Y2001995D01*
X518954Y2002835D01*
X519032Y2003780D01*
X518954Y2004725D01*
X518719Y2005565D01*
X518406Y2006195D01*
X517936Y2006720D01*
X517309Y2006930D01*
G01X499484Y1125629D02*
Y1131929D01*
X498544Y1130669D01*
G01Y1125629D02*
X500424D01*
G01X505784D02*
Y1131929D01*
X504844Y1130669D01*
G01Y1125629D02*
X506724D01*
G01X510596Y1130879D02*
X511066Y1131509D01*
X511614Y1131824D01*
X512241Y1131929D01*
X513024Y1131719D01*
X513572Y1131194D01*
X513729Y1130564D01*
X513651Y1129934D01*
X513337Y1129409D01*
X511771Y1128359D01*
X511066Y1127624D01*
X510596Y1126574D01*
X510439Y1125629D01*
X513729D01*
G01X518384D02*
X518932Y1125734D01*
X519559Y1126049D01*
X519951Y1126574D01*
X520107Y1127309D01*
X519951Y1128044D01*
X519481Y1128674D01*
X518776Y1128989D01*
X517992D01*
X517522Y1129199D01*
X517131Y1129724D01*
X516974Y1130459D01*
X517209Y1131194D01*
X517757Y1131719D01*
X518384Y1131929D01*
X519011Y1131719D01*
X519559Y1131194D01*
X519794Y1130459D01*
X519637Y1129724D01*
X519246Y1129199D01*
X518776Y1128989D01*
X517992D01*
X517287Y1128674D01*
X516817Y1128044D01*
X516661Y1127309D01*
X516817Y1126574D01*
X517209Y1126049D01*
X517836Y1125734D01*
X518384Y1125629D01*
G01X524527D02*
X524684Y1126994D01*
X524919Y1128149D01*
X525232Y1129199D01*
X525624Y1130354D01*
X526251Y1131929D01*
X523117D01*
G01X530984Y1125419D02*
X530827Y1125524D01*
Y1125734D01*
X530984Y1125839D01*
X531141Y1125734D01*
Y1125524D01*
X530984Y1125419D01*
G01X537127Y1125629D02*
X537284Y1126994D01*
X537519Y1128149D01*
X537832Y1129199D01*
X538224Y1130354D01*
X538851Y1131929D01*
X535717D01*
G01X542252Y1126364D02*
X542801Y1125839D01*
X543427Y1125629D01*
X544054Y1125839D01*
X544602Y1126469D01*
X544994Y1127414D01*
X545151Y1128359D01*
Y1129514D01*
X544994Y1130459D01*
X544602Y1131299D01*
X544132Y1131719D01*
X543584Y1131929D01*
X542957Y1131719D01*
X542487Y1131299D01*
X542174Y1130669D01*
X542017Y1129829D01*
X542174Y1129094D01*
X542566Y1128359D01*
X543036Y1127939D01*
X543584Y1127834D01*
X544211Y1128044D01*
X544681Y1128569D01*
X545151Y1129514D01*
G01X498810Y1300630D02*
Y1306930D01*
X497870Y1305670D01*
G01Y1300630D02*
X499750D01*
G01X503387Y1301890D02*
X503857Y1301155D01*
X504483Y1300735D01*
X505188Y1300630D01*
X505815Y1300735D01*
X506442Y1301260D01*
X506833Y1301890D01*
X506912Y1302520D01*
X506755Y1303255D01*
X506207Y1303780D01*
X505658Y1303990D01*
X504953D01*
G01X505658D02*
X506128Y1304305D01*
X506520Y1304830D01*
X506677Y1305460D01*
X506520Y1306090D01*
X506128Y1306615D01*
X505423Y1306930D01*
X504718Y1306825D01*
X504013Y1306405D01*
G01X511410Y1306930D02*
X510783Y1306720D01*
X510313Y1306195D01*
X510000Y1305565D01*
X509765Y1304725D01*
X509687Y1303780D01*
X509765Y1302835D01*
X510000Y1301995D01*
X510313Y1301365D01*
X510783Y1300840D01*
X511410Y1300630D01*
X512037Y1300840D01*
X512507Y1301365D01*
X512820Y1301995D01*
X513055Y1302835D01*
X513133Y1303780D01*
X513055Y1304725D01*
X512820Y1305565D01*
X512507Y1306195D01*
X512037Y1306720D01*
X511410Y1306930D01*
G01X515987Y1301890D02*
X516457Y1301155D01*
X517083Y1300735D01*
X517788Y1300630D01*
X518415Y1300735D01*
X519042Y1301260D01*
X519433Y1301890D01*
X519512Y1302520D01*
X519355Y1303255D01*
X518807Y1303780D01*
X518258Y1303990D01*
X517553D01*
G01X518258D02*
X518728Y1304305D01*
X519120Y1304830D01*
X519277Y1305460D01*
X519120Y1306090D01*
X518728Y1306615D01*
X518023Y1306930D01*
X517318Y1306825D01*
X516613Y1306405D01*
G01X523853Y1300630D02*
X524010Y1301995D01*
X524245Y1303150D01*
X524558Y1304200D01*
X524950Y1305355D01*
X525577Y1306930D01*
X522443D01*
G01X530310Y1300420D02*
X530153Y1300525D01*
Y1300735D01*
X530310Y1300840D01*
X530467Y1300735D01*
Y1300525D01*
X530310Y1300420D01*
G01X536610Y1300630D02*
X537158Y1300735D01*
X537785Y1301050D01*
X538177Y1301575D01*
X538333Y1302310D01*
X538177Y1303045D01*
X537707Y1303675D01*
X537002Y1303990D01*
X536218D01*
X535748Y1304200D01*
X535357Y1304725D01*
X535200Y1305460D01*
X535435Y1306195D01*
X535983Y1306720D01*
X536610Y1306930D01*
X537237Y1306720D01*
X537785Y1306195D01*
X538020Y1305460D01*
X537863Y1304725D01*
X537472Y1304200D01*
X537002Y1303990D01*
X536218D01*
X535513Y1303675D01*
X535043Y1303045D01*
X534887Y1302310D01*
X535043Y1301575D01*
X535435Y1301050D01*
X536062Y1300735D01*
X536610Y1300630D01*
G01X542910Y1306930D02*
X542283Y1306720D01*
X541813Y1306195D01*
X541500Y1305565D01*
X541265Y1304725D01*
X541187Y1303780D01*
X541265Y1302835D01*
X541500Y1301995D01*
X541813Y1301365D01*
X542283Y1300840D01*
X542910Y1300630D01*
X543537Y1300840D01*
X544007Y1301365D01*
X544320Y1301995D01*
X544555Y1302835D01*
X544633Y1303780D01*
X544555Y1304725D01*
X544320Y1305565D01*
X544007Y1306195D01*
X543537Y1306720D01*
X542910Y1306930D01*
G01X493420Y1340354D02*
Y1346654D01*
X492480Y1345394D01*
G01Y1340354D02*
X494360D01*
G01X497997Y1341614D02*
X498467Y1340879D01*
X499093Y1340459D01*
X499798Y1340354D01*
X500425Y1340459D01*
X501052Y1340984D01*
X501443Y1341614D01*
X501522Y1342244D01*
X501365Y1342979D01*
X500817Y1343504D01*
X500268Y1343714D01*
X499563D01*
G01X500268D02*
X500738Y1344029D01*
X501130Y1344554D01*
X501287Y1345184D01*
X501130Y1345814D01*
X500738Y1346339D01*
X500033Y1346654D01*
X499328Y1346549D01*
X498623Y1346129D01*
G01X506960Y1340354D02*
Y1346654D01*
X504062Y1342139D01*
X507978D01*
G01X510597Y1341614D02*
X511067Y1340879D01*
X511693Y1340459D01*
X512398Y1340354D01*
X513025Y1340459D01*
X513652Y1340984D01*
X514043Y1341614D01*
X514122Y1342244D01*
X513965Y1342979D01*
X513417Y1343504D01*
X512868Y1343714D01*
X512163D01*
G01X512868D02*
X513338Y1344029D01*
X513730Y1344554D01*
X513887Y1345184D01*
X513730Y1345814D01*
X513338Y1346339D01*
X512633Y1346654D01*
X511928Y1346549D01*
X511223Y1346129D01*
G01X516897Y1341299D02*
X517367Y1340774D01*
X517915Y1340459D01*
X518620Y1340354D01*
X519325Y1340564D01*
X519873Y1340984D01*
X520265Y1341719D01*
X520343Y1342559D01*
X520187Y1343399D01*
X519795Y1343924D01*
X519247Y1344344D01*
X518698Y1344449D01*
X518150Y1344344D01*
X517445Y1343924D01*
X517680Y1346654D01*
X519795D01*
G01X524920Y1340144D02*
X524763Y1340249D01*
Y1340459D01*
X524920Y1340564D01*
X525077Y1340459D01*
Y1340249D01*
X524920Y1340144D01*
G01X531220Y1346654D02*
X530593Y1346444D01*
X530123Y1345919D01*
X529810Y1345289D01*
X529575Y1344449D01*
X529497Y1343504D01*
X529575Y1342559D01*
X529810Y1341719D01*
X530123Y1341089D01*
X530593Y1340564D01*
X531220Y1340354D01*
X531847Y1340564D01*
X532317Y1341089D01*
X532630Y1341719D01*
X532865Y1342559D01*
X532943Y1343504D01*
X532865Y1344449D01*
X532630Y1345289D01*
X532317Y1345919D01*
X531847Y1346444D01*
X531220Y1346654D01*
G01X538460Y1340354D02*
Y1346654D01*
X535562Y1342139D01*
X539478D01*
G01X501505Y1475630D02*
Y1481930D01*
X500565Y1480670D01*
G01Y1475630D02*
X502445D01*
G01X508745D02*
Y1481930D01*
X505847Y1477415D01*
X509763D01*
G01X513948Y1475630D02*
X514105Y1476995D01*
X514340Y1478150D01*
X514653Y1479200D01*
X515045Y1480355D01*
X515672Y1481930D01*
X512538D01*
G01X520405Y1475630D02*
X520953Y1475735D01*
X521580Y1476050D01*
X521972Y1476575D01*
X522128Y1477310D01*
X521972Y1478045D01*
X521502Y1478675D01*
X520797Y1478990D01*
X520013D01*
X519543Y1479200D01*
X519152Y1479725D01*
X518995Y1480460D01*
X519230Y1481195D01*
X519778Y1481720D01*
X520405Y1481930D01*
X521032Y1481720D01*
X521580Y1481195D01*
X521815Y1480460D01*
X521658Y1479725D01*
X521267Y1479200D01*
X520797Y1478990D01*
X520013D01*
X519308Y1478675D01*
X518838Y1478045D01*
X518682Y1477310D01*
X518838Y1476575D01*
X519230Y1476050D01*
X519857Y1475735D01*
X520405Y1475630D01*
G01X526548D02*
X526705Y1476995D01*
X526940Y1478150D01*
X527253Y1479200D01*
X527645Y1480355D01*
X528272Y1481930D01*
X525138D01*
G01X533005Y1475420D02*
X532848Y1475525D01*
Y1475735D01*
X533005Y1475840D01*
X533162Y1475735D01*
Y1475525D01*
X533005Y1475420D01*
G01X539305Y1475630D02*
X539853Y1475735D01*
X540480Y1476050D01*
X540872Y1476575D01*
X541028Y1477310D01*
X540872Y1478045D01*
X540402Y1478675D01*
X539697Y1478990D01*
X538913D01*
X538443Y1479200D01*
X538052Y1479725D01*
X537895Y1480460D01*
X538130Y1481195D01*
X538678Y1481720D01*
X539305Y1481930D01*
X539932Y1481720D01*
X540480Y1481195D01*
X540715Y1480460D01*
X540558Y1479725D01*
X540167Y1479200D01*
X539697Y1478990D01*
X538913D01*
X538208Y1478675D01*
X537738Y1478045D01*
X537582Y1477310D01*
X537738Y1476575D01*
X538130Y1476050D01*
X538757Y1475735D01*
X539305Y1475630D01*
G01X545605Y1481930D02*
X544978Y1481720D01*
X544508Y1481195D01*
X544195Y1480565D01*
X543960Y1479725D01*
X543882Y1478780D01*
X543960Y1477835D01*
X544195Y1476995D01*
X544508Y1476365D01*
X544978Y1475840D01*
X545605Y1475630D01*
X546232Y1475840D01*
X546702Y1476365D01*
X547015Y1476995D01*
X547250Y1477835D01*
X547328Y1478780D01*
X547250Y1479725D01*
X547015Y1480565D01*
X546702Y1481195D01*
X546232Y1481720D01*
X545605Y1481930D01*
G01X504873Y1650630D02*
Y1656930D01*
X503933Y1655670D01*
G01Y1650630D02*
X505813D01*
G01X509685Y1653255D02*
X510233Y1653990D01*
X510703Y1654410D01*
X511330Y1654620D01*
X511878Y1654410D01*
X512270Y1653990D01*
X512583Y1653360D01*
X512661Y1652625D01*
X512583Y1651995D01*
X512270Y1651365D01*
X511800Y1650840D01*
X511251Y1650630D01*
X510625Y1650840D01*
X510076Y1651470D01*
X509763Y1652415D01*
X509685Y1653465D01*
X509841Y1654830D01*
X510076Y1655565D01*
X510468Y1656300D01*
X511016Y1656825D01*
X511565Y1656930D01*
X512113Y1656720D01*
X512505Y1656195D01*
G01X515750Y1651575D02*
X516220Y1651050D01*
X516768Y1650735D01*
X517473Y1650630D01*
X518178Y1650840D01*
X518726Y1651260D01*
X519118Y1651995D01*
X519196Y1652835D01*
X519040Y1653675D01*
X518648Y1654200D01*
X518100Y1654620D01*
X517551Y1654725D01*
X517003Y1654620D01*
X516298Y1654200D01*
X516533Y1656930D01*
X518648D01*
G01X522050Y1651890D02*
X522520Y1651155D01*
X523146Y1650735D01*
X523851Y1650630D01*
X524478Y1650735D01*
X525105Y1651260D01*
X525496Y1651890D01*
X525575Y1652520D01*
X525418Y1653255D01*
X524870Y1653780D01*
X524321Y1653990D01*
X523616D01*
G01X524321D02*
X524791Y1654305D01*
X525183Y1654830D01*
X525340Y1655460D01*
X525183Y1656090D01*
X524791Y1656615D01*
X524086Y1656930D01*
X523381Y1656825D01*
X522676Y1656405D01*
G01X529916Y1650630D02*
X530073Y1651995D01*
X530308Y1653150D01*
X530621Y1654200D01*
X531013Y1655355D01*
X531640Y1656930D01*
X528506D01*
G01X536373Y1650420D02*
X536216Y1650525D01*
Y1650735D01*
X536373Y1650840D01*
X536530Y1650735D01*
Y1650525D01*
X536373Y1650420D01*
G01X542673Y1650630D02*
X543221Y1650735D01*
X543848Y1651050D01*
X544240Y1651575D01*
X544396Y1652310D01*
X544240Y1653045D01*
X543770Y1653675D01*
X543065Y1653990D01*
X542281D01*
X541811Y1654200D01*
X541420Y1654725D01*
X541263Y1655460D01*
X541498Y1656195D01*
X542046Y1656720D01*
X542673Y1656930D01*
X543300Y1656720D01*
X543848Y1656195D01*
X544083Y1655460D01*
X543926Y1654725D01*
X543535Y1654200D01*
X543065Y1653990D01*
X542281D01*
X541576Y1653675D01*
X541106Y1653045D01*
X540950Y1652310D01*
X541106Y1651575D01*
X541498Y1651050D01*
X542125Y1650735D01*
X542673Y1650630D01*
G01X548973Y1656930D02*
X548346Y1656720D01*
X547876Y1656195D01*
X547563Y1655565D01*
X547328Y1654725D01*
X547250Y1653780D01*
X547328Y1652835D01*
X547563Y1651995D01*
X547876Y1651365D01*
X548346Y1650840D01*
X548973Y1650630D01*
X549600Y1650840D01*
X550070Y1651365D01*
X550383Y1651995D01*
X550618Y1652835D01*
X550696Y1653780D01*
X550618Y1654725D01*
X550383Y1655565D01*
X550070Y1656195D01*
X549600Y1656720D01*
X548973Y1656930D01*
G01X506220Y1690354D02*
Y1696654D01*
X505280Y1695394D01*
G01Y1690354D02*
X507160D01*
G01X511032Y1692979D02*
X511580Y1693714D01*
X512050Y1694134D01*
X512677Y1694344D01*
X513225Y1694134D01*
X513617Y1693714D01*
X513930Y1693084D01*
X514008Y1692349D01*
X513930Y1691719D01*
X513617Y1691089D01*
X513147Y1690564D01*
X512598Y1690354D01*
X511972Y1690564D01*
X511423Y1691194D01*
X511110Y1692139D01*
X511032Y1693189D01*
X511188Y1694554D01*
X511423Y1695289D01*
X511815Y1696024D01*
X512363Y1696549D01*
X512912Y1696654D01*
X513460Y1696444D01*
X513852Y1695919D01*
G01X517488Y1691089D02*
X518037Y1690564D01*
X518663Y1690354D01*
X519290Y1690564D01*
X519838Y1691194D01*
X520230Y1692139D01*
X520387Y1693084D01*
Y1694239D01*
X520230Y1695184D01*
X519838Y1696024D01*
X519368Y1696444D01*
X518820Y1696654D01*
X518193Y1696444D01*
X517723Y1696024D01*
X517410Y1695394D01*
X517253Y1694554D01*
X517410Y1693819D01*
X517802Y1693084D01*
X518272Y1692664D01*
X518820Y1692559D01*
X519447Y1692769D01*
X519917Y1693294D01*
X520387Y1694239D01*
G01X523397Y1691614D02*
X523867Y1690879D01*
X524493Y1690459D01*
X525198Y1690354D01*
X525825Y1690459D01*
X526452Y1690984D01*
X526843Y1691614D01*
X526922Y1692244D01*
X526765Y1692979D01*
X526217Y1693504D01*
X525668Y1693714D01*
X524963D01*
G01X525668D02*
X526138Y1694029D01*
X526530Y1694554D01*
X526687Y1695184D01*
X526530Y1695814D01*
X526138Y1696339D01*
X525433Y1696654D01*
X524728Y1696549D01*
X524023Y1696129D01*
G01X529697Y1691299D02*
X530167Y1690774D01*
X530715Y1690459D01*
X531420Y1690354D01*
X532125Y1690564D01*
X532673Y1690984D01*
X533065Y1691719D01*
X533143Y1692559D01*
X532987Y1693399D01*
X532595Y1693924D01*
X532047Y1694344D01*
X531498Y1694449D01*
X530950Y1694344D01*
X530245Y1693924D01*
X530480Y1696654D01*
X532595D01*
G01X537720Y1690144D02*
X537563Y1690249D01*
Y1690459D01*
X537720Y1690564D01*
X537877Y1690459D01*
Y1690249D01*
X537720Y1690144D01*
G01X544020Y1696654D02*
X543393Y1696444D01*
X542923Y1695919D01*
X542610Y1695289D01*
X542375Y1694449D01*
X542297Y1693504D01*
X542375Y1692559D01*
X542610Y1691719D01*
X542923Y1691089D01*
X543393Y1690564D01*
X544020Y1690354D01*
X544647Y1690564D01*
X545117Y1691089D01*
X545430Y1691719D01*
X545665Y1692559D01*
X545743Y1693504D01*
X545665Y1694449D01*
X545430Y1695289D01*
X545117Y1695919D01*
X544647Y1696444D01*
X544020Y1696654D01*
G01X551260Y1690354D02*
Y1696654D01*
X548362Y1692139D01*
X552278D01*
G01X486346Y1825629D02*
Y1831929D01*
X485406Y1830669D01*
G01Y1825629D02*
X487286D01*
G01X492646D02*
X493194Y1825734D01*
X493821Y1826049D01*
X494213Y1826574D01*
X494369Y1827309D01*
X494213Y1828044D01*
X493743Y1828674D01*
X493038Y1828989D01*
X492254D01*
X491784Y1829199D01*
X491393Y1829724D01*
X491236Y1830459D01*
X491471Y1831194D01*
X492019Y1831719D01*
X492646Y1831929D01*
X493273Y1831719D01*
X493821Y1831194D01*
X494056Y1830459D01*
X493899Y1829724D01*
X493508Y1829199D01*
X493038Y1828989D01*
X492254D01*
X491549Y1828674D01*
X491079Y1828044D01*
X490923Y1827309D01*
X491079Y1826574D01*
X491471Y1826049D01*
X492098Y1825734D01*
X492646Y1825629D01*
G01X497458Y1830879D02*
X497928Y1831509D01*
X498476Y1831824D01*
X499103Y1831929D01*
X499886Y1831719D01*
X500434Y1831194D01*
X500591Y1830564D01*
X500513Y1829934D01*
X500199Y1829409D01*
X498633Y1828359D01*
X497928Y1827624D01*
X497458Y1826574D01*
X497301Y1825629D01*
X500591D01*
G01X505246D02*
X505794Y1825734D01*
X506421Y1826049D01*
X506813Y1826574D01*
X506969Y1827309D01*
X506813Y1828044D01*
X506343Y1828674D01*
X505638Y1828989D01*
X504854D01*
X504384Y1829199D01*
X503993Y1829724D01*
X503836Y1830459D01*
X504071Y1831194D01*
X504619Y1831719D01*
X505246Y1831929D01*
X505873Y1831719D01*
X506421Y1831194D01*
X506656Y1830459D01*
X506499Y1829724D01*
X506108Y1829199D01*
X505638Y1828989D01*
X504854D01*
X504149Y1828674D01*
X503679Y1828044D01*
X503523Y1827309D01*
X503679Y1826574D01*
X504071Y1826049D01*
X504698Y1825734D01*
X505246Y1825629D01*
G01X511389D02*
X511546Y1826994D01*
X511781Y1828149D01*
X512094Y1829199D01*
X512486Y1830354D01*
X513113Y1831929D01*
X509979D01*
G01X517846Y1825419D02*
X517689Y1825524D01*
Y1825734D01*
X517846Y1825839D01*
X518003Y1825734D01*
Y1825524D01*
X517846Y1825419D01*
G01X523989Y1825629D02*
X524146Y1826994D01*
X524381Y1828149D01*
X524694Y1829199D01*
X525086Y1830354D01*
X525713Y1831929D01*
X522579D01*
G01X529114Y1826364D02*
X529663Y1825839D01*
X530289Y1825629D01*
X530916Y1825839D01*
X531464Y1826469D01*
X531856Y1827414D01*
X532013Y1828359D01*
Y1829514D01*
X531856Y1830459D01*
X531464Y1831299D01*
X530994Y1831719D01*
X530446Y1831929D01*
X529819Y1831719D01*
X529349Y1831299D01*
X529036Y1830669D01*
X528879Y1829829D01*
X529036Y1829094D01*
X529428Y1828359D01*
X529898Y1827939D01*
X530446Y1827834D01*
X531073Y1828044D01*
X531543Y1828569D01*
X532013Y1829514D01*
G01X487693Y1879921D02*
Y1886221D01*
X486753Y1884961D01*
G01Y1879921D02*
X488633D01*
G01X493993D02*
X494541Y1880026D01*
X495168Y1880341D01*
X495560Y1880866D01*
X495716Y1881601D01*
X495560Y1882336D01*
X495090Y1882966D01*
X494385Y1883281D01*
X493601D01*
X493131Y1883491D01*
X492740Y1884016D01*
X492583Y1884751D01*
X492818Y1885486D01*
X493366Y1886011D01*
X493993Y1886221D01*
X494620Y1886011D01*
X495168Y1885486D01*
X495403Y1884751D01*
X495246Y1884016D01*
X494855Y1883491D01*
X494385Y1883281D01*
X493601D01*
X492896Y1882966D01*
X492426Y1882336D01*
X492270Y1881601D01*
X492426Y1880866D01*
X492818Y1880341D01*
X493445Y1880026D01*
X493993Y1879921D01*
G01X500293D02*
X500841Y1880026D01*
X501468Y1880341D01*
X501860Y1880866D01*
X502016Y1881601D01*
X501860Y1882336D01*
X501390Y1882966D01*
X500685Y1883281D01*
X499901D01*
X499431Y1883491D01*
X499040Y1884016D01*
X498883Y1884751D01*
X499118Y1885486D01*
X499666Y1886011D01*
X500293Y1886221D01*
X500920Y1886011D01*
X501468Y1885486D01*
X501703Y1884751D01*
X501546Y1884016D01*
X501155Y1883491D01*
X500685Y1883281D01*
X499901D01*
X499196Y1882966D01*
X498726Y1882336D01*
X498570Y1881601D01*
X498726Y1880866D01*
X499118Y1880341D01*
X499745Y1880026D01*
X500293Y1879921D01*
G01X504870Y1881181D02*
X505340Y1880446D01*
X505966Y1880026D01*
X506671Y1879921D01*
X507298Y1880026D01*
X507925Y1880551D01*
X508316Y1881181D01*
X508395Y1881811D01*
X508238Y1882546D01*
X507690Y1883071D01*
X507141Y1883281D01*
X506436D01*
G01X507141D02*
X507611Y1883596D01*
X508003Y1884121D01*
X508160Y1884751D01*
X508003Y1885381D01*
X507611Y1885906D01*
X506906Y1886221D01*
X506201Y1886116D01*
X505496Y1885696D01*
G01X512893Y1886221D02*
X512266Y1886011D01*
X511796Y1885486D01*
X511483Y1884856D01*
X511248Y1884016D01*
X511170Y1883071D01*
X511248Y1882126D01*
X511483Y1881286D01*
X511796Y1880656D01*
X512266Y1880131D01*
X512893Y1879921D01*
X513520Y1880131D01*
X513990Y1880656D01*
X514303Y1881286D01*
X514538Y1882126D01*
X514616Y1883071D01*
X514538Y1884016D01*
X514303Y1884856D01*
X513990Y1885486D01*
X513520Y1886011D01*
X512893Y1886221D01*
G01X519193Y1879711D02*
X519036Y1879816D01*
Y1880026D01*
X519193Y1880131D01*
X519350Y1880026D01*
Y1879816D01*
X519193Y1879711D01*
G01X525336Y1879921D02*
X525493Y1881286D01*
X525728Y1882441D01*
X526041Y1883491D01*
X526433Y1884646D01*
X527060Y1886221D01*
X523926D01*
G01X531793Y1879921D02*
Y1886221D01*
X530853Y1884961D01*
G01Y1879921D02*
X532733D01*
G01X533639Y951365D02*
X534188Y950840D01*
X534814Y950630D01*
X535441Y950840D01*
X535989Y951470D01*
X536381Y952415D01*
X536538Y953360D01*
Y954515D01*
X536381Y955460D01*
X535989Y956300D01*
X535519Y956720D01*
X534971Y956930D01*
X534344Y956720D01*
X533874Y956300D01*
X533561Y955670D01*
X533404Y954830D01*
X533561Y954095D01*
X533953Y953360D01*
X534423Y952940D01*
X534971Y952835D01*
X535598Y953045D01*
X536068Y953570D01*
X536538Y954515D01*
G01X539548Y951575D02*
X540018Y951050D01*
X540566Y950735D01*
X541271Y950630D01*
X541976Y950840D01*
X542524Y951260D01*
X542916Y951995D01*
X542994Y952835D01*
X542838Y953675D01*
X542446Y954200D01*
X541898Y954620D01*
X541349Y954725D01*
X540801Y954620D01*
X540096Y954200D01*
X540331Y956930D01*
X542446D01*
G01X545848Y951890D02*
X546318Y951155D01*
X546944Y950735D01*
X547649Y950630D01*
X548276Y950735D01*
X548903Y951260D01*
X549294Y951890D01*
X549373Y952520D01*
X549216Y953255D01*
X548668Y953780D01*
X548119Y953990D01*
X547414D01*
G01X548119D02*
X548589Y954305D01*
X548981Y954830D01*
X549138Y955460D01*
X548981Y956090D01*
X548589Y956615D01*
X547884Y956930D01*
X547179Y956825D01*
X546474Y956405D01*
G01X553714Y950630D02*
X553871Y951995D01*
X554106Y953150D01*
X554419Y954200D01*
X554811Y955355D01*
X555438Y956930D01*
X552304D01*
G01X560171Y950420D02*
X560014Y950525D01*
Y950735D01*
X560171Y950840D01*
X560328Y950735D01*
Y950525D01*
X560171Y950420D01*
G01X566471Y950630D02*
X567019Y950735D01*
X567646Y951050D01*
X568038Y951575D01*
X568194Y952310D01*
X568038Y953045D01*
X567568Y953675D01*
X566863Y953990D01*
X566079D01*
X565609Y954200D01*
X565218Y954725D01*
X565061Y955460D01*
X565296Y956195D01*
X565844Y956720D01*
X566471Y956930D01*
X567098Y956720D01*
X567646Y956195D01*
X567881Y955460D01*
X567724Y954725D01*
X567333Y954200D01*
X566863Y953990D01*
X566079D01*
X565374Y953675D01*
X564904Y953045D01*
X564748Y952310D01*
X564904Y951575D01*
X565296Y951050D01*
X565923Y950735D01*
X566471Y950630D01*
G01X572771Y956930D02*
X572144Y956720D01*
X571674Y956195D01*
X571361Y955565D01*
X571126Y954725D01*
X571048Y953780D01*
X571126Y952835D01*
X571361Y951995D01*
X571674Y951365D01*
X572144Y950840D01*
X572771Y950630D01*
X573398Y950840D01*
X573868Y951365D01*
X574181Y951995D01*
X574416Y952835D01*
X574494Y953780D01*
X574416Y954725D01*
X574181Y955565D01*
X573868Y956195D01*
X573398Y956720D01*
X572771Y956930D01*
G01X539813Y987971D02*
Y992971D01*
X542219D01*
G01X541333Y990554D02*
X539813D01*
G01X545356Y992971D02*
X546876D01*
G01X546116D02*
Y987971D01*
G01X545356D02*
X546876D01*
G01X551596Y990471D02*
X552863D01*
Y988971D01*
X552483Y988471D01*
X552039Y988138D01*
X551406Y987971D01*
X550773Y988138D01*
X550329Y988471D01*
X549949Y988971D01*
X549696Y989554D01*
X549569Y990221D01*
Y990804D01*
X549696Y991304D01*
X549949Y991888D01*
X550329Y992388D01*
X550709Y992721D01*
X551216Y992971D01*
X551659D01*
X552166Y992804D01*
X552546Y992471D01*
G01X554923Y992971D02*
Y989388D01*
X555176Y988638D01*
X555683Y988138D01*
X556316Y987971D01*
X556949Y988138D01*
X557456Y988638D01*
X557709Y989388D01*
Y992971D01*
G01X560149Y987971D02*
Y992971D01*
X561733D01*
X562239Y992721D01*
X562556Y992388D01*
X562683Y991721D01*
X562556Y991054D01*
X562176Y990638D01*
X561733Y990388D01*
X560149D01*
G01X561733D02*
X562683Y987971D01*
G01X567783D02*
X565249D01*
Y992971D01*
X567783D01*
G01X566769Y990554D02*
X565249D01*
G01X559083Y603254D02*
X559631Y603989D01*
X560101Y604409D01*
X560728Y604619D01*
X561276Y604409D01*
X561668Y603989D01*
X561981Y603359D01*
X562059Y602624D01*
X561981Y601994D01*
X561668Y601364D01*
X561198Y600839D01*
X560649Y600629D01*
X560023Y600839D01*
X559474Y601469D01*
X559161Y602414D01*
X559083Y603464D01*
X559239Y604829D01*
X559474Y605564D01*
X559866Y606299D01*
X560414Y606824D01*
X560963Y606929D01*
X561511Y606719D01*
X561903Y606194D01*
G01X566871Y606929D02*
X566244Y606719D01*
X565774Y606194D01*
X565461Y605564D01*
X565226Y604724D01*
X565148Y603779D01*
X565226Y602834D01*
X565461Y601994D01*
X565774Y601364D01*
X566244Y600839D01*
X566871Y600629D01*
X567498Y600839D01*
X567968Y601364D01*
X568281Y601994D01*
X568516Y602834D01*
X568594Y603779D01*
X568516Y604724D01*
X568281Y605564D01*
X567968Y606194D01*
X567498Y606719D01*
X566871Y606929D01*
G01X571448Y601889D02*
X571918Y601154D01*
X572544Y600734D01*
X573249Y600629D01*
X573876Y600734D01*
X574503Y601259D01*
X574894Y601889D01*
X574973Y602519D01*
X574816Y603254D01*
X574268Y603779D01*
X573719Y603989D01*
X573014D01*
G01X573719D02*
X574189Y604304D01*
X574581Y604829D01*
X574738Y605459D01*
X574581Y606089D01*
X574189Y606614D01*
X573484Y606929D01*
X572779Y606824D01*
X572074Y606404D01*
G01X579314Y600629D02*
X579471Y601994D01*
X579706Y603149D01*
X580019Y604199D01*
X580411Y605354D01*
X581038Y606929D01*
X577904D01*
G01X585771Y600419D02*
X585614Y600524D01*
Y600734D01*
X585771Y600839D01*
X585928Y600734D01*
Y600524D01*
X585771Y600419D01*
G01X591914Y600629D02*
X592071Y601994D01*
X592306Y603149D01*
X592619Y604199D01*
X593011Y605354D01*
X593638Y606929D01*
X590504D01*
G01X597039Y601364D02*
X597588Y600839D01*
X598214Y600629D01*
X598841Y600839D01*
X599389Y601469D01*
X599781Y602414D01*
X599938Y603359D01*
Y604514D01*
X599781Y605459D01*
X599389Y606299D01*
X598919Y606719D01*
X598371Y606929D01*
X597744Y606719D01*
X597274Y606299D01*
X596961Y605669D01*
X596804Y604829D01*
X596961Y604094D01*
X597353Y603359D01*
X597823Y602939D01*
X598371Y602834D01*
X598998Y603044D01*
X599468Y603569D01*
X599938Y604514D01*
G01X563108Y775630D02*
X563265Y776995D01*
X563500Y778150D01*
X563813Y779200D01*
X564205Y780355D01*
X564832Y781930D01*
X561698D01*
G01X569408Y775630D02*
X569565Y776995D01*
X569800Y778150D01*
X570113Y779200D01*
X570505Y780355D01*
X571132Y781930D01*
X567998D01*
G01X575865Y775630D02*
X576413Y775735D01*
X577040Y776050D01*
X577432Y776575D01*
X577588Y777310D01*
X577432Y778045D01*
X576962Y778675D01*
X576257Y778990D01*
X575473D01*
X575003Y779200D01*
X574612Y779725D01*
X574455Y780460D01*
X574690Y781195D01*
X575238Y781720D01*
X575865Y781930D01*
X576492Y781720D01*
X577040Y781195D01*
X577275Y780460D01*
X577118Y779725D01*
X576727Y779200D01*
X576257Y778990D01*
X575473D01*
X574768Y778675D01*
X574298Y778045D01*
X574142Y777310D01*
X574298Y776575D01*
X574690Y776050D01*
X575317Y775735D01*
X575865Y775630D01*
G01X582008D02*
X582165Y776995D01*
X582400Y778150D01*
X582713Y779200D01*
X583105Y780355D01*
X583732Y781930D01*
X580598D01*
G01X588465Y775420D02*
X588308Y775525D01*
Y775735D01*
X588465Y775840D01*
X588622Y775735D01*
Y775525D01*
X588465Y775420D01*
G01X594765Y775630D02*
X595313Y775735D01*
X595940Y776050D01*
X596332Y776575D01*
X596488Y777310D01*
X596332Y778045D01*
X595862Y778675D01*
X595157Y778990D01*
X594373D01*
X593903Y779200D01*
X593512Y779725D01*
X593355Y780460D01*
X593590Y781195D01*
X594138Y781720D01*
X594765Y781930D01*
X595392Y781720D01*
X595940Y781195D01*
X596175Y780460D01*
X596018Y779725D01*
X595627Y779200D01*
X595157Y778990D01*
X594373D01*
X593668Y778675D01*
X593198Y778045D01*
X593042Y777310D01*
X593198Y776575D01*
X593590Y776050D01*
X594217Y775735D01*
X594765Y775630D01*
G01X601065Y781930D02*
X600438Y781720D01*
X599968Y781195D01*
X599655Y780565D01*
X599420Y779725D01*
X599342Y778780D01*
X599420Y777835D01*
X599655Y776995D01*
X599968Y776365D01*
X600438Y775840D01*
X601065Y775630D01*
X601692Y775840D01*
X602162Y776365D01*
X602475Y776995D01*
X602710Y777835D01*
X602788Y778780D01*
X602710Y779725D01*
X602475Y780565D01*
X602162Y781195D01*
X601692Y781720D01*
X601065Y781930D01*
G01X584463Y64463D02*
X584843Y64963D01*
X585286Y65213D01*
X585793Y65296D01*
X586426Y65129D01*
X586869Y64713D01*
X586996Y64213D01*
X586933Y63713D01*
X586679Y63296D01*
X585413Y62463D01*
X584843Y61879D01*
X584463Y61046D01*
X584336Y60296D01*
X586996D01*
G01X591526D02*
Y65296D01*
X589183Y61713D01*
X592349D01*
G01X596626Y60296D02*
Y65296D01*
X594283Y61713D01*
X597449D01*
G01X600966Y60129D02*
X600839Y60213D01*
Y60379D01*
X600966Y60463D01*
X601093Y60379D01*
Y60213D01*
X600966Y60129D01*
G01X606066Y65296D02*
X605559Y65129D01*
X605179Y64713D01*
X604926Y64213D01*
X604736Y63546D01*
X604673Y62796D01*
X604736Y62046D01*
X604926Y61379D01*
X605179Y60879D01*
X605559Y60463D01*
X606066Y60296D01*
X606573Y60463D01*
X606953Y60879D01*
X607206Y61379D01*
X607396Y62046D01*
X607459Y62796D01*
X607396Y63546D01*
X607206Y64213D01*
X606953Y64713D01*
X606573Y65129D01*
X606066Y65296D01*
G01X610216Y63629D02*
X612116Y60296D01*
G01Y63629D02*
X610216Y60296D01*
G01X615063Y64463D02*
X615443Y64963D01*
X615886Y65213D01*
X616393Y65296D01*
X617026Y65129D01*
X617469Y64713D01*
X617596Y64213D01*
X617533Y63713D01*
X617279Y63296D01*
X616013Y62463D01*
X615443Y61879D01*
X615063Y61046D01*
X614936Y60296D01*
X617596D01*
G01X621366Y65296D02*
X620859Y65129D01*
X620479Y64713D01*
X620226Y64213D01*
X620036Y63546D01*
X619973Y62796D01*
X620036Y62046D01*
X620226Y61379D01*
X620479Y60879D01*
X620859Y60463D01*
X621366Y60296D01*
X621873Y60463D01*
X622253Y60879D01*
X622506Y61379D01*
X622696Y62046D01*
X622759Y62796D01*
X622696Y63546D01*
X622506Y64213D01*
X622253Y64713D01*
X621873Y65129D01*
X621366Y65296D01*
G01X625073Y61046D02*
X625453Y60629D01*
X625896Y60379D01*
X626466Y60296D01*
X627036Y60463D01*
X627479Y60796D01*
X627796Y61379D01*
X627859Y62046D01*
X627733Y62713D01*
X627416Y63129D01*
X626973Y63463D01*
X626529Y63546D01*
X626086Y63463D01*
X625516Y63129D01*
X625706Y65296D01*
X627416D01*
G01X631566Y60129D02*
X631439Y60213D01*
Y60379D01*
X631566Y60463D01*
X631693Y60379D01*
Y60213D01*
X631566Y60129D01*
G01X636666Y65296D02*
X636159Y65129D01*
X635779Y64713D01*
X635526Y64213D01*
X635336Y63546D01*
X635273Y62796D01*
X635336Y62046D01*
X635526Y61379D01*
X635779Y60879D01*
X636159Y60463D01*
X636666Y60296D01*
X637173Y60463D01*
X637553Y60879D01*
X637806Y61379D01*
X637996Y62046D01*
X638059Y62796D01*
X637996Y63546D01*
X637806Y64213D01*
X637553Y64713D01*
X637173Y65129D01*
X636666Y65296D01*
G01X599573Y108546D02*
X599953Y107963D01*
X600459Y107629D01*
X601029Y107546D01*
X601536Y107629D01*
X602043Y108046D01*
X602359Y108546D01*
X602423Y109046D01*
X602296Y109629D01*
X601853Y110046D01*
X601409Y110213D01*
X600839D01*
G01X601409D02*
X601789Y110463D01*
X602106Y110879D01*
X602233Y111379D01*
X602106Y111879D01*
X601789Y112296D01*
X601219Y112546D01*
X600649Y112463D01*
X600079Y112129D01*
G01X606066Y107546D02*
Y112546D01*
X605306Y111546D01*
G01Y107546D02*
X606826D01*
G01X609773Y108296D02*
X610153Y107879D01*
X610596Y107629D01*
X611166Y107546D01*
X611736Y107713D01*
X612179Y108046D01*
X612496Y108629D01*
X612559Y109296D01*
X612433Y109963D01*
X612116Y110379D01*
X611673Y110713D01*
X611229Y110796D01*
X610786Y110713D01*
X610216Y110379D01*
X610406Y112546D01*
X612116D01*
G01X616266Y107379D02*
X616139Y107463D01*
Y107629D01*
X616266Y107713D01*
X616393Y107629D01*
Y107463D01*
X616266Y107379D01*
G01X621366Y112546D02*
X620859Y112379D01*
X620479Y111963D01*
X620226Y111463D01*
X620036Y110796D01*
X619973Y110046D01*
X620036Y109296D01*
X620226Y108629D01*
X620479Y108129D01*
X620859Y107713D01*
X621366Y107546D01*
X621873Y107713D01*
X622253Y108129D01*
X622506Y108629D01*
X622696Y109296D01*
X622759Y110046D01*
X622696Y110796D01*
X622506Y111463D01*
X622253Y111963D01*
X621873Y112379D01*
X621366Y112546D01*
G01X599763Y158963D02*
X600143Y159463D01*
X600586Y159713D01*
X601093Y159796D01*
X601726Y159629D01*
X602169Y159213D01*
X602296Y158713D01*
X602233Y158213D01*
X601979Y157796D01*
X600713Y156963D01*
X600143Y156379D01*
X599763Y155546D01*
X599636Y154796D01*
X602296D01*
G01X606066Y159796D02*
X605559Y159629D01*
X605179Y159213D01*
X604926Y158713D01*
X604736Y158046D01*
X604673Y157296D01*
X604736Y156546D01*
X604926Y155879D01*
X605179Y155379D01*
X605559Y154963D01*
X606066Y154796D01*
X606573Y154963D01*
X606953Y155379D01*
X607206Y155879D01*
X607396Y156546D01*
X607459Y157296D01*
X607396Y158046D01*
X607206Y158713D01*
X606953Y159213D01*
X606573Y159629D01*
X606066Y159796D01*
G01X609773Y155546D02*
X610153Y155129D01*
X610596Y154879D01*
X611166Y154796D01*
X611736Y154963D01*
X612179Y155296D01*
X612496Y155879D01*
X612559Y156546D01*
X612433Y157213D01*
X612116Y157629D01*
X611673Y157963D01*
X611229Y158046D01*
X610786Y157963D01*
X610216Y157629D01*
X610406Y159796D01*
X612116D01*
G01X616266Y154629D02*
X616139Y154713D01*
Y154879D01*
X616266Y154963D01*
X616393Y154879D01*
Y154713D01*
X616266Y154629D01*
G01X621366Y159796D02*
X620859Y159629D01*
X620479Y159213D01*
X620226Y158713D01*
X620036Y158046D01*
X619973Y157296D01*
X620036Y156546D01*
X620226Y155879D01*
X620479Y155379D01*
X620859Y154963D01*
X621366Y154796D01*
X621873Y154963D01*
X622253Y155379D01*
X622506Y155879D01*
X622696Y156546D01*
X622759Y157296D01*
X622696Y158046D01*
X622506Y158713D01*
X622253Y159213D01*
X621873Y159629D01*
X621366Y159796D01*
G01X600966Y202046D02*
Y207046D01*
X600206Y206046D01*
G01Y202046D02*
X601726D01*
G01X604673Y202796D02*
X605053Y202379D01*
X605496Y202129D01*
X606066Y202046D01*
X606636Y202213D01*
X607079Y202546D01*
X607396Y203129D01*
X607459Y203796D01*
X607333Y204463D01*
X607016Y204879D01*
X606573Y205213D01*
X606129Y205296D01*
X605686Y205213D01*
X605116Y204879D01*
X605306Y207046D01*
X607016D01*
G01X611166Y202046D02*
X611609Y202129D01*
X612116Y202379D01*
X612433Y202796D01*
X612559Y203379D01*
X612433Y203963D01*
X612053Y204463D01*
X611483Y204713D01*
X610849D01*
X610469Y204879D01*
X610153Y205296D01*
X610026Y205879D01*
X610216Y206463D01*
X610659Y206879D01*
X611166Y207046D01*
X611673Y206879D01*
X612116Y206463D01*
X612306Y205879D01*
X612179Y205296D01*
X611863Y204879D01*
X611483Y204713D01*
X610849D01*
X610279Y204463D01*
X609899Y203963D01*
X609773Y203379D01*
X609899Y202796D01*
X610216Y202379D01*
X610723Y202129D01*
X611166Y202046D01*
G01X616266Y201879D02*
X616139Y201963D01*
Y202129D01*
X616266Y202213D01*
X616393Y202129D01*
Y201963D01*
X616266Y201879D01*
G01X621366Y207046D02*
X620859Y206879D01*
X620479Y206463D01*
X620226Y205963D01*
X620036Y205296D01*
X619973Y204546D01*
X620036Y203796D01*
X620226Y203129D01*
X620479Y202629D01*
X620859Y202213D01*
X621366Y202046D01*
X621873Y202213D01*
X622253Y202629D01*
X622506Y203129D01*
X622696Y203796D01*
X622759Y204546D01*
X622696Y205296D01*
X622506Y205963D01*
X622253Y206463D01*
X621873Y206879D01*
X621366Y207046D01*
G01X600966Y249296D02*
Y254296D01*
X600206Y253296D01*
G01Y249296D02*
X601726D01*
G01X604673Y250296D02*
X605053Y249713D01*
X605559Y249379D01*
X606129Y249296D01*
X606636Y249379D01*
X607143Y249796D01*
X607459Y250296D01*
X607523Y250796D01*
X607396Y251379D01*
X606953Y251796D01*
X606509Y251963D01*
X605939D01*
G01X606509D02*
X606889Y252213D01*
X607206Y252629D01*
X607333Y253129D01*
X607206Y253629D01*
X606889Y254046D01*
X606319Y254296D01*
X605749Y254213D01*
X605179Y253879D01*
G01X609963Y253463D02*
X610343Y253963D01*
X610786Y254213D01*
X611293Y254296D01*
X611926Y254129D01*
X612369Y253713D01*
X612496Y253213D01*
X612433Y252713D01*
X612179Y252296D01*
X610913Y251463D01*
X610343Y250879D01*
X609963Y250046D01*
X609836Y249296D01*
X612496D01*
G01X616266Y249129D02*
X616139Y249213D01*
Y249379D01*
X616266Y249463D01*
X616393Y249379D01*
Y249213D01*
X616266Y249129D01*
G01X621366Y254296D02*
X620859Y254129D01*
X620479Y253713D01*
X620226Y253213D01*
X620036Y252546D01*
X619973Y251796D01*
X620036Y251046D01*
X620226Y250379D01*
X620479Y249879D01*
X620859Y249463D01*
X621366Y249296D01*
X621873Y249463D01*
X622253Y249879D01*
X622506Y250379D01*
X622696Y251046D01*
X622759Y251796D01*
X622696Y252546D01*
X622506Y253213D01*
X622253Y253713D01*
X621873Y254129D01*
X621366Y254296D01*
G01X600966Y296546D02*
Y301546D01*
X600206Y300546D01*
G01Y296546D02*
X601726D01*
G01X604863Y300713D02*
X605243Y301213D01*
X605686Y301463D01*
X606193Y301546D01*
X606826Y301379D01*
X607269Y300963D01*
X607396Y300463D01*
X607333Y299963D01*
X607079Y299546D01*
X605813Y298713D01*
X605243Y298129D01*
X604863Y297296D01*
X604736Y296546D01*
X607396D01*
G01X609963Y298629D02*
X610406Y299213D01*
X610786Y299546D01*
X611293Y299713D01*
X611736Y299546D01*
X612053Y299213D01*
X612306Y298713D01*
X612369Y298129D01*
X612306Y297629D01*
X612053Y297129D01*
X611673Y296713D01*
X611229Y296546D01*
X610723Y296713D01*
X610279Y297213D01*
X610026Y297963D01*
X609963Y298796D01*
X610089Y299879D01*
X610279Y300463D01*
X610596Y301046D01*
X611039Y301463D01*
X611483Y301546D01*
X611926Y301379D01*
X612243Y300963D01*
G01X616266Y296379D02*
X616139Y296463D01*
Y296629D01*
X616266Y296713D01*
X616393Y296629D01*
Y296463D01*
X616266Y296379D01*
G01X621366Y301546D02*
X620859Y301379D01*
X620479Y300963D01*
X620226Y300463D01*
X620036Y299796D01*
X619973Y299046D01*
X620036Y298296D01*
X620226Y297629D01*
X620479Y297129D01*
X620859Y296713D01*
X621366Y296546D01*
X621873Y296713D01*
X622253Y297129D01*
X622506Y297629D01*
X622696Y298296D01*
X622759Y299046D01*
X622696Y299796D01*
X622506Y300463D01*
X622253Y300963D01*
X621873Y301379D01*
X621366Y301546D01*
G01X602439Y344379D02*
X602883Y343963D01*
X603389Y343796D01*
X603896Y343963D01*
X604339Y344463D01*
X604656Y345213D01*
X604783Y345963D01*
Y346879D01*
X604656Y347629D01*
X604339Y348296D01*
X603959Y348629D01*
X603516Y348796D01*
X603009Y348629D01*
X602629Y348296D01*
X602376Y347796D01*
X602249Y347129D01*
X602376Y346546D01*
X602693Y345963D01*
X603073Y345629D01*
X603516Y345546D01*
X604023Y345713D01*
X604403Y346129D01*
X604783Y346879D01*
G01X607539Y344379D02*
X607983Y343963D01*
X608489Y343796D01*
X608996Y343963D01*
X609439Y344463D01*
X609756Y345213D01*
X609883Y345963D01*
Y346879D01*
X609756Y347629D01*
X609439Y348296D01*
X609059Y348629D01*
X608616Y348796D01*
X608109Y348629D01*
X607729Y348296D01*
X607476Y347796D01*
X607349Y347129D01*
X607476Y346546D01*
X607793Y345963D01*
X608173Y345629D01*
X608616Y345546D01*
X609123Y345713D01*
X609503Y346129D01*
X609883Y346879D01*
G01X613716Y343629D02*
X613589Y343713D01*
Y343879D01*
X613716Y343963D01*
X613843Y343879D01*
Y343713D01*
X613716Y343629D01*
G01X618816Y348796D02*
X618309Y348629D01*
X617929Y348213D01*
X617676Y347713D01*
X617486Y347046D01*
X617423Y346296D01*
X617486Y345546D01*
X617676Y344879D01*
X617929Y344379D01*
X618309Y343963D01*
X618816Y343796D01*
X619323Y343963D01*
X619703Y344379D01*
X619956Y344879D01*
X620146Y345546D01*
X620209Y346296D01*
X620146Y347046D01*
X619956Y347713D01*
X619703Y348213D01*
X619323Y348629D01*
X618816Y348796D01*
G01X602439Y391629D02*
X602883Y391213D01*
X603389Y391046D01*
X603896Y391213D01*
X604339Y391713D01*
X604656Y392463D01*
X604783Y393213D01*
Y394129D01*
X604656Y394879D01*
X604339Y395546D01*
X603959Y395879D01*
X603516Y396046D01*
X603009Y395879D01*
X602629Y395546D01*
X602376Y395046D01*
X602249Y394379D01*
X602376Y393796D01*
X602693Y393213D01*
X603073Y392879D01*
X603516Y392796D01*
X604023Y392963D01*
X604403Y393379D01*
X604783Y394129D01*
G01X607223Y391796D02*
X607603Y391379D01*
X608046Y391129D01*
X608616Y391046D01*
X609186Y391213D01*
X609629Y391546D01*
X609946Y392129D01*
X610009Y392796D01*
X609883Y393463D01*
X609566Y393879D01*
X609123Y394213D01*
X608679Y394296D01*
X608236Y394213D01*
X607666Y393879D01*
X607856Y396046D01*
X609566D01*
G01X613716Y390879D02*
X613589Y390963D01*
Y391129D01*
X613716Y391213D01*
X613843Y391129D01*
Y390963D01*
X613716Y390879D01*
G01X618816Y396046D02*
X618309Y395879D01*
X617929Y395463D01*
X617676Y394963D01*
X617486Y394296D01*
X617423Y393546D01*
X617486Y392796D01*
X617676Y392129D01*
X617929Y391629D01*
X618309Y391213D01*
X618816Y391046D01*
X619323Y391213D01*
X619703Y391629D01*
X619956Y392129D01*
X620146Y392796D01*
X620209Y393546D01*
X620146Y394296D01*
X619956Y394963D01*
X619703Y395463D01*
X619323Y395879D01*
X618816Y396046D01*
G01X602123Y439046D02*
X602503Y438629D01*
X602946Y438379D01*
X603516Y438296D01*
X604086Y438463D01*
X604529Y438796D01*
X604846Y439379D01*
X604909Y440046D01*
X604783Y440713D01*
X604466Y441129D01*
X604023Y441463D01*
X603579Y441546D01*
X603136Y441463D01*
X602566Y441129D01*
X602756Y443296D01*
X604466D01*
G01X607413Y442463D02*
X607793Y442963D01*
X608236Y443213D01*
X608743Y443296D01*
X609376Y443129D01*
X609819Y442713D01*
X609946Y442213D01*
X609883Y441713D01*
X609629Y441296D01*
X608363Y440463D01*
X607793Y439879D01*
X607413Y439046D01*
X607286Y438296D01*
X609946D01*
G01X613716Y438129D02*
X613589Y438213D01*
Y438379D01*
X613716Y438463D01*
X613843Y438379D01*
Y438213D01*
X613716Y438129D01*
G01X618816Y443296D02*
X618309Y443129D01*
X617929Y442713D01*
X617676Y442213D01*
X617486Y441546D01*
X617423Y440796D01*
X617486Y440046D01*
X617676Y439379D01*
X617929Y438879D01*
X618309Y438463D01*
X618816Y438296D01*
X619323Y438463D01*
X619703Y438879D01*
X619956Y439379D01*
X620146Y440046D01*
X620209Y440796D01*
X620146Y441546D01*
X619956Y442213D01*
X619703Y442713D01*
X619323Y443129D01*
X618816Y443296D01*
G01X602313Y487629D02*
X602756Y488213D01*
X603136Y488546D01*
X603643Y488713D01*
X604086Y488546D01*
X604403Y488213D01*
X604656Y487713D01*
X604719Y487129D01*
X604656Y486629D01*
X604403Y486129D01*
X604023Y485713D01*
X603579Y485546D01*
X603073Y485713D01*
X602629Y486213D01*
X602376Y486963D01*
X602313Y487796D01*
X602439Y488879D01*
X602629Y489463D01*
X602946Y490046D01*
X603389Y490463D01*
X603833Y490546D01*
X604276Y490379D01*
X604593Y489963D01*
G01X607223Y486546D02*
X607603Y485963D01*
X608109Y485629D01*
X608679Y485546D01*
X609186Y485629D01*
X609693Y486046D01*
X610009Y486546D01*
X610073Y487046D01*
X609946Y487629D01*
X609503Y488046D01*
X609059Y488213D01*
X608489D01*
G01X609059D02*
X609439Y488463D01*
X609756Y488879D01*
X609883Y489379D01*
X609756Y489879D01*
X609439Y490296D01*
X608869Y490546D01*
X608299Y490463D01*
X607729Y490129D01*
G01X613716Y485379D02*
X613589Y485463D01*
Y485629D01*
X613716Y485713D01*
X613843Y485629D01*
Y485463D01*
X613716Y485379D01*
G01X618816Y490546D02*
X618309Y490379D01*
X617929Y489963D01*
X617676Y489463D01*
X617486Y488796D01*
X617423Y488046D01*
X617486Y487296D01*
X617676Y486629D01*
X617929Y486129D01*
X618309Y485713D01*
X618816Y485546D01*
X619323Y485713D01*
X619703Y486129D01*
X619956Y486629D01*
X620146Y487296D01*
X620209Y488046D01*
X620146Y488796D01*
X619956Y489463D01*
X619703Y489963D01*
X619323Y490379D01*
X618816Y490546D01*
G01X602123Y533546D02*
X602503Y533129D01*
X602946Y532879D01*
X603516Y532796D01*
X604086Y532963D01*
X604529Y533296D01*
X604846Y533879D01*
X604909Y534546D01*
X604783Y535213D01*
X604466Y535629D01*
X604023Y535963D01*
X603579Y536046D01*
X603136Y535963D01*
X602566Y535629D01*
X602756Y537796D01*
X604466D01*
G01X608489Y532796D02*
X608616Y533879D01*
X608806Y534796D01*
X609059Y535629D01*
X609376Y536546D01*
X609883Y537796D01*
X607349D01*
G01X613716Y532629D02*
X613589Y532713D01*
Y532879D01*
X613716Y532963D01*
X613843Y532879D01*
Y532713D01*
X613716Y532629D01*
G01X618816Y537796D02*
X618309Y537629D01*
X617929Y537213D01*
X617676Y536713D01*
X617486Y536046D01*
X617423Y535296D01*
X617486Y534546D01*
X617676Y533879D01*
X617929Y533379D01*
X618309Y532963D01*
X618816Y532796D01*
X619323Y532963D01*
X619703Y533379D01*
X619956Y533879D01*
X620146Y534546D01*
X620209Y535296D01*
X620146Y536046D01*
X619956Y536713D01*
X619703Y537213D01*
X619323Y537629D01*
X618816Y537796D01*
G01X604276Y580046D02*
Y585046D01*
X601933Y581463D01*
X605099D01*
G01X609376Y580046D02*
Y585046D01*
X607033Y581463D01*
X610199D01*
G01X613716Y579879D02*
X613589Y579963D01*
Y580129D01*
X613716Y580213D01*
X613843Y580129D01*
Y579963D01*
X613716Y579879D01*
G01X618816Y585046D02*
X618309Y584879D01*
X617929Y584463D01*
X617676Y583963D01*
X617486Y583296D01*
X617423Y582546D01*
X617486Y581796D01*
X617676Y581129D01*
X617929Y580629D01*
X618309Y580213D01*
X618816Y580046D01*
X619323Y580213D01*
X619703Y580629D01*
X619956Y581129D01*
X620146Y581796D01*
X620209Y582546D01*
X620146Y583296D01*
X619956Y583963D01*
X619703Y584463D01*
X619323Y584879D01*
X618816Y585046D01*
G01X604276Y627296D02*
Y632296D01*
X601933Y628713D01*
X605099D01*
G01X607223Y628296D02*
X607603Y627713D01*
X608109Y627379D01*
X608679Y627296D01*
X609186Y627379D01*
X609693Y627796D01*
X610009Y628296D01*
X610073Y628796D01*
X609946Y629379D01*
X609503Y629796D01*
X609059Y629963D01*
X608489D01*
G01X609059D02*
X609439Y630213D01*
X609756Y630629D01*
X609883Y631129D01*
X609756Y631629D01*
X609439Y632046D01*
X608869Y632296D01*
X608299Y632213D01*
X607729Y631879D01*
G01X613716Y627129D02*
X613589Y627213D01*
Y627379D01*
X613716Y627463D01*
X613843Y627379D01*
Y627213D01*
X613716Y627129D01*
G01X618816Y632296D02*
X618309Y632129D01*
X617929Y631713D01*
X617676Y631213D01*
X617486Y630546D01*
X617423Y629796D01*
X617486Y629046D01*
X617676Y628379D01*
X617929Y627879D01*
X618309Y627463D01*
X618816Y627296D01*
X619323Y627463D01*
X619703Y627879D01*
X619956Y628379D01*
X620146Y629046D01*
X620209Y629796D01*
X620146Y630546D01*
X619956Y631213D01*
X619703Y631713D01*
X619323Y632129D01*
X618816Y632296D01*
G01X602123Y675546D02*
X602503Y674963D01*
X603009Y674629D01*
X603579Y674546D01*
X604086Y674629D01*
X604593Y675046D01*
X604909Y675546D01*
X604973Y676046D01*
X604846Y676629D01*
X604403Y677046D01*
X603959Y677213D01*
X603389D01*
G01X603959D02*
X604339Y677463D01*
X604656Y677879D01*
X604783Y678379D01*
X604656Y678879D01*
X604339Y679296D01*
X603769Y679546D01*
X603199Y679463D01*
X602629Y679129D01*
G01X607539Y675129D02*
X607983Y674713D01*
X608489Y674546D01*
X608996Y674713D01*
X609439Y675213D01*
X609756Y675963D01*
X609883Y676713D01*
Y677629D01*
X609756Y678379D01*
X609439Y679046D01*
X609059Y679379D01*
X608616Y679546D01*
X608109Y679379D01*
X607729Y679046D01*
X607476Y678546D01*
X607349Y677879D01*
X607476Y677296D01*
X607793Y676713D01*
X608173Y676379D01*
X608616Y676296D01*
X609123Y676463D01*
X609503Y676879D01*
X609883Y677629D01*
G01X613716Y674379D02*
X613589Y674463D01*
Y674629D01*
X613716Y674713D01*
X613843Y674629D01*
Y674463D01*
X613716Y674379D01*
G01X618816Y679546D02*
X618309Y679379D01*
X617929Y678963D01*
X617676Y678463D01*
X617486Y677796D01*
X617423Y677046D01*
X617486Y676296D01*
X617676Y675629D01*
X617929Y675129D01*
X618309Y674713D01*
X618816Y674546D01*
X619323Y674713D01*
X619703Y675129D01*
X619956Y675629D01*
X620146Y676296D01*
X620209Y677046D01*
X620146Y677796D01*
X619956Y678463D01*
X619703Y678963D01*
X619323Y679379D01*
X618816Y679546D01*
G01X602123Y722796D02*
X602503Y722213D01*
X603009Y721879D01*
X603579Y721796D01*
X604086Y721879D01*
X604593Y722296D01*
X604909Y722796D01*
X604973Y723296D01*
X604846Y723879D01*
X604403Y724296D01*
X603959Y724463D01*
X603389D01*
G01X603959D02*
X604339Y724713D01*
X604656Y725129D01*
X604783Y725629D01*
X604656Y726129D01*
X604339Y726546D01*
X603769Y726796D01*
X603199Y726713D01*
X602629Y726379D01*
G01X607413Y723879D02*
X607856Y724463D01*
X608236Y724796D01*
X608743Y724963D01*
X609186Y724796D01*
X609503Y724463D01*
X609756Y723963D01*
X609819Y723379D01*
X609756Y722879D01*
X609503Y722379D01*
X609123Y721963D01*
X608679Y721796D01*
X608173Y721963D01*
X607729Y722463D01*
X607476Y723213D01*
X607413Y724046D01*
X607539Y725129D01*
X607729Y725713D01*
X608046Y726296D01*
X608489Y726713D01*
X608933Y726796D01*
X609376Y726629D01*
X609693Y726213D01*
G01X613716Y721629D02*
X613589Y721713D01*
Y721879D01*
X613716Y721963D01*
X613843Y721879D01*
Y721713D01*
X613716Y721629D01*
G01X618816Y726796D02*
X618309Y726629D01*
X617929Y726213D01*
X617676Y725713D01*
X617486Y725046D01*
X617423Y724296D01*
X617486Y723546D01*
X617676Y722879D01*
X617929Y722379D01*
X618309Y721963D01*
X618816Y721796D01*
X619323Y721963D01*
X619703Y722379D01*
X619956Y722879D01*
X620146Y723546D01*
X620209Y724296D01*
X620146Y725046D01*
X619956Y725713D01*
X619703Y726213D01*
X619323Y726629D01*
X618816Y726796D01*
G01X602123Y770046D02*
X602503Y769463D01*
X603009Y769129D01*
X603579Y769046D01*
X604086Y769129D01*
X604593Y769546D01*
X604909Y770046D01*
X604973Y770546D01*
X604846Y771129D01*
X604403Y771546D01*
X603959Y771713D01*
X603389D01*
G01X603959D02*
X604339Y771963D01*
X604656Y772379D01*
X604783Y772879D01*
X604656Y773379D01*
X604339Y773796D01*
X603769Y774046D01*
X603199Y773963D01*
X602629Y773629D01*
G01X608616Y774046D02*
X608109Y773879D01*
X607729Y773463D01*
X607476Y772963D01*
X607286Y772296D01*
X607223Y771546D01*
X607286Y770796D01*
X607476Y770129D01*
X607729Y769629D01*
X608109Y769213D01*
X608616Y769046D01*
X609123Y769213D01*
X609503Y769629D01*
X609756Y770129D01*
X609946Y770796D01*
X610009Y771546D01*
X609946Y772296D01*
X609756Y772963D01*
X609503Y773463D01*
X609123Y773879D01*
X608616Y774046D01*
G01X613716Y768879D02*
X613589Y768963D01*
Y769129D01*
X613716Y769213D01*
X613843Y769129D01*
Y768963D01*
X613716Y768879D01*
G01X618816Y774046D02*
X618309Y773879D01*
X617929Y773463D01*
X617676Y772963D01*
X617486Y772296D01*
X617423Y771546D01*
X617486Y770796D01*
X617676Y770129D01*
X617929Y769629D01*
X618309Y769213D01*
X618816Y769046D01*
X619323Y769213D01*
X619703Y769629D01*
X619956Y770129D01*
X620146Y770796D01*
X620209Y771546D01*
X620146Y772296D01*
X619956Y772963D01*
X619703Y773463D01*
X619323Y773879D01*
X618816Y774046D01*
G01X602313Y820463D02*
X602693Y820963D01*
X603136Y821213D01*
X603643Y821296D01*
X604276Y821129D01*
X604719Y820713D01*
X604846Y820213D01*
X604783Y819713D01*
X604529Y819296D01*
X603263Y818463D01*
X602693Y817879D01*
X602313Y817046D01*
X602186Y816296D01*
X604846D01*
G01X608616D02*
X609059Y816379D01*
X609566Y816629D01*
X609883Y817046D01*
X610009Y817629D01*
X609883Y818213D01*
X609503Y818713D01*
X608933Y818963D01*
X608299D01*
X607919Y819129D01*
X607603Y819546D01*
X607476Y820129D01*
X607666Y820713D01*
X608109Y821129D01*
X608616Y821296D01*
X609123Y821129D01*
X609566Y820713D01*
X609756Y820129D01*
X609629Y819546D01*
X609313Y819129D01*
X608933Y818963D01*
X608299D01*
X607729Y818713D01*
X607349Y818213D01*
X607223Y817629D01*
X607349Y817046D01*
X607666Y816629D01*
X608173Y816379D01*
X608616Y816296D01*
G01X613716Y816129D02*
X613589Y816213D01*
Y816379D01*
X613716Y816463D01*
X613843Y816379D01*
Y816213D01*
X613716Y816129D01*
G01X618816Y821296D02*
X618309Y821129D01*
X617929Y820713D01*
X617676Y820213D01*
X617486Y819546D01*
X617423Y818796D01*
X617486Y818046D01*
X617676Y817379D01*
X617929Y816879D01*
X618309Y816463D01*
X618816Y816296D01*
X619323Y816463D01*
X619703Y816879D01*
X619956Y817379D01*
X620146Y818046D01*
X620209Y818796D01*
X620146Y819546D01*
X619956Y820213D01*
X619703Y820713D01*
X619323Y821129D01*
X618816Y821296D01*
G01X602313Y867713D02*
X602693Y868213D01*
X603136Y868463D01*
X603643Y868546D01*
X604276Y868379D01*
X604719Y867963D01*
X604846Y867463D01*
X604783Y866963D01*
X604529Y866546D01*
X603263Y865713D01*
X602693Y865129D01*
X602313Y864296D01*
X602186Y863546D01*
X604846D01*
G01X607413Y867713D02*
X607793Y868213D01*
X608236Y868463D01*
X608743Y868546D01*
X609376Y868379D01*
X609819Y867963D01*
X609946Y867463D01*
X609883Y866963D01*
X609629Y866546D01*
X608363Y865713D01*
X607793Y865129D01*
X607413Y864296D01*
X607286Y863546D01*
X609946D01*
G01X613716Y863379D02*
X613589Y863463D01*
Y863629D01*
X613716Y863713D01*
X613843Y863629D01*
Y863463D01*
X613716Y863379D01*
G01X618816Y868546D02*
X618309Y868379D01*
X617929Y867963D01*
X617676Y867463D01*
X617486Y866796D01*
X617423Y866046D01*
X617486Y865296D01*
X617676Y864629D01*
X617929Y864129D01*
X618309Y863713D01*
X618816Y863546D01*
X619323Y863713D01*
X619703Y864129D01*
X619956Y864629D01*
X620146Y865296D01*
X620209Y866046D01*
X620146Y866796D01*
X619956Y867463D01*
X619703Y867963D01*
X619323Y868379D01*
X618816Y868546D01*
G01X603516Y910796D02*
Y915796D01*
X602756Y914796D01*
G01Y910796D02*
X604276D01*
G01X608616Y915796D02*
X608109Y915629D01*
X607729Y915213D01*
X607476Y914713D01*
X607286Y914046D01*
X607223Y913296D01*
X607286Y912546D01*
X607476Y911879D01*
X607729Y911379D01*
X608109Y910963D01*
X608616Y910796D01*
X609123Y910963D01*
X609503Y911379D01*
X609756Y911879D01*
X609946Y912546D01*
X610009Y913296D01*
X609946Y914046D01*
X609756Y914713D01*
X609503Y915213D01*
X609123Y915629D01*
X608616Y915796D01*
G01X613716Y910629D02*
X613589Y910713D01*
Y910879D01*
X613716Y910963D01*
X613843Y910879D01*
Y910713D01*
X613716Y910629D01*
G01X618816Y915796D02*
X618309Y915629D01*
X617929Y915213D01*
X617676Y914713D01*
X617486Y914046D01*
X617423Y913296D01*
X617486Y912546D01*
X617676Y911879D01*
X617929Y911379D01*
X618309Y910963D01*
X618816Y910796D01*
X619323Y910963D01*
X619703Y911379D01*
X619956Y911879D01*
X620146Y912546D01*
X620209Y913296D01*
X620146Y914046D01*
X619956Y914713D01*
X619703Y915213D01*
X619323Y915629D01*
X618816Y915796D01*
G01X603516Y958046D02*
Y963046D01*
X602756Y962046D01*
G01Y958046D02*
X604276D01*
G01X608616Y963046D02*
X608109Y962879D01*
X607729Y962463D01*
X607476Y961963D01*
X607286Y961296D01*
X607223Y960546D01*
X607286Y959796D01*
X607476Y959129D01*
X607729Y958629D01*
X608109Y958213D01*
X608616Y958046D01*
X609123Y958213D01*
X609503Y958629D01*
X609756Y959129D01*
X609946Y959796D01*
X610009Y960546D01*
X609946Y961296D01*
X609756Y961963D01*
X609503Y962463D01*
X609123Y962879D01*
X608616Y963046D01*
G01X613716Y957879D02*
X613589Y957963D01*
Y958129D01*
X613716Y958213D01*
X613843Y958129D01*
Y957963D01*
X613716Y957879D01*
G01X618816Y963046D02*
X618309Y962879D01*
X617929Y962463D01*
X617676Y961963D01*
X617486Y961296D01*
X617423Y960546D01*
X617486Y959796D01*
X617676Y959129D01*
X617929Y958629D01*
X618309Y958213D01*
X618816Y958046D01*
X619323Y958213D01*
X619703Y958629D01*
X619956Y959129D01*
X620146Y959796D01*
X620209Y960546D01*
X620146Y961296D01*
X619956Y961963D01*
X619703Y962463D01*
X619323Y962879D01*
X618816Y963046D01*
G01X602186Y988638D02*
X602693Y988221D01*
X603263Y987971D01*
X603769D01*
X604276Y988221D01*
X604656Y988638D01*
X604846Y989221D01*
X604719Y989804D01*
X604403Y990304D01*
X603833Y990638D01*
X603073Y990804D01*
X602629Y991138D01*
X602439Y991721D01*
X602566Y992304D01*
X602883Y992721D01*
X603326Y992971D01*
X603769D01*
X604213Y992804D01*
X604593Y992388D01*
G01X607856Y992971D02*
X609376D01*
G01X608616D02*
Y987971D01*
G01X607856D02*
X609376D01*
G01X612513Y992971D02*
X614919D01*
X612513Y987971D01*
X614919D01*
G01X620083D02*
X617549D01*
Y992971D01*
X620083D01*
G01X619069Y990554D02*
X617549D01*
G01X621083Y999271D02*
X622666Y1004271D01*
X624249Y999271D01*
G01X623679Y1001021D02*
X621653D01*
G01X626499Y1004271D02*
Y999271D01*
X629033D01*
G01X631599Y1004271D02*
Y999271D01*
X634133D01*
G01X641673Y1004271D02*
Y1000688D01*
X641926Y999938D01*
X642433Y999438D01*
X643066Y999271D01*
X643699Y999438D01*
X644206Y999938D01*
X644459Y1000688D01*
Y1004271D01*
G01X646709Y999271D02*
Y1004271D01*
X649623Y999271D01*
Y1004271D01*
G01X652506D02*
X654026D01*
G01X653266D02*
Y999271D01*
G01X652506D02*
X654026D01*
G01X658366Y1004271D02*
Y999271D01*
G01X656909Y1004271D02*
X659823D01*
G01X662136Y999938D02*
X662643Y999521D01*
X663213Y999271D01*
X663719D01*
X664226Y999521D01*
X664606Y999938D01*
X664796Y1000521D01*
X664669Y1001104D01*
X664353Y1001604D01*
X663783Y1001938D01*
X663023Y1002104D01*
X662579Y1002438D01*
X662389Y1003021D01*
X662516Y1003604D01*
X662833Y1004021D01*
X663276Y1004271D01*
X663719D01*
X664163Y1004104D01*
X664543Y1003688D01*
G01X672083Y999271D02*
X673666Y1004271D01*
X675249Y999271D01*
G01X674679Y1001021D02*
X672653D01*
G01X677499Y999271D02*
Y1004271D01*
X679083D01*
X679589Y1004021D01*
X679906Y1003688D01*
X680033Y1003021D01*
X679906Y1002354D01*
X679526Y1001938D01*
X679083Y1001688D01*
X677499D01*
G01X679083D02*
X680033Y999271D01*
G01X685133D02*
X682599D01*
Y1004271D01*
X685133D01*
G01X684119Y1001854D02*
X682599D01*
G01X693306Y1004271D02*
X694826D01*
G01X694066D02*
Y999271D01*
G01X693306D02*
X694826D01*
G01X697709D02*
Y1004271D01*
X700623Y999271D01*
Y1004271D01*
G01X707719Y999271D02*
Y1004271D01*
X709366Y1000104D01*
X711013Y1004271D01*
Y999271D01*
G01X713706Y1004271D02*
X715226D01*
G01X714466D02*
Y999271D01*
G01X713706D02*
X715226D01*
G01X718299Y1004271D02*
Y999271D01*
X720833D01*
G01X723336Y999938D02*
X723843Y999521D01*
X724413Y999271D01*
X724919D01*
X725426Y999521D01*
X725806Y999938D01*
X725996Y1000521D01*
X725869Y1001104D01*
X725553Y1001604D01*
X724983Y1001938D01*
X724223Y1002104D01*
X723779Y1002438D01*
X723589Y1003021D01*
X723716Y1003604D01*
X724033Y1004021D01*
X724476Y1004271D01*
X724919D01*
X725363Y1004104D01*
X725743Y1003688D01*
G01X608523Y1024271D02*
Y1029271D01*
X609789D01*
X610296Y1029021D01*
X610676Y1028688D01*
X610993Y1028188D01*
X611246Y1027604D01*
X611309Y1026771D01*
X611246Y1025938D01*
X610993Y1025354D01*
X610676Y1024854D01*
X610296Y1024521D01*
X609789Y1024271D01*
X608523D01*
G01X613749D02*
Y1029271D01*
X615333D01*
X615839Y1029021D01*
X616156Y1028688D01*
X616283Y1028021D01*
X616156Y1027354D01*
X615776Y1026938D01*
X615333Y1026688D01*
X613749D01*
G01X615333D02*
X616283Y1024271D01*
G01X619356Y1029271D02*
X620876D01*
G01X620116D02*
Y1024271D01*
G01X619356D02*
X620876D01*
G01X623949Y1029271D02*
Y1024271D01*
X626483D01*
G01X629049Y1029271D02*
Y1024271D01*
X631583D01*
G01X641909Y1028854D02*
X641529Y1029104D01*
X641086Y1029271D01*
X640579D01*
X640009Y1029021D01*
X639566Y1028604D01*
X639249Y1028104D01*
X638996Y1027271D01*
X638933Y1026521D01*
X639059Y1025771D01*
X639249Y1025271D01*
X639629Y1024771D01*
X640073Y1024438D01*
X640516Y1024271D01*
X640959D01*
X641403Y1024438D01*
X641783Y1024688D01*
X642099Y1025021D01*
G01X644286Y1024271D02*
Y1029271D01*
G01X646946D02*
Y1024271D01*
G01Y1026771D02*
X644286D01*
G01X649133Y1024271D02*
X650716Y1029271D01*
X652299Y1024271D01*
G01X651729Y1026021D02*
X649703D01*
G01X654549Y1024271D02*
Y1029271D01*
X656133D01*
X656639Y1029021D01*
X656956Y1028688D01*
X657083Y1028021D01*
X656956Y1027354D01*
X656576Y1026938D01*
X656133Y1026688D01*
X654549D01*
G01X656133D02*
X657083Y1024271D01*
G01X660916Y1029271D02*
Y1024271D01*
G01X659459Y1029271D02*
X662373D01*
G01X666016Y1024104D02*
X665889Y1024188D01*
Y1024354D01*
X666016Y1024438D01*
X666143Y1024354D01*
Y1024188D01*
X666016Y1024104D01*
G01Y1026354D02*
X665889Y1026438D01*
Y1026604D01*
X666016Y1026688D01*
X666143Y1026604D01*
Y1026438D01*
X666016Y1026354D01*
G01X676216Y1029271D02*
Y1024271D01*
G01X674759Y1029271D02*
X677673D01*
G01X681316Y1024271D02*
X680809Y1024354D01*
X680366Y1024688D01*
X679986Y1025188D01*
X679733Y1025771D01*
X679606Y1026438D01*
Y1027104D01*
X679733Y1027771D01*
X679986Y1028354D01*
X680366Y1028854D01*
X680809Y1029188D01*
X681316Y1029271D01*
X681823Y1029188D01*
X682266Y1028854D01*
X682646Y1028354D01*
X682899Y1027771D01*
X683026Y1027104D01*
Y1026438D01*
X682899Y1025771D01*
X682646Y1025188D01*
X682266Y1024688D01*
X681823Y1024354D01*
X681316Y1024271D01*
G01X685149D02*
Y1029271D01*
X686669D01*
X687176Y1029021D01*
X687556Y1028438D01*
X687683Y1027771D01*
X687556Y1027104D01*
X687239Y1026604D01*
X686669Y1026354D01*
X685149D01*
G01X696616Y1029271D02*
Y1024271D01*
G01X695729Y1027604D02*
X697503D01*
G01X701716Y1024271D02*
X701336Y1024354D01*
X700956Y1024688D01*
X700703Y1025271D01*
X700576Y1025938D01*
X700703Y1026604D01*
X700956Y1027188D01*
X701336Y1027521D01*
X701716Y1027604D01*
X702096Y1027521D01*
X702476Y1027188D01*
X702729Y1026604D01*
X702793Y1025938D01*
X702729Y1025271D01*
X702476Y1024688D01*
X702096Y1024354D01*
X701716Y1024271D01*
G01X712423Y1026938D02*
X712676Y1027188D01*
X712866Y1027604D01*
X712993Y1028188D01*
X712866Y1028688D01*
X712613Y1029021D01*
X712169Y1029271D01*
X710459D01*
Y1024271D01*
X712549D01*
X712993Y1024604D01*
X713246Y1025104D01*
X713373Y1025688D01*
X713246Y1026271D01*
X712866Y1026771D01*
X712423Y1026938D01*
X710459D01*
G01X717016Y1024271D02*
X716509Y1024354D01*
X716066Y1024688D01*
X715686Y1025188D01*
X715433Y1025771D01*
X715306Y1026438D01*
Y1027104D01*
X715433Y1027771D01*
X715686Y1028354D01*
X716066Y1028854D01*
X716509Y1029188D01*
X717016Y1029271D01*
X717523Y1029188D01*
X717966Y1028854D01*
X718346Y1028354D01*
X718599Y1027771D01*
X718726Y1027104D01*
Y1026438D01*
X718599Y1025771D01*
X718346Y1025188D01*
X717966Y1024688D01*
X717523Y1024354D01*
X717016Y1024271D01*
G01X722116Y1029271D02*
Y1024271D01*
G01X720659Y1029271D02*
X723573D01*
G01X727216D02*
Y1024271D01*
G01X725759Y1029271D02*
X728673D01*
G01X732316Y1024271D02*
X731809Y1024354D01*
X731366Y1024688D01*
X730986Y1025188D01*
X730733Y1025771D01*
X730606Y1026438D01*
Y1027104D01*
X730733Y1027771D01*
X730986Y1028354D01*
X731366Y1028854D01*
X731809Y1029188D01*
X732316Y1029271D01*
X732823Y1029188D01*
X733266Y1028854D01*
X733646Y1028354D01*
X733899Y1027771D01*
X734026Y1027104D01*
Y1026438D01*
X733899Y1025771D01*
X733646Y1025188D01*
X733266Y1024688D01*
X732823Y1024354D01*
X732316Y1024271D01*
G01X735769D02*
Y1029271D01*
X737416Y1025104D01*
X739063Y1029271D01*
Y1024271D01*
G01X667869Y61963D02*
X669389D01*
G01X668566Y63046D02*
Y60879D01*
G01X674426Y60296D02*
Y65296D01*
X672083Y61713D01*
X675249D01*
G01X678766Y60129D02*
X678639Y60213D01*
Y60379D01*
X678766Y60463D01*
X678893Y60379D01*
Y60213D01*
X678766Y60129D01*
G01X683866Y65296D02*
X683359Y65129D01*
X682979Y64713D01*
X682726Y64213D01*
X682536Y63546D01*
X682473Y62796D01*
X682536Y62046D01*
X682726Y61379D01*
X682979Y60879D01*
X683359Y60463D01*
X683866Y60296D01*
X684373Y60463D01*
X684753Y60879D01*
X685006Y61379D01*
X685196Y62046D01*
X685259Y62796D01*
X685196Y63546D01*
X685006Y64213D01*
X684753Y64713D01*
X684373Y65129D01*
X683866Y65296D01*
G01X687826Y60129D02*
X690106Y65296D01*
G01X693243Y61963D02*
X694889D01*
G01X699926Y60296D02*
Y65296D01*
X697583Y61713D01*
X700749D01*
G01X704266Y60129D02*
X704139Y60213D01*
Y60379D01*
X704266Y60463D01*
X704393Y60379D01*
Y60213D01*
X704266Y60129D01*
G01X709366Y65296D02*
X708859Y65129D01*
X708479Y64713D01*
X708226Y64213D01*
X708036Y63546D01*
X707973Y62796D01*
X708036Y62046D01*
X708226Y61379D01*
X708479Y60879D01*
X708859Y60463D01*
X709366Y60296D01*
X709873Y60463D01*
X710253Y60879D01*
X710506Y61379D01*
X710696Y62046D01*
X710759Y62796D01*
X710696Y63546D01*
X710506Y64213D01*
X710253Y64713D01*
X709873Y65129D01*
X709366Y65296D01*
G01X667869Y109213D02*
X669389D01*
G01X668566Y110296D02*
Y108129D01*
G01X674426Y107546D02*
Y112546D01*
X672083Y108963D01*
X675249D01*
G01X678766Y107379D02*
X678639Y107463D01*
Y107629D01*
X678766Y107713D01*
X678893Y107629D01*
Y107463D01*
X678766Y107379D01*
G01X683866Y112546D02*
X683359Y112379D01*
X682979Y111963D01*
X682726Y111463D01*
X682536Y110796D01*
X682473Y110046D01*
X682536Y109296D01*
X682726Y108629D01*
X682979Y108129D01*
X683359Y107713D01*
X683866Y107546D01*
X684373Y107713D01*
X684753Y108129D01*
X685006Y108629D01*
X685196Y109296D01*
X685259Y110046D01*
X685196Y110796D01*
X685006Y111463D01*
X684753Y111963D01*
X684373Y112379D01*
X683866Y112546D01*
G01X687826Y107379D02*
X690106Y112546D01*
G01X693243Y109213D02*
X694889D01*
G01X699926Y107546D02*
Y112546D01*
X697583Y108963D01*
X700749D01*
G01X704266Y107379D02*
X704139Y107463D01*
Y107629D01*
X704266Y107713D01*
X704393Y107629D01*
Y107463D01*
X704266Y107379D01*
G01X709366Y112546D02*
X708859Y112379D01*
X708479Y111963D01*
X708226Y111463D01*
X708036Y110796D01*
X707973Y110046D01*
X708036Y109296D01*
X708226Y108629D01*
X708479Y108129D01*
X708859Y107713D01*
X709366Y107546D01*
X709873Y107713D01*
X710253Y108129D01*
X710506Y108629D01*
X710696Y109296D01*
X710759Y110046D01*
X710696Y110796D01*
X710506Y111463D01*
X710253Y111963D01*
X709873Y112379D01*
X709366Y112546D01*
G01X667869Y156463D02*
X669389D01*
G01X668566Y157546D02*
Y155379D01*
G01X672463Y158963D02*
X672843Y159463D01*
X673286Y159713D01*
X673793Y159796D01*
X674426Y159629D01*
X674869Y159213D01*
X674996Y158713D01*
X674933Y158213D01*
X674679Y157796D01*
X673413Y156963D01*
X672843Y156379D01*
X672463Y155546D01*
X672336Y154796D01*
X674996D01*
G01X678766Y154629D02*
X678639Y154713D01*
Y154879D01*
X678766Y154963D01*
X678893Y154879D01*
Y154713D01*
X678766Y154629D01*
G01X683866Y159796D02*
X683359Y159629D01*
X682979Y159213D01*
X682726Y158713D01*
X682536Y158046D01*
X682473Y157296D01*
X682536Y156546D01*
X682726Y155879D01*
X682979Y155379D01*
X683359Y154963D01*
X683866Y154796D01*
X684373Y154963D01*
X684753Y155379D01*
X685006Y155879D01*
X685196Y156546D01*
X685259Y157296D01*
X685196Y158046D01*
X685006Y158713D01*
X684753Y159213D01*
X684373Y159629D01*
X683866Y159796D01*
G01X687826Y154629D02*
X690106Y159796D01*
G01X693243Y156463D02*
X694889D01*
G01X697963Y158963D02*
X698343Y159463D01*
X698786Y159713D01*
X699293Y159796D01*
X699926Y159629D01*
X700369Y159213D01*
X700496Y158713D01*
X700433Y158213D01*
X700179Y157796D01*
X698913Y156963D01*
X698343Y156379D01*
X697963Y155546D01*
X697836Y154796D01*
X700496D01*
G01X704266Y154629D02*
X704139Y154713D01*
Y154879D01*
X704266Y154963D01*
X704393Y154879D01*
Y154713D01*
X704266Y154629D01*
G01X709366Y159796D02*
X708859Y159629D01*
X708479Y159213D01*
X708226Y158713D01*
X708036Y158046D01*
X707973Y157296D01*
X708036Y156546D01*
X708226Y155879D01*
X708479Y155379D01*
X708859Y154963D01*
X709366Y154796D01*
X709873Y154963D01*
X710253Y155379D01*
X710506Y155879D01*
X710696Y156546D01*
X710759Y157296D01*
X710696Y158046D01*
X710506Y158713D01*
X710253Y159213D01*
X709873Y159629D01*
X709366Y159796D01*
G01X667869Y203713D02*
X669389D01*
G01X668566Y204796D02*
Y202629D01*
G01X672463Y206213D02*
X672843Y206713D01*
X673286Y206963D01*
X673793Y207046D01*
X674426Y206879D01*
X674869Y206463D01*
X674996Y205963D01*
X674933Y205463D01*
X674679Y205046D01*
X673413Y204213D01*
X672843Y203629D01*
X672463Y202796D01*
X672336Y202046D01*
X674996D01*
G01X678766Y201879D02*
X678639Y201963D01*
Y202129D01*
X678766Y202213D01*
X678893Y202129D01*
Y201963D01*
X678766Y201879D01*
G01X683866Y207046D02*
X683359Y206879D01*
X682979Y206463D01*
X682726Y205963D01*
X682536Y205296D01*
X682473Y204546D01*
X682536Y203796D01*
X682726Y203129D01*
X682979Y202629D01*
X683359Y202213D01*
X683866Y202046D01*
X684373Y202213D01*
X684753Y202629D01*
X685006Y203129D01*
X685196Y203796D01*
X685259Y204546D01*
X685196Y205296D01*
X685006Y205963D01*
X684753Y206463D01*
X684373Y206879D01*
X683866Y207046D01*
G01X687826Y201879D02*
X690106Y207046D01*
G01X693243Y203713D02*
X694889D01*
G01X697963Y206213D02*
X698343Y206713D01*
X698786Y206963D01*
X699293Y207046D01*
X699926Y206879D01*
X700369Y206463D01*
X700496Y205963D01*
X700433Y205463D01*
X700179Y205046D01*
X698913Y204213D01*
X698343Y203629D01*
X697963Y202796D01*
X697836Y202046D01*
X700496D01*
G01X704266Y201879D02*
X704139Y201963D01*
Y202129D01*
X704266Y202213D01*
X704393Y202129D01*
Y201963D01*
X704266Y201879D01*
G01X709366Y207046D02*
X708859Y206879D01*
X708479Y206463D01*
X708226Y205963D01*
X708036Y205296D01*
X707973Y204546D01*
X708036Y203796D01*
X708226Y203129D01*
X708479Y202629D01*
X708859Y202213D01*
X709366Y202046D01*
X709873Y202213D01*
X710253Y202629D01*
X710506Y203129D01*
X710696Y203796D01*
X710759Y204546D01*
X710696Y205296D01*
X710506Y205963D01*
X710253Y206463D01*
X709873Y206879D01*
X709366Y207046D01*
G01X667869Y250963D02*
X669389D01*
G01X668566Y252046D02*
Y249879D01*
G01X672463Y253463D02*
X672843Y253963D01*
X673286Y254213D01*
X673793Y254296D01*
X674426Y254129D01*
X674869Y253713D01*
X674996Y253213D01*
X674933Y252713D01*
X674679Y252296D01*
X673413Y251463D01*
X672843Y250879D01*
X672463Y250046D01*
X672336Y249296D01*
X674996D01*
G01X678766Y249129D02*
X678639Y249213D01*
Y249379D01*
X678766Y249463D01*
X678893Y249379D01*
Y249213D01*
X678766Y249129D01*
G01X683866Y254296D02*
X683359Y254129D01*
X682979Y253713D01*
X682726Y253213D01*
X682536Y252546D01*
X682473Y251796D01*
X682536Y251046D01*
X682726Y250379D01*
X682979Y249879D01*
X683359Y249463D01*
X683866Y249296D01*
X684373Y249463D01*
X684753Y249879D01*
X685006Y250379D01*
X685196Y251046D01*
X685259Y251796D01*
X685196Y252546D01*
X685006Y253213D01*
X684753Y253713D01*
X684373Y254129D01*
X683866Y254296D01*
G01X687826Y249129D02*
X690106Y254296D01*
G01X693243Y250963D02*
X694889D01*
G01X697963Y253463D02*
X698343Y253963D01*
X698786Y254213D01*
X699293Y254296D01*
X699926Y254129D01*
X700369Y253713D01*
X700496Y253213D01*
X700433Y252713D01*
X700179Y252296D01*
X698913Y251463D01*
X698343Y250879D01*
X697963Y250046D01*
X697836Y249296D01*
X700496D01*
G01X704266Y249129D02*
X704139Y249213D01*
Y249379D01*
X704266Y249463D01*
X704393Y249379D01*
Y249213D01*
X704266Y249129D01*
G01X709366Y254296D02*
X708859Y254129D01*
X708479Y253713D01*
X708226Y253213D01*
X708036Y252546D01*
X707973Y251796D01*
X708036Y251046D01*
X708226Y250379D01*
X708479Y249879D01*
X708859Y249463D01*
X709366Y249296D01*
X709873Y249463D01*
X710253Y249879D01*
X710506Y250379D01*
X710696Y251046D01*
X710759Y251796D01*
X710696Y252546D01*
X710506Y253213D01*
X710253Y253713D01*
X709873Y254129D01*
X709366Y254296D01*
G01X667869Y298213D02*
X669389D01*
G01X668566Y299296D02*
Y297129D01*
G01X672463Y300713D02*
X672843Y301213D01*
X673286Y301463D01*
X673793Y301546D01*
X674426Y301379D01*
X674869Y300963D01*
X674996Y300463D01*
X674933Y299963D01*
X674679Y299546D01*
X673413Y298713D01*
X672843Y298129D01*
X672463Y297296D01*
X672336Y296546D01*
X674996D01*
G01X678766Y296379D02*
X678639Y296463D01*
Y296629D01*
X678766Y296713D01*
X678893Y296629D01*
Y296463D01*
X678766Y296379D01*
G01X683866Y301546D02*
X683359Y301379D01*
X682979Y300963D01*
X682726Y300463D01*
X682536Y299796D01*
X682473Y299046D01*
X682536Y298296D01*
X682726Y297629D01*
X682979Y297129D01*
X683359Y296713D01*
X683866Y296546D01*
X684373Y296713D01*
X684753Y297129D01*
X685006Y297629D01*
X685196Y298296D01*
X685259Y299046D01*
X685196Y299796D01*
X685006Y300463D01*
X684753Y300963D01*
X684373Y301379D01*
X683866Y301546D01*
G01X687826Y296379D02*
X690106Y301546D01*
G01X693243Y298213D02*
X694889D01*
G01X697963Y300713D02*
X698343Y301213D01*
X698786Y301463D01*
X699293Y301546D01*
X699926Y301379D01*
X700369Y300963D01*
X700496Y300463D01*
X700433Y299963D01*
X700179Y299546D01*
X698913Y298713D01*
X698343Y298129D01*
X697963Y297296D01*
X697836Y296546D01*
X700496D01*
G01X704266Y296379D02*
X704139Y296463D01*
Y296629D01*
X704266Y296713D01*
X704393Y296629D01*
Y296463D01*
X704266Y296379D01*
G01X709366Y301546D02*
X708859Y301379D01*
X708479Y300963D01*
X708226Y300463D01*
X708036Y299796D01*
X707973Y299046D01*
X708036Y298296D01*
X708226Y297629D01*
X708479Y297129D01*
X708859Y296713D01*
X709366Y296546D01*
X709873Y296713D01*
X710253Y297129D01*
X710506Y297629D01*
X710696Y298296D01*
X710759Y299046D01*
X710696Y299796D01*
X710506Y300463D01*
X710253Y300963D01*
X709873Y301379D01*
X709366Y301546D01*
G01X667869Y345463D02*
X669389D01*
G01X668566Y346546D02*
Y344379D01*
G01X672463Y347963D02*
X672843Y348463D01*
X673286Y348713D01*
X673793Y348796D01*
X674426Y348629D01*
X674869Y348213D01*
X674996Y347713D01*
X674933Y347213D01*
X674679Y346796D01*
X673413Y345963D01*
X672843Y345379D01*
X672463Y344546D01*
X672336Y343796D01*
X674996D01*
G01X678766Y343629D02*
X678639Y343713D01*
Y343879D01*
X678766Y343963D01*
X678893Y343879D01*
Y343713D01*
X678766Y343629D01*
G01X683866Y348796D02*
X683359Y348629D01*
X682979Y348213D01*
X682726Y347713D01*
X682536Y347046D01*
X682473Y346296D01*
X682536Y345546D01*
X682726Y344879D01*
X682979Y344379D01*
X683359Y343963D01*
X683866Y343796D01*
X684373Y343963D01*
X684753Y344379D01*
X685006Y344879D01*
X685196Y345546D01*
X685259Y346296D01*
X685196Y347046D01*
X685006Y347713D01*
X684753Y348213D01*
X684373Y348629D01*
X683866Y348796D01*
G01X687826Y343629D02*
X690106Y348796D01*
G01X693243Y345463D02*
X694889D01*
G01X697963Y347963D02*
X698343Y348463D01*
X698786Y348713D01*
X699293Y348796D01*
X699926Y348629D01*
X700369Y348213D01*
X700496Y347713D01*
X700433Y347213D01*
X700179Y346796D01*
X698913Y345963D01*
X698343Y345379D01*
X697963Y344546D01*
X697836Y343796D01*
X700496D01*
G01X704266Y343629D02*
X704139Y343713D01*
Y343879D01*
X704266Y343963D01*
X704393Y343879D01*
Y343713D01*
X704266Y343629D01*
G01X709366Y348796D02*
X708859Y348629D01*
X708479Y348213D01*
X708226Y347713D01*
X708036Y347046D01*
X707973Y346296D01*
X708036Y345546D01*
X708226Y344879D01*
X708479Y344379D01*
X708859Y343963D01*
X709366Y343796D01*
X709873Y343963D01*
X710253Y344379D01*
X710506Y344879D01*
X710696Y345546D01*
X710759Y346296D01*
X710696Y347046D01*
X710506Y347713D01*
X710253Y348213D01*
X709873Y348629D01*
X709366Y348796D01*
G01X667869Y392713D02*
X669389D01*
G01X668566Y393796D02*
Y391629D01*
G01X672463Y395213D02*
X672843Y395713D01*
X673286Y395963D01*
X673793Y396046D01*
X674426Y395879D01*
X674869Y395463D01*
X674996Y394963D01*
X674933Y394463D01*
X674679Y394046D01*
X673413Y393213D01*
X672843Y392629D01*
X672463Y391796D01*
X672336Y391046D01*
X674996D01*
G01X678766Y390879D02*
X678639Y390963D01*
Y391129D01*
X678766Y391213D01*
X678893Y391129D01*
Y390963D01*
X678766Y390879D01*
G01X683866Y396046D02*
X683359Y395879D01*
X682979Y395463D01*
X682726Y394963D01*
X682536Y394296D01*
X682473Y393546D01*
X682536Y392796D01*
X682726Y392129D01*
X682979Y391629D01*
X683359Y391213D01*
X683866Y391046D01*
X684373Y391213D01*
X684753Y391629D01*
X685006Y392129D01*
X685196Y392796D01*
X685259Y393546D01*
X685196Y394296D01*
X685006Y394963D01*
X684753Y395463D01*
X684373Y395879D01*
X683866Y396046D01*
G01X687826Y390879D02*
X690106Y396046D01*
G01X693243Y392713D02*
X694889D01*
G01X697963Y395213D02*
X698343Y395713D01*
X698786Y395963D01*
X699293Y396046D01*
X699926Y395879D01*
X700369Y395463D01*
X700496Y394963D01*
X700433Y394463D01*
X700179Y394046D01*
X698913Y393213D01*
X698343Y392629D01*
X697963Y391796D01*
X697836Y391046D01*
X700496D01*
G01X704266Y390879D02*
X704139Y390963D01*
Y391129D01*
X704266Y391213D01*
X704393Y391129D01*
Y390963D01*
X704266Y390879D01*
G01X709366Y396046D02*
X708859Y395879D01*
X708479Y395463D01*
X708226Y394963D01*
X708036Y394296D01*
X707973Y393546D01*
X708036Y392796D01*
X708226Y392129D01*
X708479Y391629D01*
X708859Y391213D01*
X709366Y391046D01*
X709873Y391213D01*
X710253Y391629D01*
X710506Y392129D01*
X710696Y392796D01*
X710759Y393546D01*
X710696Y394296D01*
X710506Y394963D01*
X710253Y395463D01*
X709873Y395879D01*
X709366Y396046D01*
G01X667869Y439963D02*
X669389D01*
G01X668566Y441046D02*
Y438879D01*
G01X672463Y442463D02*
X672843Y442963D01*
X673286Y443213D01*
X673793Y443296D01*
X674426Y443129D01*
X674869Y442713D01*
X674996Y442213D01*
X674933Y441713D01*
X674679Y441296D01*
X673413Y440463D01*
X672843Y439879D01*
X672463Y439046D01*
X672336Y438296D01*
X674996D01*
G01X678766Y438129D02*
X678639Y438213D01*
Y438379D01*
X678766Y438463D01*
X678893Y438379D01*
Y438213D01*
X678766Y438129D01*
G01X683866Y443296D02*
X683359Y443129D01*
X682979Y442713D01*
X682726Y442213D01*
X682536Y441546D01*
X682473Y440796D01*
X682536Y440046D01*
X682726Y439379D01*
X682979Y438879D01*
X683359Y438463D01*
X683866Y438296D01*
X684373Y438463D01*
X684753Y438879D01*
X685006Y439379D01*
X685196Y440046D01*
X685259Y440796D01*
X685196Y441546D01*
X685006Y442213D01*
X684753Y442713D01*
X684373Y443129D01*
X683866Y443296D01*
G01X687826Y438129D02*
X690106Y443296D01*
G01X693243Y439963D02*
X694889D01*
G01X697963Y442463D02*
X698343Y442963D01*
X698786Y443213D01*
X699293Y443296D01*
X699926Y443129D01*
X700369Y442713D01*
X700496Y442213D01*
X700433Y441713D01*
X700179Y441296D01*
X698913Y440463D01*
X698343Y439879D01*
X697963Y439046D01*
X697836Y438296D01*
X700496D01*
G01X704266Y438129D02*
X704139Y438213D01*
Y438379D01*
X704266Y438463D01*
X704393Y438379D01*
Y438213D01*
X704266Y438129D01*
G01X709366Y443296D02*
X708859Y443129D01*
X708479Y442713D01*
X708226Y442213D01*
X708036Y441546D01*
X707973Y440796D01*
X708036Y440046D01*
X708226Y439379D01*
X708479Y438879D01*
X708859Y438463D01*
X709366Y438296D01*
X709873Y438463D01*
X710253Y438879D01*
X710506Y439379D01*
X710696Y440046D01*
X710759Y440796D01*
X710696Y441546D01*
X710506Y442213D01*
X710253Y442713D01*
X709873Y443129D01*
X709366Y443296D01*
G01X667869Y487213D02*
X669389D01*
G01X668566Y488296D02*
Y486129D01*
G01X672273Y486546D02*
X672653Y485963D01*
X673159Y485629D01*
X673729Y485546D01*
X674236Y485629D01*
X674743Y486046D01*
X675059Y486546D01*
X675123Y487046D01*
X674996Y487629D01*
X674553Y488046D01*
X674109Y488213D01*
X673539D01*
G01X674109D02*
X674489Y488463D01*
X674806Y488879D01*
X674933Y489379D01*
X674806Y489879D01*
X674489Y490296D01*
X673919Y490546D01*
X673349Y490463D01*
X672779Y490129D01*
G01X678766Y485379D02*
X678639Y485463D01*
Y485629D01*
X678766Y485713D01*
X678893Y485629D01*
Y485463D01*
X678766Y485379D01*
G01X683866Y490546D02*
X683359Y490379D01*
X682979Y489963D01*
X682726Y489463D01*
X682536Y488796D01*
X682473Y488046D01*
X682536Y487296D01*
X682726Y486629D01*
X682979Y486129D01*
X683359Y485713D01*
X683866Y485546D01*
X684373Y485713D01*
X684753Y486129D01*
X685006Y486629D01*
X685196Y487296D01*
X685259Y488046D01*
X685196Y488796D01*
X685006Y489463D01*
X684753Y489963D01*
X684373Y490379D01*
X683866Y490546D01*
G01X687826Y485379D02*
X690106Y490546D01*
G01X693243Y487213D02*
X694889D01*
G01X697773Y486546D02*
X698153Y485963D01*
X698659Y485629D01*
X699229Y485546D01*
X699736Y485629D01*
X700243Y486046D01*
X700559Y486546D01*
X700623Y487046D01*
X700496Y487629D01*
X700053Y488046D01*
X699609Y488213D01*
X699039D01*
G01X699609D02*
X699989Y488463D01*
X700306Y488879D01*
X700433Y489379D01*
X700306Y489879D01*
X699989Y490296D01*
X699419Y490546D01*
X698849Y490463D01*
X698279Y490129D01*
G01X704266Y485379D02*
X704139Y485463D01*
Y485629D01*
X704266Y485713D01*
X704393Y485629D01*
Y485463D01*
X704266Y485379D01*
G01X709366Y490546D02*
X708859Y490379D01*
X708479Y489963D01*
X708226Y489463D01*
X708036Y488796D01*
X707973Y488046D01*
X708036Y487296D01*
X708226Y486629D01*
X708479Y486129D01*
X708859Y485713D01*
X709366Y485546D01*
X709873Y485713D01*
X710253Y486129D01*
X710506Y486629D01*
X710696Y487296D01*
X710759Y488046D01*
X710696Y488796D01*
X710506Y489463D01*
X710253Y489963D01*
X709873Y490379D01*
X709366Y490546D01*
G01X667869Y534463D02*
X669389D01*
G01X668566Y535546D02*
Y533379D01*
G01X672273Y533796D02*
X672653Y533213D01*
X673159Y532879D01*
X673729Y532796D01*
X674236Y532879D01*
X674743Y533296D01*
X675059Y533796D01*
X675123Y534296D01*
X674996Y534879D01*
X674553Y535296D01*
X674109Y535463D01*
X673539D01*
G01X674109D02*
X674489Y535713D01*
X674806Y536129D01*
X674933Y536629D01*
X674806Y537129D01*
X674489Y537546D01*
X673919Y537796D01*
X673349Y537713D01*
X672779Y537379D01*
G01X678766Y532629D02*
X678639Y532713D01*
Y532879D01*
X678766Y532963D01*
X678893Y532879D01*
Y532713D01*
X678766Y532629D01*
G01X683866Y537796D02*
X683359Y537629D01*
X682979Y537213D01*
X682726Y536713D01*
X682536Y536046D01*
X682473Y535296D01*
X682536Y534546D01*
X682726Y533879D01*
X682979Y533379D01*
X683359Y532963D01*
X683866Y532796D01*
X684373Y532963D01*
X684753Y533379D01*
X685006Y533879D01*
X685196Y534546D01*
X685259Y535296D01*
X685196Y536046D01*
X685006Y536713D01*
X684753Y537213D01*
X684373Y537629D01*
X683866Y537796D01*
G01X687826Y532629D02*
X690106Y537796D01*
G01X693243Y534463D02*
X694889D01*
G01X697773Y533796D02*
X698153Y533213D01*
X698659Y532879D01*
X699229Y532796D01*
X699736Y532879D01*
X700243Y533296D01*
X700559Y533796D01*
X700623Y534296D01*
X700496Y534879D01*
X700053Y535296D01*
X699609Y535463D01*
X699039D01*
G01X699609D02*
X699989Y535713D01*
X700306Y536129D01*
X700433Y536629D01*
X700306Y537129D01*
X699989Y537546D01*
X699419Y537796D01*
X698849Y537713D01*
X698279Y537379D01*
G01X704266Y532629D02*
X704139Y532713D01*
Y532879D01*
X704266Y532963D01*
X704393Y532879D01*
Y532713D01*
X704266Y532629D01*
G01X709366Y537796D02*
X708859Y537629D01*
X708479Y537213D01*
X708226Y536713D01*
X708036Y536046D01*
X707973Y535296D01*
X708036Y534546D01*
X708226Y533879D01*
X708479Y533379D01*
X708859Y532963D01*
X709366Y532796D01*
X709873Y532963D01*
X710253Y533379D01*
X710506Y533879D01*
X710696Y534546D01*
X710759Y535296D01*
X710696Y536046D01*
X710506Y536713D01*
X710253Y537213D01*
X709873Y537629D01*
X709366Y537796D01*
G01X667869Y581713D02*
X669389D01*
G01X668566Y582796D02*
Y580629D01*
G01X672273Y581046D02*
X672653Y580463D01*
X673159Y580129D01*
X673729Y580046D01*
X674236Y580129D01*
X674743Y580546D01*
X675059Y581046D01*
X675123Y581546D01*
X674996Y582129D01*
X674553Y582546D01*
X674109Y582713D01*
X673539D01*
G01X674109D02*
X674489Y582963D01*
X674806Y583379D01*
X674933Y583879D01*
X674806Y584379D01*
X674489Y584796D01*
X673919Y585046D01*
X673349Y584963D01*
X672779Y584629D01*
G01X678766Y579879D02*
X678639Y579963D01*
Y580129D01*
X678766Y580213D01*
X678893Y580129D01*
Y579963D01*
X678766Y579879D01*
G01X683866Y585046D02*
X683359Y584879D01*
X682979Y584463D01*
X682726Y583963D01*
X682536Y583296D01*
X682473Y582546D01*
X682536Y581796D01*
X682726Y581129D01*
X682979Y580629D01*
X683359Y580213D01*
X683866Y580046D01*
X684373Y580213D01*
X684753Y580629D01*
X685006Y581129D01*
X685196Y581796D01*
X685259Y582546D01*
X685196Y583296D01*
X685006Y583963D01*
X684753Y584463D01*
X684373Y584879D01*
X683866Y585046D01*
G01X687826Y579879D02*
X690106Y585046D01*
G01X693243Y581713D02*
X694889D01*
G01X697773Y581046D02*
X698153Y580463D01*
X698659Y580129D01*
X699229Y580046D01*
X699736Y580129D01*
X700243Y580546D01*
X700559Y581046D01*
X700623Y581546D01*
X700496Y582129D01*
X700053Y582546D01*
X699609Y582713D01*
X699039D01*
G01X699609D02*
X699989Y582963D01*
X700306Y583379D01*
X700433Y583879D01*
X700306Y584379D01*
X699989Y584796D01*
X699419Y585046D01*
X698849Y584963D01*
X698279Y584629D01*
G01X704266Y579879D02*
X704139Y579963D01*
Y580129D01*
X704266Y580213D01*
X704393Y580129D01*
Y579963D01*
X704266Y579879D01*
G01X709366Y585046D02*
X708859Y584879D01*
X708479Y584463D01*
X708226Y583963D01*
X708036Y583296D01*
X707973Y582546D01*
X708036Y581796D01*
X708226Y581129D01*
X708479Y580629D01*
X708859Y580213D01*
X709366Y580046D01*
X709873Y580213D01*
X710253Y580629D01*
X710506Y581129D01*
X710696Y581796D01*
X710759Y582546D01*
X710696Y583296D01*
X710506Y583963D01*
X710253Y584463D01*
X709873Y584879D01*
X709366Y585046D01*
G01X667869Y628963D02*
X669389D01*
G01X668566Y630046D02*
Y627879D01*
G01X672273Y628296D02*
X672653Y627713D01*
X673159Y627379D01*
X673729Y627296D01*
X674236Y627379D01*
X674743Y627796D01*
X675059Y628296D01*
X675123Y628796D01*
X674996Y629379D01*
X674553Y629796D01*
X674109Y629963D01*
X673539D01*
G01X674109D02*
X674489Y630213D01*
X674806Y630629D01*
X674933Y631129D01*
X674806Y631629D01*
X674489Y632046D01*
X673919Y632296D01*
X673349Y632213D01*
X672779Y631879D01*
G01X678766Y627129D02*
X678639Y627213D01*
Y627379D01*
X678766Y627463D01*
X678893Y627379D01*
Y627213D01*
X678766Y627129D01*
G01X683866Y632296D02*
X683359Y632129D01*
X682979Y631713D01*
X682726Y631213D01*
X682536Y630546D01*
X682473Y629796D01*
X682536Y629046D01*
X682726Y628379D01*
X682979Y627879D01*
X683359Y627463D01*
X683866Y627296D01*
X684373Y627463D01*
X684753Y627879D01*
X685006Y628379D01*
X685196Y629046D01*
X685259Y629796D01*
X685196Y630546D01*
X685006Y631213D01*
X684753Y631713D01*
X684373Y632129D01*
X683866Y632296D01*
G01X687826Y627129D02*
X690106Y632296D01*
G01X693243Y628963D02*
X694889D01*
G01X697773Y628296D02*
X698153Y627713D01*
X698659Y627379D01*
X699229Y627296D01*
X699736Y627379D01*
X700243Y627796D01*
X700559Y628296D01*
X700623Y628796D01*
X700496Y629379D01*
X700053Y629796D01*
X699609Y629963D01*
X699039D01*
G01X699609D02*
X699989Y630213D01*
X700306Y630629D01*
X700433Y631129D01*
X700306Y631629D01*
X699989Y632046D01*
X699419Y632296D01*
X698849Y632213D01*
X698279Y631879D01*
G01X704266Y627129D02*
X704139Y627213D01*
Y627379D01*
X704266Y627463D01*
X704393Y627379D01*
Y627213D01*
X704266Y627129D01*
G01X709366Y632296D02*
X708859Y632129D01*
X708479Y631713D01*
X708226Y631213D01*
X708036Y630546D01*
X707973Y629796D01*
X708036Y629046D01*
X708226Y628379D01*
X708479Y627879D01*
X708859Y627463D01*
X709366Y627296D01*
X709873Y627463D01*
X710253Y627879D01*
X710506Y628379D01*
X710696Y629046D01*
X710759Y629796D01*
X710696Y630546D01*
X710506Y631213D01*
X710253Y631713D01*
X709873Y632129D01*
X709366Y632296D01*
G01X667869Y676213D02*
X669389D01*
G01X668566Y677296D02*
Y675129D01*
G01X672273Y675546D02*
X672653Y674963D01*
X673159Y674629D01*
X673729Y674546D01*
X674236Y674629D01*
X674743Y675046D01*
X675059Y675546D01*
X675123Y676046D01*
X674996Y676629D01*
X674553Y677046D01*
X674109Y677213D01*
X673539D01*
G01X674109D02*
X674489Y677463D01*
X674806Y677879D01*
X674933Y678379D01*
X674806Y678879D01*
X674489Y679296D01*
X673919Y679546D01*
X673349Y679463D01*
X672779Y679129D01*
G01X678766Y674379D02*
X678639Y674463D01*
Y674629D01*
X678766Y674713D01*
X678893Y674629D01*
Y674463D01*
X678766Y674379D01*
G01X683866Y679546D02*
X683359Y679379D01*
X682979Y678963D01*
X682726Y678463D01*
X682536Y677796D01*
X682473Y677046D01*
X682536Y676296D01*
X682726Y675629D01*
X682979Y675129D01*
X683359Y674713D01*
X683866Y674546D01*
X684373Y674713D01*
X684753Y675129D01*
X685006Y675629D01*
X685196Y676296D01*
X685259Y677046D01*
X685196Y677796D01*
X685006Y678463D01*
X684753Y678963D01*
X684373Y679379D01*
X683866Y679546D01*
G01X687826Y674379D02*
X690106Y679546D01*
G01X693243Y676213D02*
X694889D01*
G01X697773Y675546D02*
X698153Y674963D01*
X698659Y674629D01*
X699229Y674546D01*
X699736Y674629D01*
X700243Y675046D01*
X700559Y675546D01*
X700623Y676046D01*
X700496Y676629D01*
X700053Y677046D01*
X699609Y677213D01*
X699039D01*
G01X699609D02*
X699989Y677463D01*
X700306Y677879D01*
X700433Y678379D01*
X700306Y678879D01*
X699989Y679296D01*
X699419Y679546D01*
X698849Y679463D01*
X698279Y679129D01*
G01X704266Y674379D02*
X704139Y674463D01*
Y674629D01*
X704266Y674713D01*
X704393Y674629D01*
Y674463D01*
X704266Y674379D01*
G01X709366Y679546D02*
X708859Y679379D01*
X708479Y678963D01*
X708226Y678463D01*
X708036Y677796D01*
X707973Y677046D01*
X708036Y676296D01*
X708226Y675629D01*
X708479Y675129D01*
X708859Y674713D01*
X709366Y674546D01*
X709873Y674713D01*
X710253Y675129D01*
X710506Y675629D01*
X710696Y676296D01*
X710759Y677046D01*
X710696Y677796D01*
X710506Y678463D01*
X710253Y678963D01*
X709873Y679379D01*
X709366Y679546D01*
G01X667869Y723463D02*
X669389D01*
G01X668566Y724546D02*
Y722379D01*
G01X672273Y722796D02*
X672653Y722213D01*
X673159Y721879D01*
X673729Y721796D01*
X674236Y721879D01*
X674743Y722296D01*
X675059Y722796D01*
X675123Y723296D01*
X674996Y723879D01*
X674553Y724296D01*
X674109Y724463D01*
X673539D01*
G01X674109D02*
X674489Y724713D01*
X674806Y725129D01*
X674933Y725629D01*
X674806Y726129D01*
X674489Y726546D01*
X673919Y726796D01*
X673349Y726713D01*
X672779Y726379D01*
G01X678766Y721629D02*
X678639Y721713D01*
Y721879D01*
X678766Y721963D01*
X678893Y721879D01*
Y721713D01*
X678766Y721629D01*
G01X683866Y726796D02*
X683359Y726629D01*
X682979Y726213D01*
X682726Y725713D01*
X682536Y725046D01*
X682473Y724296D01*
X682536Y723546D01*
X682726Y722879D01*
X682979Y722379D01*
X683359Y721963D01*
X683866Y721796D01*
X684373Y721963D01*
X684753Y722379D01*
X685006Y722879D01*
X685196Y723546D01*
X685259Y724296D01*
X685196Y725046D01*
X685006Y725713D01*
X684753Y726213D01*
X684373Y726629D01*
X683866Y726796D01*
G01X687826Y721629D02*
X690106Y726796D01*
G01X693243Y723463D02*
X694889D01*
G01X697773Y722796D02*
X698153Y722213D01*
X698659Y721879D01*
X699229Y721796D01*
X699736Y721879D01*
X700243Y722296D01*
X700559Y722796D01*
X700623Y723296D01*
X700496Y723879D01*
X700053Y724296D01*
X699609Y724463D01*
X699039D01*
G01X699609D02*
X699989Y724713D01*
X700306Y725129D01*
X700433Y725629D01*
X700306Y726129D01*
X699989Y726546D01*
X699419Y726796D01*
X698849Y726713D01*
X698279Y726379D01*
G01X704266Y721629D02*
X704139Y721713D01*
Y721879D01*
X704266Y721963D01*
X704393Y721879D01*
Y721713D01*
X704266Y721629D01*
G01X709366Y726796D02*
X708859Y726629D01*
X708479Y726213D01*
X708226Y725713D01*
X708036Y725046D01*
X707973Y724296D01*
X708036Y723546D01*
X708226Y722879D01*
X708479Y722379D01*
X708859Y721963D01*
X709366Y721796D01*
X709873Y721963D01*
X710253Y722379D01*
X710506Y722879D01*
X710696Y723546D01*
X710759Y724296D01*
X710696Y725046D01*
X710506Y725713D01*
X710253Y726213D01*
X709873Y726629D01*
X709366Y726796D01*
G01X667869Y770713D02*
X669389D01*
G01X668566Y771796D02*
Y769629D01*
G01X672463Y773213D02*
X672843Y773713D01*
X673286Y773963D01*
X673793Y774046D01*
X674426Y773879D01*
X674869Y773463D01*
X674996Y772963D01*
X674933Y772463D01*
X674679Y772046D01*
X673413Y771213D01*
X672843Y770629D01*
X672463Y769796D01*
X672336Y769046D01*
X674996D01*
G01X678766Y768879D02*
X678639Y768963D01*
Y769129D01*
X678766Y769213D01*
X678893Y769129D01*
Y768963D01*
X678766Y768879D01*
G01X683866Y774046D02*
X683359Y773879D01*
X682979Y773463D01*
X682726Y772963D01*
X682536Y772296D01*
X682473Y771546D01*
X682536Y770796D01*
X682726Y770129D01*
X682979Y769629D01*
X683359Y769213D01*
X683866Y769046D01*
X684373Y769213D01*
X684753Y769629D01*
X685006Y770129D01*
X685196Y770796D01*
X685259Y771546D01*
X685196Y772296D01*
X685006Y772963D01*
X684753Y773463D01*
X684373Y773879D01*
X683866Y774046D01*
G01X687826Y768879D02*
X690106Y774046D01*
G01X693243Y770713D02*
X694889D01*
G01X697963Y773213D02*
X698343Y773713D01*
X698786Y773963D01*
X699293Y774046D01*
X699926Y773879D01*
X700369Y773463D01*
X700496Y772963D01*
X700433Y772463D01*
X700179Y772046D01*
X698913Y771213D01*
X698343Y770629D01*
X697963Y769796D01*
X697836Y769046D01*
X700496D01*
G01X704266Y768879D02*
X704139Y768963D01*
Y769129D01*
X704266Y769213D01*
X704393Y769129D01*
Y768963D01*
X704266Y768879D01*
G01X709366Y774046D02*
X708859Y773879D01*
X708479Y773463D01*
X708226Y772963D01*
X708036Y772296D01*
X707973Y771546D01*
X708036Y770796D01*
X708226Y770129D01*
X708479Y769629D01*
X708859Y769213D01*
X709366Y769046D01*
X709873Y769213D01*
X710253Y769629D01*
X710506Y770129D01*
X710696Y770796D01*
X710759Y771546D01*
X710696Y772296D01*
X710506Y772963D01*
X710253Y773463D01*
X709873Y773879D01*
X709366Y774046D01*
G01X667869Y817963D02*
X669389D01*
G01X668566Y819046D02*
Y816879D01*
G01X672463Y820463D02*
X672843Y820963D01*
X673286Y821213D01*
X673793Y821296D01*
X674426Y821129D01*
X674869Y820713D01*
X674996Y820213D01*
X674933Y819713D01*
X674679Y819296D01*
X673413Y818463D01*
X672843Y817879D01*
X672463Y817046D01*
X672336Y816296D01*
X674996D01*
G01X678766Y816129D02*
X678639Y816213D01*
Y816379D01*
X678766Y816463D01*
X678893Y816379D01*
Y816213D01*
X678766Y816129D01*
G01X683866Y821296D02*
X683359Y821129D01*
X682979Y820713D01*
X682726Y820213D01*
X682536Y819546D01*
X682473Y818796D01*
X682536Y818046D01*
X682726Y817379D01*
X682979Y816879D01*
X683359Y816463D01*
X683866Y816296D01*
X684373Y816463D01*
X684753Y816879D01*
X685006Y817379D01*
X685196Y818046D01*
X685259Y818796D01*
X685196Y819546D01*
X685006Y820213D01*
X684753Y820713D01*
X684373Y821129D01*
X683866Y821296D01*
G01X687826Y816129D02*
X690106Y821296D01*
G01X693243Y817963D02*
X694889D01*
G01X697963Y820463D02*
X698343Y820963D01*
X698786Y821213D01*
X699293Y821296D01*
X699926Y821129D01*
X700369Y820713D01*
X700496Y820213D01*
X700433Y819713D01*
X700179Y819296D01*
X698913Y818463D01*
X698343Y817879D01*
X697963Y817046D01*
X697836Y816296D01*
X700496D01*
G01X704266Y816129D02*
X704139Y816213D01*
Y816379D01*
X704266Y816463D01*
X704393Y816379D01*
Y816213D01*
X704266Y816129D01*
G01X709366Y821296D02*
X708859Y821129D01*
X708479Y820713D01*
X708226Y820213D01*
X708036Y819546D01*
X707973Y818796D01*
X708036Y818046D01*
X708226Y817379D01*
X708479Y816879D01*
X708859Y816463D01*
X709366Y816296D01*
X709873Y816463D01*
X710253Y816879D01*
X710506Y817379D01*
X710696Y818046D01*
X710759Y818796D01*
X710696Y819546D01*
X710506Y820213D01*
X710253Y820713D01*
X709873Y821129D01*
X709366Y821296D01*
G01X667869Y865213D02*
X669389D01*
G01X668566Y866296D02*
Y864129D01*
G01X672273Y864546D02*
X672653Y863963D01*
X673159Y863629D01*
X673729Y863546D01*
X674236Y863629D01*
X674743Y864046D01*
X675059Y864546D01*
X675123Y865046D01*
X674996Y865629D01*
X674553Y866046D01*
X674109Y866213D01*
X673539D01*
G01X674109D02*
X674489Y866463D01*
X674806Y866879D01*
X674933Y867379D01*
X674806Y867879D01*
X674489Y868296D01*
X673919Y868546D01*
X673349Y868463D01*
X672779Y868129D01*
G01X678766Y863379D02*
X678639Y863463D01*
Y863629D01*
X678766Y863713D01*
X678893Y863629D01*
Y863463D01*
X678766Y863379D01*
G01X683866Y868546D02*
X683359Y868379D01*
X682979Y867963D01*
X682726Y867463D01*
X682536Y866796D01*
X682473Y866046D01*
X682536Y865296D01*
X682726Y864629D01*
X682979Y864129D01*
X683359Y863713D01*
X683866Y863546D01*
X684373Y863713D01*
X684753Y864129D01*
X685006Y864629D01*
X685196Y865296D01*
X685259Y866046D01*
X685196Y866796D01*
X685006Y867463D01*
X684753Y867963D01*
X684373Y868379D01*
X683866Y868546D01*
G01X687826Y863379D02*
X690106Y868546D01*
G01X693243Y865213D02*
X694889D01*
G01X697773Y864546D02*
X698153Y863963D01*
X698659Y863629D01*
X699229Y863546D01*
X699736Y863629D01*
X700243Y864046D01*
X700559Y864546D01*
X700623Y865046D01*
X700496Y865629D01*
X700053Y866046D01*
X699609Y866213D01*
X699039D01*
G01X699609D02*
X699989Y866463D01*
X700306Y866879D01*
X700433Y867379D01*
X700306Y867879D01*
X699989Y868296D01*
X699419Y868546D01*
X698849Y868463D01*
X698279Y868129D01*
G01X704266Y863379D02*
X704139Y863463D01*
Y863629D01*
X704266Y863713D01*
X704393Y863629D01*
Y863463D01*
X704266Y863379D01*
G01X709366Y868546D02*
X708859Y868379D01*
X708479Y867963D01*
X708226Y867463D01*
X708036Y866796D01*
X707973Y866046D01*
X708036Y865296D01*
X708226Y864629D01*
X708479Y864129D01*
X708859Y863713D01*
X709366Y863546D01*
X709873Y863713D01*
X710253Y864129D01*
X710506Y864629D01*
X710696Y865296D01*
X710759Y866046D01*
X710696Y866796D01*
X710506Y867463D01*
X710253Y867963D01*
X709873Y868379D01*
X709366Y868546D01*
G01X667869Y912463D02*
X669389D01*
G01X668566Y913546D02*
Y911379D01*
G01X672273Y911796D02*
X672653Y911213D01*
X673159Y910879D01*
X673729Y910796D01*
X674236Y910879D01*
X674743Y911296D01*
X675059Y911796D01*
X675123Y912296D01*
X674996Y912879D01*
X674553Y913296D01*
X674109Y913463D01*
X673539D01*
G01X674109D02*
X674489Y913713D01*
X674806Y914129D01*
X674933Y914629D01*
X674806Y915129D01*
X674489Y915546D01*
X673919Y915796D01*
X673349Y915713D01*
X672779Y915379D01*
G01X678766Y910629D02*
X678639Y910713D01*
Y910879D01*
X678766Y910963D01*
X678893Y910879D01*
Y910713D01*
X678766Y910629D01*
G01X683866Y915796D02*
X683359Y915629D01*
X682979Y915213D01*
X682726Y914713D01*
X682536Y914046D01*
X682473Y913296D01*
X682536Y912546D01*
X682726Y911879D01*
X682979Y911379D01*
X683359Y910963D01*
X683866Y910796D01*
X684373Y910963D01*
X684753Y911379D01*
X685006Y911879D01*
X685196Y912546D01*
X685259Y913296D01*
X685196Y914046D01*
X685006Y914713D01*
X684753Y915213D01*
X684373Y915629D01*
X683866Y915796D01*
G01X687826Y910629D02*
X690106Y915796D01*
G01X693243Y912463D02*
X694889D01*
G01X697773Y911796D02*
X698153Y911213D01*
X698659Y910879D01*
X699229Y910796D01*
X699736Y910879D01*
X700243Y911296D01*
X700559Y911796D01*
X700623Y912296D01*
X700496Y912879D01*
X700053Y913296D01*
X699609Y913463D01*
X699039D01*
G01X699609D02*
X699989Y913713D01*
X700306Y914129D01*
X700433Y914629D01*
X700306Y915129D01*
X699989Y915546D01*
X699419Y915796D01*
X698849Y915713D01*
X698279Y915379D01*
G01X704266Y910629D02*
X704139Y910713D01*
Y910879D01*
X704266Y910963D01*
X704393Y910879D01*
Y910713D01*
X704266Y910629D01*
G01X709366Y915796D02*
X708859Y915629D01*
X708479Y915213D01*
X708226Y914713D01*
X708036Y914046D01*
X707973Y913296D01*
X708036Y912546D01*
X708226Y911879D01*
X708479Y911379D01*
X708859Y910963D01*
X709366Y910796D01*
X709873Y910963D01*
X710253Y911379D01*
X710506Y911879D01*
X710696Y912546D01*
X710759Y913296D01*
X710696Y914046D01*
X710506Y914713D01*
X710253Y915213D01*
X709873Y915629D01*
X709366Y915796D01*
G01X667869Y959713D02*
X669389D01*
G01X668566Y960796D02*
Y958629D01*
G01X672273Y959046D02*
X672653Y958463D01*
X673159Y958129D01*
X673729Y958046D01*
X674236Y958129D01*
X674743Y958546D01*
X675059Y959046D01*
X675123Y959546D01*
X674996Y960129D01*
X674553Y960546D01*
X674109Y960713D01*
X673539D01*
G01X674109D02*
X674489Y960963D01*
X674806Y961379D01*
X674933Y961879D01*
X674806Y962379D01*
X674489Y962796D01*
X673919Y963046D01*
X673349Y962963D01*
X672779Y962629D01*
G01X678766Y957879D02*
X678639Y957963D01*
Y958129D01*
X678766Y958213D01*
X678893Y958129D01*
Y957963D01*
X678766Y957879D01*
G01X683866Y963046D02*
X683359Y962879D01*
X682979Y962463D01*
X682726Y961963D01*
X682536Y961296D01*
X682473Y960546D01*
X682536Y959796D01*
X682726Y959129D01*
X682979Y958629D01*
X683359Y958213D01*
X683866Y958046D01*
X684373Y958213D01*
X684753Y958629D01*
X685006Y959129D01*
X685196Y959796D01*
X685259Y960546D01*
X685196Y961296D01*
X685006Y961963D01*
X684753Y962463D01*
X684373Y962879D01*
X683866Y963046D01*
G01X687826Y957879D02*
X690106Y963046D01*
G01X693243Y959713D02*
X694889D01*
G01X697773Y959046D02*
X698153Y958463D01*
X698659Y958129D01*
X699229Y958046D01*
X699736Y958129D01*
X700243Y958546D01*
X700559Y959046D01*
X700623Y959546D01*
X700496Y960129D01*
X700053Y960546D01*
X699609Y960713D01*
X699039D01*
G01X699609D02*
X699989Y960963D01*
X700306Y961379D01*
X700433Y961879D01*
X700306Y962379D01*
X699989Y962796D01*
X699419Y963046D01*
X698849Y962963D01*
X698279Y962629D01*
G01X704266Y957879D02*
X704139Y957963D01*
Y958129D01*
X704266Y958213D01*
X704393Y958129D01*
Y957963D01*
X704266Y957879D01*
G01X709366Y963046D02*
X708859Y962879D01*
X708479Y962463D01*
X708226Y961963D01*
X708036Y961296D01*
X707973Y960546D01*
X708036Y959796D01*
X708226Y959129D01*
X708479Y958629D01*
X708859Y958213D01*
X709366Y958046D01*
X709873Y958213D01*
X710253Y958629D01*
X710506Y959129D01*
X710696Y959796D01*
X710759Y960546D01*
X710696Y961296D01*
X710506Y961963D01*
X710253Y962463D01*
X709873Y962879D01*
X709366Y963046D01*
G01X668566Y992971D02*
Y987971D01*
G01X667109Y992971D02*
X670023D01*
G01X673666Y987971D02*
X673159Y988054D01*
X672716Y988388D01*
X672336Y988888D01*
X672083Y989471D01*
X671956Y990138D01*
Y990804D01*
X672083Y991471D01*
X672336Y992054D01*
X672716Y992554D01*
X673159Y992888D01*
X673666Y992971D01*
X674173Y992888D01*
X674616Y992554D01*
X674996Y992054D01*
X675249Y991471D01*
X675376Y990804D01*
Y990138D01*
X675249Y989471D01*
X674996Y988888D01*
X674616Y988388D01*
X674173Y988054D01*
X673666Y987971D01*
G01X677499Y992971D02*
Y987971D01*
X680033D01*
G01X685133D02*
X682599D01*
Y992971D01*
X685133D01*
G01X684119Y990554D02*
X682599D01*
G01X687699Y987971D02*
Y992971D01*
X689283D01*
X689789Y992721D01*
X690106Y992388D01*
X690233Y991721D01*
X690106Y991054D01*
X689726Y990638D01*
X689283Y990388D01*
X687699D01*
G01X689283D02*
X690233Y987971D01*
G01X692483D02*
X694066Y992971D01*
X695649Y987971D01*
G01X695079Y989721D02*
X693053D01*
G01X697709Y987971D02*
Y992971D01*
X700623Y987971D01*
Y992971D01*
G01X705659Y992554D02*
X705279Y992804D01*
X704836Y992971D01*
X704329D01*
X703759Y992721D01*
X703316Y992304D01*
X702999Y991804D01*
X702746Y990971D01*
X702683Y990221D01*
X702809Y989471D01*
X702999Y988971D01*
X703379Y988471D01*
X703823Y988138D01*
X704266Y987971D01*
X704709D01*
X705153Y988138D01*
X705533Y988388D01*
X705849Y988721D01*
G01X710633Y987971D02*
X708099D01*
Y992971D01*
X710633D01*
G01X709619Y990554D02*
X708099D01*
G01X729609Y60296D02*
Y65296D01*
X732523Y60296D01*
Y65296D01*
G01X736166Y60296D02*
X735659Y60379D01*
X735216Y60713D01*
X734836Y61213D01*
X734583Y61796D01*
X734456Y62463D01*
Y63129D01*
X734583Y63796D01*
X734836Y64379D01*
X735216Y64879D01*
X735659Y65213D01*
X736166Y65296D01*
X736673Y65213D01*
X737116Y64879D01*
X737496Y64379D01*
X737749Y63796D01*
X737876Y63129D01*
Y62463D01*
X737749Y61796D01*
X737496Y61213D01*
X737116Y60713D01*
X736673Y60379D01*
X736166Y60296D01*
G01X739809D02*
Y65296D01*
X742723Y60296D01*
Y65296D01*
G01X745543Y61963D02*
X747189D01*
G01X750199Y60296D02*
Y65296D01*
X751719D01*
X752226Y65046D01*
X752606Y64463D01*
X752733Y63796D01*
X752606Y63129D01*
X752289Y62629D01*
X751719Y62379D01*
X750199D01*
G01X755299Y65296D02*
Y60296D01*
X757833D01*
G01X760083D02*
X761666Y65296D01*
X763249Y60296D01*
G01X762679Y62046D02*
X760653D01*
G01X766766Y65296D02*
Y60296D01*
G01X765309Y65296D02*
X768223D01*
G01X773133Y60296D02*
X770599D01*
Y65296D01*
X773133D01*
G01X772119Y62879D02*
X770599D01*
G01X775573Y60296D02*
Y65296D01*
X776839D01*
X777346Y65046D01*
X777726Y64713D01*
X778043Y64213D01*
X778296Y63629D01*
X778359Y62796D01*
X778296Y61963D01*
X778043Y61379D01*
X777726Y60879D01*
X777346Y60546D01*
X776839Y60296D01*
X775573D01*
G01X729609Y107546D02*
Y112546D01*
X732523Y107546D01*
Y112546D01*
G01X736166Y107546D02*
X735659Y107629D01*
X735216Y107963D01*
X734836Y108463D01*
X734583Y109046D01*
X734456Y109713D01*
Y110379D01*
X734583Y111046D01*
X734836Y111629D01*
X735216Y112129D01*
X735659Y112463D01*
X736166Y112546D01*
X736673Y112463D01*
X737116Y112129D01*
X737496Y111629D01*
X737749Y111046D01*
X737876Y110379D01*
Y109713D01*
X737749Y109046D01*
X737496Y108463D01*
X737116Y107963D01*
X736673Y107629D01*
X736166Y107546D01*
G01X739809D02*
Y112546D01*
X742723Y107546D01*
Y112546D01*
G01X745543Y109213D02*
X747189D01*
G01X750199Y107546D02*
Y112546D01*
X751719D01*
X752226Y112296D01*
X752606Y111713D01*
X752733Y111046D01*
X752606Y110379D01*
X752289Y109879D01*
X751719Y109629D01*
X750199D01*
G01X755299Y112546D02*
Y107546D01*
X757833D01*
G01X760083D02*
X761666Y112546D01*
X763249Y107546D01*
G01X762679Y109296D02*
X760653D01*
G01X766766Y112546D02*
Y107546D01*
G01X765309Y112546D02*
X768223D01*
G01X773133Y107546D02*
X770599D01*
Y112546D01*
X773133D01*
G01X772119Y110129D02*
X770599D01*
G01X775573Y107546D02*
Y112546D01*
X776839D01*
X777346Y112296D01*
X777726Y111963D01*
X778043Y111463D01*
X778296Y110879D01*
X778359Y110046D01*
X778296Y109213D01*
X778043Y108629D01*
X777726Y108129D01*
X777346Y107796D01*
X776839Y107546D01*
X775573D01*
G01X729609Y154796D02*
Y159796D01*
X732523Y154796D01*
Y159796D01*
G01X736166Y154796D02*
X735659Y154879D01*
X735216Y155213D01*
X734836Y155713D01*
X734583Y156296D01*
X734456Y156963D01*
Y157629D01*
X734583Y158296D01*
X734836Y158879D01*
X735216Y159379D01*
X735659Y159713D01*
X736166Y159796D01*
X736673Y159713D01*
X737116Y159379D01*
X737496Y158879D01*
X737749Y158296D01*
X737876Y157629D01*
Y156963D01*
X737749Y156296D01*
X737496Y155713D01*
X737116Y155213D01*
X736673Y154879D01*
X736166Y154796D01*
G01X739809D02*
Y159796D01*
X742723Y154796D01*
Y159796D01*
G01X745543Y156463D02*
X747189D01*
G01X750199Y154796D02*
Y159796D01*
X751719D01*
X752226Y159546D01*
X752606Y158963D01*
X752733Y158296D01*
X752606Y157629D01*
X752289Y157129D01*
X751719Y156879D01*
X750199D01*
G01X755299Y159796D02*
Y154796D01*
X757833D01*
G01X760083D02*
X761666Y159796D01*
X763249Y154796D01*
G01X762679Y156546D02*
X760653D01*
G01X766766Y159796D02*
Y154796D01*
G01X765309Y159796D02*
X768223D01*
G01X773133Y154796D02*
X770599D01*
Y159796D01*
X773133D01*
G01X772119Y157379D02*
X770599D01*
G01X775573Y154796D02*
Y159796D01*
X776839D01*
X777346Y159546D01*
X777726Y159213D01*
X778043Y158713D01*
X778296Y158129D01*
X778359Y157296D01*
X778296Y156463D01*
X778043Y155879D01*
X777726Y155379D01*
X777346Y155046D01*
X776839Y154796D01*
X775573D01*
G01X729609Y202046D02*
Y207046D01*
X732523Y202046D01*
Y207046D01*
G01X736166Y202046D02*
X735659Y202129D01*
X735216Y202463D01*
X734836Y202963D01*
X734583Y203546D01*
X734456Y204213D01*
Y204879D01*
X734583Y205546D01*
X734836Y206129D01*
X735216Y206629D01*
X735659Y206963D01*
X736166Y207046D01*
X736673Y206963D01*
X737116Y206629D01*
X737496Y206129D01*
X737749Y205546D01*
X737876Y204879D01*
Y204213D01*
X737749Y203546D01*
X737496Y202963D01*
X737116Y202463D01*
X736673Y202129D01*
X736166Y202046D01*
G01X739809D02*
Y207046D01*
X742723Y202046D01*
Y207046D01*
G01X745543Y203713D02*
X747189D01*
G01X750199Y202046D02*
Y207046D01*
X751719D01*
X752226Y206796D01*
X752606Y206213D01*
X752733Y205546D01*
X752606Y204879D01*
X752289Y204379D01*
X751719Y204129D01*
X750199D01*
G01X755299Y207046D02*
Y202046D01*
X757833D01*
G01X760083D02*
X761666Y207046D01*
X763249Y202046D01*
G01X762679Y203796D02*
X760653D01*
G01X766766Y207046D02*
Y202046D01*
G01X765309Y207046D02*
X768223D01*
G01X773133Y202046D02*
X770599D01*
Y207046D01*
X773133D01*
G01X772119Y204629D02*
X770599D01*
G01X775573Y202046D02*
Y207046D01*
X776839D01*
X777346Y206796D01*
X777726Y206463D01*
X778043Y205963D01*
X778296Y205379D01*
X778359Y204546D01*
X778296Y203713D01*
X778043Y203129D01*
X777726Y202629D01*
X777346Y202296D01*
X776839Y202046D01*
X775573D01*
G01X729609Y249296D02*
Y254296D01*
X732523Y249296D01*
Y254296D01*
G01X736166Y249296D02*
X735659Y249379D01*
X735216Y249713D01*
X734836Y250213D01*
X734583Y250796D01*
X734456Y251463D01*
Y252129D01*
X734583Y252796D01*
X734836Y253379D01*
X735216Y253879D01*
X735659Y254213D01*
X736166Y254296D01*
X736673Y254213D01*
X737116Y253879D01*
X737496Y253379D01*
X737749Y252796D01*
X737876Y252129D01*
Y251463D01*
X737749Y250796D01*
X737496Y250213D01*
X737116Y249713D01*
X736673Y249379D01*
X736166Y249296D01*
G01X739809D02*
Y254296D01*
X742723Y249296D01*
Y254296D01*
G01X745543Y250963D02*
X747189D01*
G01X750199Y249296D02*
Y254296D01*
X751719D01*
X752226Y254046D01*
X752606Y253463D01*
X752733Y252796D01*
X752606Y252129D01*
X752289Y251629D01*
X751719Y251379D01*
X750199D01*
G01X755299Y254296D02*
Y249296D01*
X757833D01*
G01X760083D02*
X761666Y254296D01*
X763249Y249296D01*
G01X762679Y251046D02*
X760653D01*
G01X766766Y254296D02*
Y249296D01*
G01X765309Y254296D02*
X768223D01*
G01X773133Y249296D02*
X770599D01*
Y254296D01*
X773133D01*
G01X772119Y251879D02*
X770599D01*
G01X775573Y249296D02*
Y254296D01*
X776839D01*
X777346Y254046D01*
X777726Y253713D01*
X778043Y253213D01*
X778296Y252629D01*
X778359Y251796D01*
X778296Y250963D01*
X778043Y250379D01*
X777726Y249879D01*
X777346Y249546D01*
X776839Y249296D01*
X775573D01*
G01X729609Y296546D02*
Y301546D01*
X732523Y296546D01*
Y301546D01*
G01X736166Y296546D02*
X735659Y296629D01*
X735216Y296963D01*
X734836Y297463D01*
X734583Y298046D01*
X734456Y298713D01*
Y299379D01*
X734583Y300046D01*
X734836Y300629D01*
X735216Y301129D01*
X735659Y301463D01*
X736166Y301546D01*
X736673Y301463D01*
X737116Y301129D01*
X737496Y300629D01*
X737749Y300046D01*
X737876Y299379D01*
Y298713D01*
X737749Y298046D01*
X737496Y297463D01*
X737116Y296963D01*
X736673Y296629D01*
X736166Y296546D01*
G01X739809D02*
Y301546D01*
X742723Y296546D01*
Y301546D01*
G01X745543Y298213D02*
X747189D01*
G01X750199Y296546D02*
Y301546D01*
X751719D01*
X752226Y301296D01*
X752606Y300713D01*
X752733Y300046D01*
X752606Y299379D01*
X752289Y298879D01*
X751719Y298629D01*
X750199D01*
G01X755299Y301546D02*
Y296546D01*
X757833D01*
G01X760083D02*
X761666Y301546D01*
X763249Y296546D01*
G01X762679Y298296D02*
X760653D01*
G01X766766Y301546D02*
Y296546D01*
G01X765309Y301546D02*
X768223D01*
G01X773133Y296546D02*
X770599D01*
Y301546D01*
X773133D01*
G01X772119Y299129D02*
X770599D01*
G01X775573Y296546D02*
Y301546D01*
X776839D01*
X777346Y301296D01*
X777726Y300963D01*
X778043Y300463D01*
X778296Y299879D01*
X778359Y299046D01*
X778296Y298213D01*
X778043Y297629D01*
X777726Y297129D01*
X777346Y296796D01*
X776839Y296546D01*
X775573D01*
G01X729609Y343796D02*
Y348796D01*
X732523Y343796D01*
Y348796D01*
G01X736166Y343796D02*
X735659Y343879D01*
X735216Y344213D01*
X734836Y344713D01*
X734583Y345296D01*
X734456Y345963D01*
Y346629D01*
X734583Y347296D01*
X734836Y347879D01*
X735216Y348379D01*
X735659Y348713D01*
X736166Y348796D01*
X736673Y348713D01*
X737116Y348379D01*
X737496Y347879D01*
X737749Y347296D01*
X737876Y346629D01*
Y345963D01*
X737749Y345296D01*
X737496Y344713D01*
X737116Y344213D01*
X736673Y343879D01*
X736166Y343796D01*
G01X739809D02*
Y348796D01*
X742723Y343796D01*
Y348796D01*
G01X745543Y345463D02*
X747189D01*
G01X750199Y343796D02*
Y348796D01*
X751719D01*
X752226Y348546D01*
X752606Y347963D01*
X752733Y347296D01*
X752606Y346629D01*
X752289Y346129D01*
X751719Y345879D01*
X750199D01*
G01X755299Y348796D02*
Y343796D01*
X757833D01*
G01X760083D02*
X761666Y348796D01*
X763249Y343796D01*
G01X762679Y345546D02*
X760653D01*
G01X766766Y348796D02*
Y343796D01*
G01X765309Y348796D02*
X768223D01*
G01X773133Y343796D02*
X770599D01*
Y348796D01*
X773133D01*
G01X772119Y346379D02*
X770599D01*
G01X775573Y343796D02*
Y348796D01*
X776839D01*
X777346Y348546D01*
X777726Y348213D01*
X778043Y347713D01*
X778296Y347129D01*
X778359Y346296D01*
X778296Y345463D01*
X778043Y344879D01*
X777726Y344379D01*
X777346Y344046D01*
X776839Y343796D01*
X775573D01*
G01X729609Y391046D02*
Y396046D01*
X732523Y391046D01*
Y396046D01*
G01X736166Y391046D02*
X735659Y391129D01*
X735216Y391463D01*
X734836Y391963D01*
X734583Y392546D01*
X734456Y393213D01*
Y393879D01*
X734583Y394546D01*
X734836Y395129D01*
X735216Y395629D01*
X735659Y395963D01*
X736166Y396046D01*
X736673Y395963D01*
X737116Y395629D01*
X737496Y395129D01*
X737749Y394546D01*
X737876Y393879D01*
Y393213D01*
X737749Y392546D01*
X737496Y391963D01*
X737116Y391463D01*
X736673Y391129D01*
X736166Y391046D01*
G01X739809D02*
Y396046D01*
X742723Y391046D01*
Y396046D01*
G01X745543Y392713D02*
X747189D01*
G01X750199Y391046D02*
Y396046D01*
X751719D01*
X752226Y395796D01*
X752606Y395213D01*
X752733Y394546D01*
X752606Y393879D01*
X752289Y393379D01*
X751719Y393129D01*
X750199D01*
G01X755299Y396046D02*
Y391046D01*
X757833D01*
G01X760083D02*
X761666Y396046D01*
X763249Y391046D01*
G01X762679Y392796D02*
X760653D01*
G01X766766Y396046D02*
Y391046D01*
G01X765309Y396046D02*
X768223D01*
G01X773133Y391046D02*
X770599D01*
Y396046D01*
X773133D01*
G01X772119Y393629D02*
X770599D01*
G01X775573Y391046D02*
Y396046D01*
X776839D01*
X777346Y395796D01*
X777726Y395463D01*
X778043Y394963D01*
X778296Y394379D01*
X778359Y393546D01*
X778296Y392713D01*
X778043Y392129D01*
X777726Y391629D01*
X777346Y391296D01*
X776839Y391046D01*
X775573D01*
G01X729609Y438296D02*
Y443296D01*
X732523Y438296D01*
Y443296D01*
G01X736166Y438296D02*
X735659Y438379D01*
X735216Y438713D01*
X734836Y439213D01*
X734583Y439796D01*
X734456Y440463D01*
Y441129D01*
X734583Y441796D01*
X734836Y442379D01*
X735216Y442879D01*
X735659Y443213D01*
X736166Y443296D01*
X736673Y443213D01*
X737116Y442879D01*
X737496Y442379D01*
X737749Y441796D01*
X737876Y441129D01*
Y440463D01*
X737749Y439796D01*
X737496Y439213D01*
X737116Y438713D01*
X736673Y438379D01*
X736166Y438296D01*
G01X739809D02*
Y443296D01*
X742723Y438296D01*
Y443296D01*
G01X745543Y439963D02*
X747189D01*
G01X750199Y438296D02*
Y443296D01*
X751719D01*
X752226Y443046D01*
X752606Y442463D01*
X752733Y441796D01*
X752606Y441129D01*
X752289Y440629D01*
X751719Y440379D01*
X750199D01*
G01X755299Y443296D02*
Y438296D01*
X757833D01*
G01X760083D02*
X761666Y443296D01*
X763249Y438296D01*
G01X762679Y440046D02*
X760653D01*
G01X766766Y443296D02*
Y438296D01*
G01X765309Y443296D02*
X768223D01*
G01X773133Y438296D02*
X770599D01*
Y443296D01*
X773133D01*
G01X772119Y440879D02*
X770599D01*
G01X775573Y438296D02*
Y443296D01*
X776839D01*
X777346Y443046D01*
X777726Y442713D01*
X778043Y442213D01*
X778296Y441629D01*
X778359Y440796D01*
X778296Y439963D01*
X778043Y439379D01*
X777726Y438879D01*
X777346Y438546D01*
X776839Y438296D01*
X775573D01*
G01X739999Y485546D02*
Y490546D01*
X741519D01*
X742026Y490296D01*
X742406Y489713D01*
X742533Y489046D01*
X742406Y488379D01*
X742089Y487879D01*
X741519Y487629D01*
X739999D01*
G01X745099Y490546D02*
Y485546D01*
X747633D01*
G01X749883D02*
X751466Y490546D01*
X753049Y485546D01*
G01X752479Y487296D02*
X750453D01*
G01X756566Y490546D02*
Y485546D01*
G01X755109Y490546D02*
X758023D01*
G01X762933Y485546D02*
X760399D01*
Y490546D01*
X762933D01*
G01X761919Y488129D02*
X760399D01*
G01X765373Y485546D02*
Y490546D01*
X766639D01*
X767146Y490296D01*
X767526Y489963D01*
X767843Y489463D01*
X768096Y488879D01*
X768159Y488046D01*
X768096Y487213D01*
X767843Y486629D01*
X767526Y486129D01*
X767146Y485796D01*
X766639Y485546D01*
X765373D01*
G01X739999Y532796D02*
Y537796D01*
X741519D01*
X742026Y537546D01*
X742406Y536963D01*
X742533Y536296D01*
X742406Y535629D01*
X742089Y535129D01*
X741519Y534879D01*
X739999D01*
G01X745099Y537796D02*
Y532796D01*
X747633D01*
G01X749883D02*
X751466Y537796D01*
X753049Y532796D01*
G01X752479Y534546D02*
X750453D01*
G01X756566Y537796D02*
Y532796D01*
G01X755109Y537796D02*
X758023D01*
G01X762933Y532796D02*
X760399D01*
Y537796D01*
X762933D01*
G01X761919Y535379D02*
X760399D01*
G01X765373Y532796D02*
Y537796D01*
X766639D01*
X767146Y537546D01*
X767526Y537213D01*
X767843Y536713D01*
X768096Y536129D01*
X768159Y535296D01*
X768096Y534463D01*
X767843Y533879D01*
X767526Y533379D01*
X767146Y533046D01*
X766639Y532796D01*
X765373D01*
G01X739999Y580046D02*
Y585046D01*
X741519D01*
X742026Y584796D01*
X742406Y584213D01*
X742533Y583546D01*
X742406Y582879D01*
X742089Y582379D01*
X741519Y582129D01*
X739999D01*
G01X745099Y585046D02*
Y580046D01*
X747633D01*
G01X749883D02*
X751466Y585046D01*
X753049Y580046D01*
G01X752479Y581796D02*
X750453D01*
G01X756566Y585046D02*
Y580046D01*
G01X755109Y585046D02*
X758023D01*
G01X762933Y580046D02*
X760399D01*
Y585046D01*
X762933D01*
G01X761919Y582629D02*
X760399D01*
G01X765373Y580046D02*
Y585046D01*
X766639D01*
X767146Y584796D01*
X767526Y584463D01*
X767843Y583963D01*
X768096Y583379D01*
X768159Y582546D01*
X768096Y581713D01*
X767843Y581129D01*
X767526Y580629D01*
X767146Y580296D01*
X766639Y580046D01*
X765373D01*
G01X739999Y627296D02*
Y632296D01*
X741519D01*
X742026Y632046D01*
X742406Y631463D01*
X742533Y630796D01*
X742406Y630129D01*
X742089Y629629D01*
X741519Y629379D01*
X739999D01*
G01X745099Y632296D02*
Y627296D01*
X747633D01*
G01X749883D02*
X751466Y632296D01*
X753049Y627296D01*
G01X752479Y629046D02*
X750453D01*
G01X756566Y632296D02*
Y627296D01*
G01X755109Y632296D02*
X758023D01*
G01X762933Y627296D02*
X760399D01*
Y632296D01*
X762933D01*
G01X761919Y629879D02*
X760399D01*
G01X765373Y627296D02*
Y632296D01*
X766639D01*
X767146Y632046D01*
X767526Y631713D01*
X767843Y631213D01*
X768096Y630629D01*
X768159Y629796D01*
X768096Y628963D01*
X767843Y628379D01*
X767526Y627879D01*
X767146Y627546D01*
X766639Y627296D01*
X765373D01*
G01X739999Y674546D02*
Y679546D01*
X741519D01*
X742026Y679296D01*
X742406Y678713D01*
X742533Y678046D01*
X742406Y677379D01*
X742089Y676879D01*
X741519Y676629D01*
X739999D01*
G01X745099Y679546D02*
Y674546D01*
X747633D01*
G01X749883D02*
X751466Y679546D01*
X753049Y674546D01*
G01X752479Y676296D02*
X750453D01*
G01X756566Y679546D02*
Y674546D01*
G01X755109Y679546D02*
X758023D01*
G01X762933Y674546D02*
X760399D01*
Y679546D01*
X762933D01*
G01X761919Y677129D02*
X760399D01*
G01X765373Y674546D02*
Y679546D01*
X766639D01*
X767146Y679296D01*
X767526Y678963D01*
X767843Y678463D01*
X768096Y677879D01*
X768159Y677046D01*
X768096Y676213D01*
X767843Y675629D01*
X767526Y675129D01*
X767146Y674796D01*
X766639Y674546D01*
X765373D01*
G01X739999Y721796D02*
Y726796D01*
X741519D01*
X742026Y726546D01*
X742406Y725963D01*
X742533Y725296D01*
X742406Y724629D01*
X742089Y724129D01*
X741519Y723879D01*
X739999D01*
G01X745099Y726796D02*
Y721796D01*
X747633D01*
G01X749883D02*
X751466Y726796D01*
X753049Y721796D01*
G01X752479Y723546D02*
X750453D01*
G01X756566Y726796D02*
Y721796D01*
G01X755109Y726796D02*
X758023D01*
G01X762933Y721796D02*
X760399D01*
Y726796D01*
X762933D01*
G01X761919Y724379D02*
X760399D01*
G01X765373Y721796D02*
Y726796D01*
X766639D01*
X767146Y726546D01*
X767526Y726213D01*
X767843Y725713D01*
X768096Y725129D01*
X768159Y724296D01*
X768096Y723463D01*
X767843Y722879D01*
X767526Y722379D01*
X767146Y722046D01*
X766639Y721796D01*
X765373D01*
G01X739999Y769046D02*
Y774046D01*
X741519D01*
X742026Y773796D01*
X742406Y773213D01*
X742533Y772546D01*
X742406Y771879D01*
X742089Y771379D01*
X741519Y771129D01*
X739999D01*
G01X745099Y774046D02*
Y769046D01*
X747633D01*
G01X749883D02*
X751466Y774046D01*
X753049Y769046D01*
G01X752479Y770796D02*
X750453D01*
G01X756566Y774046D02*
Y769046D01*
G01X755109Y774046D02*
X758023D01*
G01X762933Y769046D02*
X760399D01*
Y774046D01*
X762933D01*
G01X761919Y771629D02*
X760399D01*
G01X765373Y769046D02*
Y774046D01*
X766639D01*
X767146Y773796D01*
X767526Y773463D01*
X767843Y772963D01*
X768096Y772379D01*
X768159Y771546D01*
X768096Y770713D01*
X767843Y770129D01*
X767526Y769629D01*
X767146Y769296D01*
X766639Y769046D01*
X765373D01*
G01X739999Y816296D02*
Y821296D01*
X741519D01*
X742026Y821046D01*
X742406Y820463D01*
X742533Y819796D01*
X742406Y819129D01*
X742089Y818629D01*
X741519Y818379D01*
X739999D01*
G01X745099Y821296D02*
Y816296D01*
X747633D01*
G01X749883D02*
X751466Y821296D01*
X753049Y816296D01*
G01X752479Y818046D02*
X750453D01*
G01X756566Y821296D02*
Y816296D01*
G01X755109Y821296D02*
X758023D01*
G01X762933Y816296D02*
X760399D01*
Y821296D01*
X762933D01*
G01X761919Y818879D02*
X760399D01*
G01X765373Y816296D02*
Y821296D01*
X766639D01*
X767146Y821046D01*
X767526Y820713D01*
X767843Y820213D01*
X768096Y819629D01*
X768159Y818796D01*
X768096Y817963D01*
X767843Y817379D01*
X767526Y816879D01*
X767146Y816546D01*
X766639Y816296D01*
X765373D01*
G01X739999Y863546D02*
Y868546D01*
X741519D01*
X742026Y868296D01*
X742406Y867713D01*
X742533Y867046D01*
X742406Y866379D01*
X742089Y865879D01*
X741519Y865629D01*
X739999D01*
G01X745099Y868546D02*
Y863546D01*
X747633D01*
G01X749883D02*
X751466Y868546D01*
X753049Y863546D01*
G01X752479Y865296D02*
X750453D01*
G01X756566Y868546D02*
Y863546D01*
G01X755109Y868546D02*
X758023D01*
G01X762933Y863546D02*
X760399D01*
Y868546D01*
X762933D01*
G01X761919Y866129D02*
X760399D01*
G01X765373Y863546D02*
Y868546D01*
X766639D01*
X767146Y868296D01*
X767526Y867963D01*
X767843Y867463D01*
X768096Y866879D01*
X768159Y866046D01*
X768096Y865213D01*
X767843Y864629D01*
X767526Y864129D01*
X767146Y863796D01*
X766639Y863546D01*
X765373D01*
G01X739999Y910796D02*
Y915796D01*
X741519D01*
X742026Y915546D01*
X742406Y914963D01*
X742533Y914296D01*
X742406Y913629D01*
X742089Y913129D01*
X741519Y912879D01*
X739999D01*
G01X745099Y915796D02*
Y910796D01*
X747633D01*
G01X749883D02*
X751466Y915796D01*
X753049Y910796D01*
G01X752479Y912546D02*
X750453D01*
G01X756566Y915796D02*
Y910796D01*
G01X755109Y915796D02*
X758023D01*
G01X762933Y910796D02*
X760399D01*
Y915796D01*
X762933D01*
G01X761919Y913379D02*
X760399D01*
G01X765373Y910796D02*
Y915796D01*
X766639D01*
X767146Y915546D01*
X767526Y915213D01*
X767843Y914713D01*
X768096Y914129D01*
X768159Y913296D01*
X768096Y912463D01*
X767843Y911879D01*
X767526Y911379D01*
X767146Y911046D01*
X766639Y910796D01*
X765373D01*
G01X739999Y958046D02*
Y963046D01*
X741519D01*
X742026Y962796D01*
X742406Y962213D01*
X742533Y961546D01*
X742406Y960879D01*
X742089Y960379D01*
X741519Y960129D01*
X739999D01*
G01X745099Y963046D02*
Y958046D01*
X747633D01*
G01X749883D02*
X751466Y963046D01*
X753049Y958046D01*
G01X752479Y959796D02*
X750453D01*
G01X756566Y963046D02*
Y958046D01*
G01X755109Y963046D02*
X758023D01*
G01X762933Y958046D02*
X760399D01*
Y963046D01*
X762933D01*
G01X761919Y960629D02*
X760399D01*
G01X765373Y958046D02*
Y963046D01*
X766639D01*
X767146Y962796D01*
X767526Y962463D01*
X767843Y961963D01*
X768096Y961379D01*
X768159Y960546D01*
X768096Y959713D01*
X767843Y959129D01*
X767526Y958629D01*
X767146Y958296D01*
X766639Y958046D01*
X765373D01*
G01X739999Y987971D02*
Y992971D01*
X741519D01*
X742026Y992721D01*
X742406Y992138D01*
X742533Y991471D01*
X742406Y990804D01*
X742089Y990304D01*
X741519Y990054D01*
X739999D01*
G01X745099Y992971D02*
Y987971D01*
X747633D01*
G01X749883D02*
X751466Y992971D01*
X753049Y987971D01*
G01X752479Y989721D02*
X750453D01*
G01X756566Y992971D02*
Y987971D01*
G01X755109Y992971D02*
X758023D01*
G01X762933Y987971D02*
X760399D01*
Y992971D01*
X762933D01*
G01X761919Y990554D02*
X760399D01*
G01X765373Y987971D02*
Y992971D01*
X766639D01*
X767146Y992721D01*
X767526Y992388D01*
X767843Y991888D01*
X768096Y991304D01*
X768159Y990471D01*
X768096Y989638D01*
X767843Y989054D01*
X767526Y988554D01*
X767146Y988221D01*
X766639Y987971D01*
X765373D01*
G01X796116Y60296D02*
Y65296D01*
X795356Y64296D01*
G01Y60296D02*
X796876D01*
G01X793566Y107546D02*
Y112546D01*
X792806Y111546D01*
G01Y107546D02*
X794326D01*
G01X797463Y111713D02*
X797843Y112213D01*
X798286Y112463D01*
X798793Y112546D01*
X799426Y112379D01*
X799869Y111963D01*
X799996Y111463D01*
X799933Y110963D01*
X799679Y110546D01*
X798413Y109713D01*
X797843Y109129D01*
X797463Y108296D01*
X797336Y107546D01*
X799996D01*
G01X796116Y154796D02*
Y159796D01*
X795356Y158796D01*
G01Y154796D02*
X796876D01*
G01X793566Y202046D02*
Y207046D01*
X792806Y206046D01*
G01Y202046D02*
X794326D01*
G01X797463Y206213D02*
X797843Y206713D01*
X798286Y206963D01*
X798793Y207046D01*
X799426Y206879D01*
X799869Y206463D01*
X799996Y205963D01*
X799933Y205463D01*
X799679Y205046D01*
X798413Y204213D01*
X797843Y203629D01*
X797463Y202796D01*
X797336Y202046D01*
X799996D01*
G01X796116Y249296D02*
X796559Y249379D01*
X797066Y249629D01*
X797383Y250046D01*
X797509Y250629D01*
X797383Y251213D01*
X797003Y251713D01*
X796433Y251963D01*
X795799D01*
X795419Y252129D01*
X795103Y252546D01*
X794976Y253129D01*
X795166Y253713D01*
X795609Y254129D01*
X796116Y254296D01*
X796623Y254129D01*
X797066Y253713D01*
X797256Y253129D01*
X797129Y252546D01*
X796813Y252129D01*
X796433Y251963D01*
X795799D01*
X795229Y251713D01*
X794849Y251213D01*
X794723Y250629D01*
X794849Y250046D01*
X795166Y249629D01*
X795673Y249379D01*
X796116Y249296D01*
G01X796876Y296546D02*
Y301546D01*
X794533Y297963D01*
X797699D01*
G01X792363Y347963D02*
X792743Y348463D01*
X793186Y348713D01*
X793693Y348796D01*
X794326Y348629D01*
X794769Y348213D01*
X794896Y347713D01*
X794833Y347213D01*
X794579Y346796D01*
X793313Y345963D01*
X792743Y345379D01*
X792363Y344546D01*
X792236Y343796D01*
X794896D01*
G01X799426D02*
Y348796D01*
X797083Y345213D01*
X800249D01*
G01X796876Y391046D02*
Y396046D01*
X794533Y392463D01*
X797699D01*
G01X793566Y438296D02*
Y443296D01*
X792806Y442296D01*
G01Y438296D02*
X794326D01*
G01X798666Y443296D02*
X798159Y443129D01*
X797779Y442713D01*
X797526Y442213D01*
X797336Y441546D01*
X797273Y440796D01*
X797336Y440046D01*
X797526Y439379D01*
X797779Y438879D01*
X798159Y438463D01*
X798666Y438296D01*
X799173Y438463D01*
X799553Y438879D01*
X799806Y439379D01*
X799996Y440046D01*
X800059Y440796D01*
X799996Y441546D01*
X799806Y442213D01*
X799553Y442713D01*
X799173Y443129D01*
X798666Y443296D01*
G01X796876Y485546D02*
Y490546D01*
X794533Y486963D01*
X797699D01*
G01X792363Y536963D02*
X792743Y537463D01*
X793186Y537713D01*
X793693Y537796D01*
X794326Y537629D01*
X794769Y537213D01*
X794896Y536713D01*
X794833Y536213D01*
X794579Y535796D01*
X793313Y534963D01*
X792743Y534379D01*
X792363Y533546D01*
X792236Y532796D01*
X794896D01*
G01X798666Y537796D02*
X798159Y537629D01*
X797779Y537213D01*
X797526Y536713D01*
X797336Y536046D01*
X797273Y535296D01*
X797336Y534546D01*
X797526Y533879D01*
X797779Y533379D01*
X798159Y532963D01*
X798666Y532796D01*
X799173Y532963D01*
X799553Y533379D01*
X799806Y533879D01*
X799996Y534546D01*
X800059Y535296D01*
X799996Y536046D01*
X799806Y536713D01*
X799553Y537213D01*
X799173Y537629D01*
X798666Y537796D01*
G01X789623Y581046D02*
X790003Y580463D01*
X790509Y580129D01*
X791079Y580046D01*
X791586Y580129D01*
X792093Y580546D01*
X792409Y581046D01*
X792473Y581546D01*
X792346Y582129D01*
X791903Y582546D01*
X791459Y582713D01*
X790889D01*
G01X791459D02*
X791839Y582963D01*
X792156Y583379D01*
X792283Y583879D01*
X792156Y584379D01*
X791839Y584796D01*
X791269Y585046D01*
X790699Y584963D01*
X790129Y584629D01*
G01X796116Y580046D02*
X796559Y580129D01*
X797066Y580379D01*
X797383Y580796D01*
X797509Y581379D01*
X797383Y581963D01*
X797003Y582463D01*
X796433Y582713D01*
X795799D01*
X795419Y582879D01*
X795103Y583296D01*
X794976Y583879D01*
X795166Y584463D01*
X795609Y584879D01*
X796116Y585046D01*
X796623Y584879D01*
X797066Y584463D01*
X797256Y583879D01*
X797129Y583296D01*
X796813Y582879D01*
X796433Y582713D01*
X795799D01*
X795229Y582463D01*
X794849Y581963D01*
X794723Y581379D01*
X794849Y580796D01*
X795166Y580379D01*
X795673Y580129D01*
X796116Y580046D01*
G01X801976D02*
Y585046D01*
X799633Y581463D01*
X802799D01*
G01X793566Y627296D02*
Y632296D01*
X792806Y631296D01*
G01Y627296D02*
X794326D01*
G01X798666D02*
Y632296D01*
X797906Y631296D01*
G01Y627296D02*
X799426D01*
G01X792173Y675546D02*
X792553Y674963D01*
X793059Y674629D01*
X793629Y674546D01*
X794136Y674629D01*
X794643Y675046D01*
X794959Y675546D01*
X795023Y676046D01*
X794896Y676629D01*
X794453Y677046D01*
X794009Y677213D01*
X793439D01*
G01X794009D02*
X794389Y677463D01*
X794706Y677879D01*
X794833Y678379D01*
X794706Y678879D01*
X794389Y679296D01*
X793819Y679546D01*
X793249Y679463D01*
X792679Y679129D01*
G01X797463Y678713D02*
X797843Y679213D01*
X798286Y679463D01*
X798793Y679546D01*
X799426Y679379D01*
X799869Y678963D01*
X799996Y678463D01*
X799933Y677963D01*
X799679Y677546D01*
X798413Y676713D01*
X797843Y676129D01*
X797463Y675296D01*
X797336Y674546D01*
X799996D01*
G01X793439Y721796D02*
X793566Y722879D01*
X793756Y723796D01*
X794009Y724629D01*
X794326Y725546D01*
X794833Y726796D01*
X792299D01*
G01X797463Y725963D02*
X797843Y726463D01*
X798286Y726713D01*
X798793Y726796D01*
X799426Y726629D01*
X799869Y726213D01*
X799996Y725713D01*
X799933Y725213D01*
X799679Y724796D01*
X798413Y723963D01*
X797843Y723379D01*
X797463Y722546D01*
X797336Y721796D01*
X799996D01*
G01X789623Y769796D02*
X790003Y769379D01*
X790446Y769129D01*
X791016Y769046D01*
X791586Y769213D01*
X792029Y769546D01*
X792346Y770129D01*
X792409Y770796D01*
X792283Y771463D01*
X791966Y771879D01*
X791523Y772213D01*
X791079Y772296D01*
X790636Y772213D01*
X790066Y771879D01*
X790256Y774046D01*
X791966D01*
G01X794913Y773213D02*
X795293Y773713D01*
X795736Y773963D01*
X796243Y774046D01*
X796876Y773879D01*
X797319Y773463D01*
X797446Y772963D01*
X797383Y772463D01*
X797129Y772046D01*
X795863Y771213D01*
X795293Y770629D01*
X794913Y769796D01*
X794786Y769046D01*
X797446D01*
G01X801216D02*
X801659Y769129D01*
X802166Y769379D01*
X802483Y769796D01*
X802609Y770379D01*
X802483Y770963D01*
X802103Y771463D01*
X801533Y771713D01*
X800899D01*
X800519Y771879D01*
X800203Y772296D01*
X800076Y772879D01*
X800266Y773463D01*
X800709Y773879D01*
X801216Y774046D01*
X801723Y773879D01*
X802166Y773463D01*
X802356Y772879D01*
X802229Y772296D01*
X801913Y771879D01*
X801533Y771713D01*
X800899D01*
X800329Y771463D01*
X799949Y770963D01*
X799823Y770379D01*
X799949Y769796D01*
X800266Y769379D01*
X800773Y769129D01*
X801216Y769046D01*
G01X789623Y817296D02*
X790003Y816713D01*
X790509Y816379D01*
X791079Y816296D01*
X791586Y816379D01*
X792093Y816796D01*
X792409Y817296D01*
X792473Y817796D01*
X792346Y818379D01*
X791903Y818796D01*
X791459Y818963D01*
X790889D01*
G01X791459D02*
X791839Y819213D01*
X792156Y819629D01*
X792283Y820129D01*
X792156Y820629D01*
X791839Y821046D01*
X791269Y821296D01*
X790699Y821213D01*
X790129Y820879D01*
G01X794913Y820463D02*
X795293Y820963D01*
X795736Y821213D01*
X796243Y821296D01*
X796876Y821129D01*
X797319Y820713D01*
X797446Y820213D01*
X797383Y819713D01*
X797129Y819296D01*
X795863Y818463D01*
X795293Y817879D01*
X794913Y817046D01*
X794786Y816296D01*
X797446D01*
G01X801216D02*
X801659Y816379D01*
X802166Y816629D01*
X802483Y817046D01*
X802609Y817629D01*
X802483Y818213D01*
X802103Y818713D01*
X801533Y818963D01*
X800899D01*
X800519Y819129D01*
X800203Y819546D01*
X800076Y820129D01*
X800266Y820713D01*
X800709Y821129D01*
X801216Y821296D01*
X801723Y821129D01*
X802166Y820713D01*
X802356Y820129D01*
X802229Y819546D01*
X801913Y819129D01*
X801533Y818963D01*
X800899D01*
X800329Y818713D01*
X799949Y818213D01*
X799823Y817629D01*
X799949Y817046D01*
X800266Y816629D01*
X800773Y816379D01*
X801216Y816296D01*
G01X792489Y864129D02*
X792933Y863713D01*
X793439Y863546D01*
X793946Y863713D01*
X794389Y864213D01*
X794706Y864963D01*
X794833Y865713D01*
Y866629D01*
X794706Y867379D01*
X794389Y868046D01*
X794009Y868379D01*
X793566Y868546D01*
X793059Y868379D01*
X792679Y868046D01*
X792426Y867546D01*
X792299Y866879D01*
X792426Y866296D01*
X792743Y865713D01*
X793123Y865379D01*
X793566Y865296D01*
X794073Y865463D01*
X794453Y865879D01*
X794833Y866629D01*
G01X797463Y865629D02*
X797906Y866213D01*
X798286Y866546D01*
X798793Y866713D01*
X799236Y866546D01*
X799553Y866213D01*
X799806Y865713D01*
X799869Y865129D01*
X799806Y864629D01*
X799553Y864129D01*
X799173Y863713D01*
X798729Y863546D01*
X798223Y863713D01*
X797779Y864213D01*
X797526Y864963D01*
X797463Y865796D01*
X797589Y866879D01*
X797779Y867463D01*
X798096Y868046D01*
X798539Y868463D01*
X798983Y868546D01*
X799426Y868379D01*
X799743Y867963D01*
G01X789813Y914963D02*
X790193Y915463D01*
X790636Y915713D01*
X791143Y915796D01*
X791776Y915629D01*
X792219Y915213D01*
X792346Y914713D01*
X792283Y914213D01*
X792029Y913796D01*
X790763Y912963D01*
X790193Y912379D01*
X789813Y911546D01*
X789686Y910796D01*
X792346D01*
G01X794913Y912879D02*
X795356Y913463D01*
X795736Y913796D01*
X796243Y913963D01*
X796686Y913796D01*
X797003Y913463D01*
X797256Y912963D01*
X797319Y912379D01*
X797256Y911879D01*
X797003Y911379D01*
X796623Y910963D01*
X796179Y910796D01*
X795673Y910963D01*
X795229Y911463D01*
X794976Y912213D01*
X794913Y913046D01*
X795039Y914129D01*
X795229Y914713D01*
X795546Y915296D01*
X795989Y915713D01*
X796433Y915796D01*
X796876Y915629D01*
X797193Y915213D01*
G01X801216Y915796D02*
X800709Y915629D01*
X800329Y915213D01*
X800076Y914713D01*
X799886Y914046D01*
X799823Y913296D01*
X799886Y912546D01*
X800076Y911879D01*
X800329Y911379D01*
X800709Y910963D01*
X801216Y910796D01*
X801723Y910963D01*
X802103Y911379D01*
X802356Y911879D01*
X802546Y912546D01*
X802609Y913296D01*
X802546Y914046D01*
X802356Y914713D01*
X802103Y915213D01*
X801723Y915629D01*
X801216Y915796D01*
G01X788466Y958046D02*
Y963046D01*
X787706Y962046D01*
G01Y958046D02*
X789226D01*
G01X792363Y960129D02*
X792806Y960713D01*
X793186Y961046D01*
X793693Y961213D01*
X794136Y961046D01*
X794453Y960713D01*
X794706Y960213D01*
X794769Y959629D01*
X794706Y959129D01*
X794453Y958629D01*
X794073Y958213D01*
X793629Y958046D01*
X793123Y958213D01*
X792679Y958713D01*
X792426Y959463D01*
X792363Y960296D01*
X792489Y961379D01*
X792679Y961963D01*
X792996Y962546D01*
X793439Y962963D01*
X793883Y963046D01*
X794326Y962879D01*
X794643Y962463D01*
G01X799426Y958046D02*
Y963046D01*
X797083Y959463D01*
X800249D01*
G01X803766Y958046D02*
Y963046D01*
X803006Y962046D01*
G01Y958046D02*
X804526D01*
G01X791016Y987971D02*
X790509Y988054D01*
X790066Y988388D01*
X789686Y988888D01*
X789433Y989471D01*
X789306Y990138D01*
Y990804D01*
X789433Y991471D01*
X789686Y992054D01*
X790066Y992554D01*
X790509Y992888D01*
X791016Y992971D01*
X791523Y992888D01*
X791966Y992554D01*
X792346Y992054D01*
X792599Y991471D01*
X792726Y990804D01*
Y990138D01*
X792599Y989471D01*
X792346Y988888D01*
X791966Y988388D01*
X791523Y988054D01*
X791016Y987971D01*
G01X791523Y989304D02*
X792283Y987971D01*
G01X796116Y992971D02*
Y987971D01*
G01X794659Y992971D02*
X797573D01*
G01X801216Y987971D02*
Y990221D01*
X799949Y992971D01*
G01X802483D02*
X801216Y990221D01*
M02*
